(kicad_sch
	(version 20250114)
	(generator "eeschema")
	(generator_version "9.0")
	(paper "A3")
	(title_block
		(title "Thunderbolt to 10GbE adapter")
		(date "2026-04-23")
		(rev "1.1.0")
		(company "Antmicro Ltd")
		(comment 1 "www.antmicro.com")
	)
	(text "ICT Testpoints\nplace on bottom"
		(exclude_from_sim no)
		(at 236.22 173.228 0)
		(effects
			(font
				(size 1.27 1.27)
			)
		)
	)
	(text "X710-AT2 Power"
		(exclude_from_sim no)
		(at 215.9 38.1 0)
		(effects
			(font
				(size 2.54 2.54)
				(thickness 0.508)
				(bold yes)
			)
		)
	)
	(text_box "XGB_AVDDH Decoupling"
		(exclude_from_sim no)
		(at 22.86 83.82 0)
		(size 135.89 25.4)
		(margins 0.9525 0.9525 0.9525 0.9525)
		(stroke
			(width 0)
			(type dash)
		)
		(fill
			(type none)
		)
		(effects
			(font
				(size 1.27 1.27)
			)
			(justify right top)
		)
	)
	(text_box "P0_AVDDL Decoupling"
		(exclude_from_sim no)
		(at 22.86 137.16 0)
		(size 135.89 25.4)
		(margins 0.9525 0.9525 0.9525 0.9525)
		(stroke
			(width 0)
			(type dash)
		)
		(fill
			(type none)
		)
		(effects
			(font
				(size 1.27 1.27)
			)
			(justify right top)
		)
	)
	(text_box "XFI_VDD Decoupling"
		(exclude_from_sim no)
		(at 22.86 190.5 0)
		(size 135.89 25.4)
		(margins 0.9525 0.9525 0.9525 0.9525)
		(stroke
			(width 0)
			(type dash)
		)
		(fill
			(type none)
		)
		(effects
			(font
				(size 1.27 1.27)
			)
			(justify right top)
		)
	)
	(text_box "AVDDH Decoupling"
		(exclude_from_sim no)
		(at 22.86 110.49 0)
		(size 135.89 25.4)
		(margins 0.9525 0.9525 0.9525 0.9525)
		(stroke
			(width 0)
			(type dash)
		)
		(fill
			(type none)
		)
		(effects
			(font
				(size 1.27 1.27)
			)
			(justify right top)
		)
	)
	(text_box "XFI_PVDD Decoupling"
		(exclude_from_sim no)
		(at 22.86 217.17 0)
		(size 135.89 25.4)
		(margins 0.9525 0.9525 0.9525 0.9525)
		(stroke
			(width 0)
			(type dash)
		)
		(fill
			(type none)
		)
		(effects
			(font
				(size 1.27 1.27)
			)
			(justify right top)
		)
	)
	(text_box "VCCD Decoupling"
		(exclude_from_sim no)
		(at 295.91 62.23 0)
		(size 109.22 38.1)
		(margins 0.9525 0.9525 0.9525 0.9525)
		(stroke
			(width 0)
			(type dash)
		)
		(fill
			(type none)
		)
		(effects
			(font
				(size 1.27 1.27)
			)
			(justify right top)
		)
	)
	(text_box "DVDD Decoupling"
		(exclude_from_sim no)
		(at 22.86 40.64 0)
		(size 135.89 20.32)
		(margins 0.9525 0.9525 0.9525 0.9525)
		(stroke
			(width 0)
			(type dash)
		)
		(fill
			(type none)
		)
		(effects
			(font
				(size 1.27 1.27)
			)
			(justify right top)
		)
	)
	(text_box "+3V3 Decoupling"
		(exclude_from_sim no)
		(at 295.91 101.6 0)
		(size 109.22 38.1)
		(margins 0.9525 0.9525 0.9525 0.9525)
		(stroke
			(width 0)
			(type dash)
		)
		(fill
			(type none)
		)
		(effects
			(font
				(size 1.27 1.27)
			)
			(justify right top)
		)
	)
	(text_box "Place close\nto T2 pin"
		(exclude_from_sim no)
		(at 302.26 113.03 0)
		(size 7.62 8.89)
		(margins 0.9525 0.9525 0.9525 0.9525)
		(stroke
			(width 0)
			(type solid)
		)
		(fill
			(type none)
		)
		(effects
			(font
				(size 1.27 1.27)
			)
		)
	)
	(text_box "P1_AVDDL Decoupling"
		(exclude_from_sim no)
		(at 22.86 163.83 0)
		(size 135.89 25.4)
		(margins 0.9525 0.9525 0.9525 0.9525)
		(stroke
			(width 0)
			(type dash)
		)
		(fill
			(type none)
		)
		(effects
			(font
				(size 1.27 1.27)
			)
			(justify right top)
		)
	)
	(text_box "+1V8 Decoupling (VDDIO1, VDDIO2)"
		(exclude_from_sim no)
		(at 22.86 62.23 0)
		(size 135.89 20.32)
		(margins 0.9525 0.9525 0.9525 0.9525)
		(stroke
			(width 0)
			(type dash)
		)
		(fill
			(type none)
		)
		(effects
			(font
				(size 1.27 1.27)
			)
			(justify right top)
		)
	)
	(text_box "VCCA Decoupling"
		(exclude_from_sim no)
		(at 295.91 40.64 0)
		(size 109.22 20.32)
		(margins 0.9525 0.9525 0.9525 0.9525)
		(stroke
			(width 0)
			(type dash)
		)
		(fill
			(type none)
		)
		(effects
			(font
				(size 1.27 1.27)
			)
			(justify right top)
		)
	)
	(text_box "PLL_VDD Decoupling"
		(exclude_from_sim no)
		(at 22.86 243.84 0)
		(size 135.89 25.4)
		(margins 0.9525 0.9525 0.9525 0.9525)
		(stroke
			(width 0)
			(type dash)
		)
		(fill
			(type none)
		)
		(effects
			(font
				(size 1.27 1.27)
			)
			(justify right top)
		)
	)
	(junction
		(at 370.84 123.19)
		(diameter 0)
		(color 0 0 0 0)
	)
	(junction
		(at 214.63 95.25)
		(diameter 0)
		(color 0 0 0 0)
	)
	(junction
		(at 97.79 172.72)
		(diameter 0)
		(color 0 0 0 0)
	)
	(junction
		(at 77.47 172.72)
		(diameter 0)
		(color 0 0 0 0)
	)
	(junction
		(at 142.24 172.72)
		(diameter 0)
		(color 0 0 0 0)
	)
	(junction
		(at 199.39 110.49)
		(diameter 0)
		(color 0 0 0 0)
	)
	(junction
		(at 151.13 66.04)
		(diameter 0)
		(color 0 0 0 0)
	)
	(junction
		(at 133.35 66.04)
		(diameter 0)
		(color 0 0 0 0)
	)
	(junction
		(at 379.73 44.45)
		(diameter 0)
		(color 0 0 0 0)
	)
	(junction
		(at 101.6 119.38)
		(diameter 0)
		(color 0 0 0 0)
	)
	(junction
		(at 90.17 226.06)
		(diameter 0)
		(color 0 0 0 0)
	)
	(junction
		(at 270.51 138.43)
		(diameter 0)
		(color 0 0 0 0)
	)
	(junction
		(at 90.17 44.45)
		(diameter 0)
		(color 0 0 0 0)
	)
	(junction
		(at 74.93 252.73)
		(diameter 0)
		(color 0 0 0 0)
	)
	(junction
		(at 115.57 146.05)
		(diameter 0)
		(color 0 0 0 0)
	)
	(junction
		(at 270.51 105.41)
		(diameter 0)
		(color 0 0 0 0)
	)
	(junction
		(at 344.17 44.45)
		(diameter 0)
		(color 0 0 0 0)
	)
	(junction
		(at 326.39 123.19)
		(diameter 0)
		(color 0 0 0 0)
	)
	(junction
		(at 283.21 142.24)
		(diameter 0)
		(color 0 0 0 0)
	)
	(junction
		(at 198.12 125.73)
		(diameter 0)
		(color 0 0 0 0)
	)
	(junction
		(at 361.95 105.41)
		(diameter 0)
		(color 0 0 0 0)
	)
	(junction
		(at 283.21 118.11)
		(diameter 0)
		(color 0 0 0 0)
	)
	(junction
		(at 388.62 83.82)
		(diameter 0)
		(color 0 0 0 0)
	)
	(junction
		(at 335.28 66.04)
		(diameter 0)
		(color 0 0 0 0)
	)
	(junction
		(at 208.28 105.41)
		(diameter 0)
		(color 0 0 0 0)
	)
	(junction
		(at 101.6 226.06)
		(diameter 0)
		(color 0 0 0 0)
	)
	(junction
		(at 299.72 105.41)
		(diameter 0)
		(color 0 0 0 0)
	)
	(junction
		(at 81.28 44.45)
		(diameter 0)
		(color 0 0 0 0)
	)
	(junction
		(at 115.57 44.45)
		(diameter 0)
		(color 0 0 0 0)
	)
	(junction
		(at 361.95 123.19)
		(diameter 0)
		(color 0 0 0 0)
	)
	(junction
		(at 76.2 146.05)
		(diameter 0)
		(color 0 0 0 0)
	)
	(junction
		(at 214.63 97.79)
		(diameter 0)
		(color 0 0 0 0)
	)
	(junction
		(at 189.23 130.81)
		(diameter 0)
		(color 0 0 0 0)
	)
	(junction
		(at 299.72 83.82)
		(diameter 0)
		(color 0 0 0 0)
	)
	(junction
		(at 299.72 66.04)
		(diameter 0)
		(color 0 0 0 0)
	)
	(junction
		(at 353.06 44.45)
		(diameter 0)
		(color 0 0 0 0)
	)
	(junction
		(at 106.68 172.72)
		(diameter 0)
		(color 0 0 0 0)
	)
	(junction
		(at 326.39 44.45)
		(diameter 0)
		(color 0 0 0 0)
	)
	(junction
		(at 90.17 252.73)
		(diameter 0)
		(color 0 0 0 0)
	)
	(junction
		(at 55.88 44.45)
		(diameter 0)
		(color 0 0 0 0)
	)
	(junction
		(at 317.5 66.04)
		(diameter 0)
		(color 0 0 0 0)
	)
	(junction
		(at 353.06 83.82)
		(diameter 0)
		(color 0 0 0 0)
	)
	(junction
		(at 46.99 44.45)
		(diameter 0)
		(color 0 0 0 0)
	)
	(junction
		(at 335.28 105.41)
		(diameter 0)
		(color 0 0 0 0)
	)
	(junction
		(at 151.13 172.72)
		(diameter 0)
		(color 0 0 0 0)
	)
	(junction
		(at 308.61 123.19)
		(diameter 0)
		(color 0 0 0 0)
	)
	(junction
		(at 353.06 123.19)
		(diameter 0)
		(color 0 0 0 0)
	)
	(junction
		(at 308.61 83.82)
		(diameter 0)
		(color 0 0 0 0)
	)
	(junction
		(at 133.35 44.45)
		(diameter 0)
		(color 0 0 0 0)
	)
	(junction
		(at 101.6 199.39)
		(diameter 0)
		(color 0 0 0 0)
	)
	(junction
		(at 77.47 92.71)
		(diameter 0)
		(color 0 0 0 0)
	)
	(junction
		(at 208.28 120.65)
		(diameter 0)
		(color 0 0 0 0)
	)
	(junction
		(at 344.17 66.04)
		(diameter 0)
		(color 0 0 0 0)
	)
	(junction
		(at 110.49 146.05)
		(diameter 0)
		(color 0 0 0 0)
	)
	(junction
		(at 101.6 252.73)
		(diameter 0)
		(color 0 0 0 0)
	)
	(junction
		(at 30.48 146.05)
		(diameter 0)
		(color 0 0 0 0)
	)
	(junction
		(at 214.63 113.03)
		(diameter 0)
		(color 0 0 0 0)
	)
	(junction
		(at 379.73 123.19)
		(diameter 0)
		(color 0 0 0 0)
	)
	(junction
		(at 133.35 119.38)
		(diameter 0)
		(color 0 0 0 0)
	)
	(junction
		(at 283.21 105.41)
		(diameter 0)
		(color 0 0 0 0)
	)
	(junction
		(at 270.51 143.51)
		(diameter 0)
		(color 0 0 0 0)
	)
	(junction
		(at 102.87 92.71)
		(diameter 0)
		(color 0 0 0 0)
	)
	(junction
		(at 74.93 199.39)
		(diameter 0)
		(color 0 0 0 0)
	)
	(junction
		(at 299.72 44.45)
		(diameter 0)
		(color 0 0 0 0)
	)
	(junction
		(at 293.37 83.82)
		(diameter 0)
		(color 0 0 0 0)
	)
	(junction
		(at 66.04 146.05)
		(diameter 0)
		(color 0 0 0 0)
	)
	(junction
		(at 142.24 146.05)
		(diameter 0)
		(color 0 0 0 0)
	)
	(junction
		(at 97.79 146.05)
		(diameter 0)
		(color 0 0 0 0)
	)
	(junction
		(at 353.06 105.41)
		(diameter 0)
		(color 0 0 0 0)
	)
	(junction
		(at 124.46 119.38)
		(diameter 0)
		(color 0 0 0 0)
	)
	(junction
		(at 361.95 44.45)
		(diameter 0)
		(color 0 0 0 0)
	)
	(junction
		(at 99.06 44.45)
		(diameter 0)
		(color 0 0 0 0)
	)
	(junction
		(at 379.73 83.82)
		(diameter 0)
		(color 0 0 0 0)
	)
	(junction
		(at 326.39 105.41)
		(diameter 0)
		(color 0 0 0 0)
	)
	(junction
		(at 317.5 105.41)
		(diameter 0)
		(color 0 0 0 0)
	)
	(junction
		(at 133.35 172.72)
		(diameter 0)
		(color 0 0 0 0)
	)
	(junction
		(at 326.39 66.04)
		(diameter 0)
		(color 0 0 0 0)
	)
	(junction
		(at 151.13 119.38)
		(diameter 0)
		(color 0 0 0 0)
	)
	(junction
		(at 142.24 44.45)
		(diameter 0)
		(color 0 0 0 0)
	)
	(junction
		(at 124.46 172.72)
		(diameter 0)
		(color 0 0 0 0)
	)
	(junction
		(at 317.5 123.19)
		(diameter 0)
		(color 0 0 0 0)
	)
	(junction
		(at 214.63 90.17)
		(diameter 0)
		(color 0 0 0 0)
	)
	(junction
		(at 270.51 107.95)
		(diameter 0)
		(color 0 0 0 0)
	)
	(junction
		(at 97.79 66.04)
		(diameter 0)
		(color 0 0 0 0)
	)
	(junction
		(at 151.13 146.05)
		(diameter 0)
		(color 0 0 0 0)
	)
	(junction
		(at 335.28 83.82)
		(diameter 0)
		(color 0 0 0 0)
	)
	(junction
		(at 39.37 146.05)
		(diameter 0)
		(color 0 0 0 0)
	)
	(junction
		(at 270.51 110.49)
		(diameter 0)
		(color 0 0 0 0)
	)
	(junction
		(at 88.9 92.71)
		(diameter 0)
		(color 0 0 0 0)
	)
	(junction
		(at 142.24 66.04)
		(diameter 0)
		(color 0 0 0 0)
	)
	(junction
		(at 151.13 44.45)
		(diameter 0)
		(color 0 0 0 0)
	)
	(junction
		(at 317.5 83.82)
		(diameter 0)
		(color 0 0 0 0)
	)
	(junction
		(at 67.31 172.72)
		(diameter 0)
		(color 0 0 0 0)
	)
	(junction
		(at 293.37 105.41)
		(diameter 0)
		(color 0 0 0 0)
	)
	(junction
		(at 388.62 44.45)
		(diameter 0)
		(color 0 0 0 0)
	)
	(junction
		(at 270.51 140.97)
		(diameter 0)
		(color 0 0 0 0)
	)
	(junction
		(at 270.51 90.17)
		(diameter 0)
		(color 0 0 0 0)
	)
	(junction
		(at 124.46 66.04)
		(diameter 0)
		(color 0 0 0 0)
	)
	(junction
		(at 90.17 199.39)
		(diameter 0)
		(color 0 0 0 0)
	)
	(junction
		(at 88.9 172.72)
		(diameter 0)
		(color 0 0 0 0)
	)
	(junction
		(at 388.62 66.04)
		(diameter 0)
		(color 0 0 0 0)
	)
	(junction
		(at 115.57 119.38)
		(diameter 0)
		(color 0 0 0 0)
	)
	(junction
		(at 208.28 95.25)
		(diameter 0)
		(color 0 0 0 0)
	)
	(junction
		(at 133.35 199.39)
		(diameter 0)
		(color 0 0 0 0)
	)
	(junction
		(at 270.51 97.79)
		(diameter 0)
		(color 0 0 0 0)
	)
	(junction
		(at 151.13 199.39)
		(diameter 0)
		(color 0 0 0 0)
	)
	(junction
		(at 276.86 95.25)
		(diameter 0)
		(color 0 0 0 0)
	)
	(junction
		(at 86.36 146.05)
		(diameter 0)
		(color 0 0 0 0)
	)
	(junction
		(at 344.17 105.41)
		(diameter 0)
		(color 0 0 0 0)
	)
	(junction
		(at 142.24 119.38)
		(diameter 0)
		(color 0 0 0 0)
	)
	(junction
		(at 124.46 44.45)
		(diameter 0)
		(color 0 0 0 0)
	)
	(junction
		(at 270.51 133.35)
		(diameter 0)
		(color 0 0 0 0)
	)
	(junction
		(at 64.77 44.45)
		(diameter 0)
		(color 0 0 0 0)
	)
	(junction
		(at 101.6 172.72)
		(diameter 0)
		(color 0 0 0 0)
	)
	(junction
		(at 142.24 199.39)
		(diameter 0)
		(color 0 0 0 0)
	)
	(junction
		(at 326.39 83.82)
		(diameter 0)
		(color 0 0 0 0)
	)
	(junction
		(at 133.35 146.05)
		(diameter 0)
		(color 0 0 0 0)
	)
	(junction
		(at 106.68 146.05)
		(diameter 0)
		(color 0 0 0 0)
	)
	(junction
		(at 74.93 226.06)
		(diameter 0)
		(color 0 0 0 0)
	)
	(junction
		(at 77.47 119.38)
		(diameter 0)
		(color 0 0 0 0)
	)
	(junction
		(at 299.72 123.19)
		(diameter 0)
		(color 0 0 0 0)
	)
	(junction
		(at 270.51 135.89)
		(diameter 0)
		(color 0 0 0 0)
	)
	(junction
		(at 379.73 66.04)
		(diameter 0)
		(color 0 0 0 0)
	)
	(junction
		(at 370.84 83.82)
		(diameter 0)
		(color 0 0 0 0)
	)
	(junction
		(at 344.17 123.19)
		(diameter 0)
		(color 0 0 0 0)
	)
	(junction
		(at 370.84 44.45)
		(diameter 0)
		(color 0 0 0 0)
	)
	(junction
		(at 48.26 146.05)
		(diameter 0)
		(color 0 0 0 0)
	)
	(junction
		(at 151.13 226.06)
		(diameter 0)
		(color 0 0 0 0)
	)
	(junction
		(at 308.61 66.04)
		(diameter 0)
		(color 0 0 0 0)
	)
	(junction
		(at 361.95 66.04)
		(diameter 0)
		(color 0 0 0 0)
	)
	(junction
		(at 361.95 83.82)
		(diameter 0)
		(color 0 0 0 0)
	)
	(junction
		(at 300.99 142.24)
		(diameter 0)
		(color 0 0 0 0)
	)
	(junction
		(at 124.46 146.05)
		(diameter 0)
		(color 0 0 0 0)
	)
	(junction
		(at 97.79 119.38)
		(diameter 0)
		(color 0 0 0 0)
	)
	(junction
		(at 214.63 110.49)
		(diameter 0)
		(color 0 0 0 0)
	)
	(junction
		(at 88.9 119.38)
		(diameter 0)
		(color 0 0 0 0)
	)
	(junction
		(at 317.5 44.45)
		(diameter 0)
		(color 0 0 0 0)
	)
	(junction
		(at 370.84 66.04)
		(diameter 0)
		(color 0 0 0 0)
	)
	(junction
		(at 124.46 199.39)
		(diameter 0)
		(color 0 0 0 0)
	)
	(junction
		(at 335.28 44.45)
		(diameter 0)
		(color 0 0 0 0)
	)
	(junction
		(at 73.66 44.45)
		(diameter 0)
		(color 0 0 0 0)
	)
	(junction
		(at 289.56 142.24)
		(diameter 0)
		(color 0 0 0 0)
	)
	(junction
		(at 292.1 142.24)
		(diameter 0)
		(color 0 0 0 0)
	)
	(junction
		(at 353.06 66.04)
		(diameter 0)
		(color 0 0 0 0)
	)
	(junction
		(at 57.15 146.05)
		(diameter 0)
		(color 0 0 0 0)
	)
	(junction
		(at 180.34 135.89)
		(diameter 0)
		(color 0 0 0 0)
	)
	(junction
		(at 308.61 44.45)
		(diameter 0)
		(color 0 0 0 0)
	)
	(junction
		(at 171.45 140.97)
		(diameter 0)
		(color 0 0 0 0)
	)
	(junction
		(at 270.51 95.25)
		(diameter 0)
		(color 0 0 0 0)
	)
	(no_connect
		(at 267.97 125.73)
	)
	(no_connect
		(at 267.97 123.19)
	)
	(wire
		(pts
			(xy 90.17 233.68) (xy 90.17 236.22)
		)
		(stroke
			(width 0)
			(type default)
		)
	)
	(wire
		(pts
			(xy 142.24 153.67) (xy 142.24 156.21)
		)
		(stroke
			(width 0)
			(type default)
		)
	)
	(wire
		(pts
			(xy 26.67 226.06) (xy 74.93 226.06)
		)
		(stroke
			(width 0)
			(type default)
		)
	)
	(wire
		(pts
			(xy 214.63 113.03) (xy 214.63 115.57)
		)
		(stroke
			(width 0)
			(type default)
		)
	)
	(wire
		(pts
			(xy 370.84 66.04) (xy 379.73 66.04)
		)
		(stroke
			(width 0)
			(type default)
		)
	)
	(wire
		(pts
			(xy 299.72 66.04) (xy 308.61 66.04)
		)
		(stroke
			(width 0)
			(type default)
		)
	)
	(wire
		(pts
			(xy 77.47 119.38) (xy 77.47 121.92)
		)
		(stroke
			(width 0)
			(type default)
		)
	)
	(wire
		(pts
			(xy 115.57 146.05) (xy 124.46 146.05)
		)
		(stroke
			(width 0)
			(type default)
		)
	)
	(wire
		(pts
			(xy 353.06 44.45) (xy 361.95 44.45)
		)
		(stroke
			(width 0)
			(type default)
		)
	)
	(wire
		(pts
			(xy 276.86 95.25) (xy 276.86 78.74)
		)
		(stroke
			(width 0)
			(type default)
		)
	)
	(wire
		(pts
			(xy 142.24 73.66) (xy 142.24 76.2)
		)
		(stroke
			(width 0)
			(type default)
		)
	)
	(wire
		(pts
			(xy 293.37 66.04) (xy 293.37 83.82)
		)
		(stroke
			(width 0)
			(type default)
		)
	)
	(wire
		(pts
			(xy 317.5 83.82) (xy 326.39 83.82)
		)
		(stroke
			(width 0)
			(type default)
		)
	)
	(wire
		(pts
			(xy 115.57 46.99) (xy 115.57 44.45)
		)
		(stroke
			(width 0)
			(type default)
		)
	)
	(wire
		(pts
			(xy 133.35 201.93) (xy 133.35 199.39)
		)
		(stroke
			(width 0)
			(type default)
		)
	)
	(wire
		(pts
			(xy 39.37 146.05) (xy 39.37 148.59)
		)
		(stroke
			(width 0)
			(type default)
		)
	)
	(wire
		(pts
			(xy 133.35 66.04) (xy 133.35 68.58)
		)
		(stroke
			(width 0)
			(type default)
		)
	)
	(wire
		(pts
			(xy 26.67 143.51) (xy 26.67 146.05)
		)
		(stroke
			(width 0)
			(type default)
		)
	)
	(wire
		(pts
			(xy 26.67 223.52) (xy 26.67 226.06)
		)
		(stroke
			(width 0)
			(type default)
		)
	)
	(wire
		(pts
			(xy 344.17 105.41) (xy 353.06 105.41)
		)
		(stroke
			(width 0)
			(type default)
		)
	)
	(wire
		(pts
			(xy 214.63 90.17) (xy 163.83 90.17)
		)
		(stroke
			(width 0)
			(type default)
		)
	)
	(wire
		(pts
			(xy 74.93 226.06) (xy 74.93 228.6)
		)
		(stroke
			(width 0)
			(type default)
		)
	)
	(wire
		(pts
			(xy 308.61 44.45) (xy 317.5 44.45)
		)
		(stroke
			(width 0)
			(type default)
		)
	)
	(wire
		(pts
			(xy 163.83 90.17) (xy 163.83 44.45)
		)
		(stroke
			(width 0)
			(type default)
		)
	)
	(wire
		(pts
			(xy 353.06 91.44) (xy 353.06 93.98)
		)
		(stroke
			(width 0)
			(type default)
		)
	)
	(wire
		(pts
			(xy 151.13 68.58) (xy 151.13 66.04)
		)
		(stroke
			(width 0)
			(type default)
		)
	)
	(wire
		(pts
			(xy 208.28 87.63) (xy 208.28 95.25)
		)
		(stroke
			(width 0)
			(type default)
		)
	)
	(wire
		(pts
			(xy 267.97 110.49) (xy 270.51 110.49)
		)
		(stroke
			(width 0)
			(type default)
		)
	)
	(wire
		(pts
			(xy 370.84 107.95) (xy 370.84 105.41)
		)
		(stroke
			(width 0)
			(type default)
		)
	)
	(wire
		(pts
			(xy 270.51 97.79) (xy 270.51 100.33)
		)
		(stroke
			(width 0)
			(type default)
		)
	)
	(wire
		(pts
			(xy 388.62 91.44) (xy 388.62 93.98)
		)
		(stroke
			(width 0)
			(type default)
		)
	)
	(wire
		(pts
			(xy 361.95 130.81) (xy 361.95 133.35)
		)
		(stroke
			(width 0)
			(type default)
		)
	)
	(wire
		(pts
			(xy 88.9 95.25) (xy 88.9 92.71)
		)
		(stroke
			(width 0)
			(type default)
		)
	)
	(wire
		(pts
			(xy 317.5 52.07) (xy 317.5 54.61)
		)
		(stroke
			(width 0)
			(type default)
		)
	)
	(wire
		(pts
			(xy 292.1 152.4) (xy 292.1 149.86)
		)
		(stroke
			(width 0)
			(type default)
		)
	)
	(wire
		(pts
			(xy 166.37 130.81) (xy 166.37 199.39)
		)
		(stroke
			(width 0)
			(type default)
		)
	)
	(wire
		(pts
			(xy 370.84 86.36) (xy 370.84 83.82)
		)
		(stroke
			(width 0)
			(type default)
		)
	)
	(wire
		(pts
			(xy 74.93 226.06) (xy 80.01 226.06)
		)
		(stroke
			(width 0)
			(type default)
		)
	)
	(wire
		(pts
			(xy 73.66 46.99) (xy 73.66 44.45)
		)
		(stroke
			(width 0)
			(type default)
		)
	)
	(wire
		(pts
			(xy 283.21 105.41) (xy 270.51 105.41)
		)
		(stroke
			(width 0)
			(type default)
		)
	)
	(wire
		(pts
			(xy 26.67 199.39) (xy 74.93 199.39)
		)
		(stroke
			(width 0)
			(type default)
		)
	)
	(wire
		(pts
			(xy 388.62 125.73) (xy 388.62 123.19)
		)
		(stroke
			(width 0)
			(type default)
		)
	)
	(wire
		(pts
			(xy 102.87 91.44) (xy 102.87 92.71)
		)
		(stroke
			(width 0)
			(type default)
		)
	)
	(wire
		(pts
			(xy 317.5 91.44) (xy 317.5 93.98)
		)
		(stroke
			(width 0)
			(type default)
		)
	)
	(wire
		(pts
			(xy 361.95 44.45) (xy 370.84 44.45)
		)
		(stroke
			(width 0)
			(type default)
		)
	)
	(wire
		(pts
			(xy 97.79 119.38) (xy 101.6 119.38)
		)
		(stroke
			(width 0)
			(type default)
		)
	)
	(wire
		(pts
			(xy 151.13 172.72) (xy 163.83 172.72)
		)
		(stroke
			(width 0)
			(type default)
		)
	)
	(wire
		(pts
			(xy 388.62 86.36) (xy 388.62 83.82)
		)
		(stroke
			(width 0)
			(type default)
		)
	)
	(wire
		(pts
			(xy 115.57 121.92) (xy 115.57 119.38)
		)
		(stroke
			(width 0)
			(type default)
		)
	)
	(wire
		(pts
			(xy 166.37 199.39) (xy 151.13 199.39)
		)
		(stroke
			(width 0)
			(type default)
		)
	)
	(wire
		(pts
			(xy 64.77 46.99) (xy 64.77 44.45)
		)
		(stroke
			(width 0)
			(type default)
		)
	)
	(wire
		(pts
			(xy 379.73 68.58) (xy 379.73 66.04)
		)
		(stroke
			(width 0)
			(type default)
		)
	)
	(wire
		(pts
			(xy 97.79 119.38) (xy 88.9 119.38)
		)
		(stroke
			(width 0)
			(type default)
		)
	)
	(wire
		(pts
			(xy 267.97 140.97) (xy 270.51 140.97)
		)
		(stroke
			(width 0)
			(type default)
		)
	)
	(wire
		(pts
			(xy 163.83 125.73) (xy 163.83 172.72)
		)
		(stroke
			(width 0)
			(type default)
		)
	)
	(wire
		(pts
			(xy 26.67 196.85) (xy 26.67 199.39)
		)
		(stroke
			(width 0)
			(type default)
		)
	)
	(wire
		(pts
			(xy 142.24 66.04) (xy 142.24 68.58)
		)
		(stroke
			(width 0)
			(type default)
		)
	)
	(wire
		(pts
			(xy 101.6 198.12) (xy 101.6 199.39)
		)
		(stroke
			(width 0)
			(type default)
		)
	)
	(wire
		(pts
			(xy 151.13 172.72) (xy 151.13 175.26)
		)
		(stroke
			(width 0)
			(type default)
		)
	)
	(wire
		(pts
			(xy 99.06 46.99) (xy 99.06 44.45)
		)
		(stroke
			(width 0)
			(type default)
		)
	)
	(wire
		(pts
			(xy 208.28 116.84) (xy 208.28 120.65)
		)
		(stroke
			(width 0)
			(type default)
		)
	)
	(wire
		(pts
			(xy 115.57 44.45) (xy 124.46 44.45)
		)
		(stroke
			(width 0)
			(type default)
		)
	)
	(wire
		(pts
			(xy 379.73 44.45) (xy 388.62 44.45)
		)
		(stroke
			(width 0)
			(type default)
		)
	)
	(wire
		(pts
			(xy 46.99 44.45) (xy 38.1 44.45)
		)
		(stroke
			(width 0)
			(type default)
		)
	)
	(wire
		(pts
			(xy 335.28 105.41) (xy 344.17 105.41)
		)
		(stroke
			(width 0)
			(type default)
		)
	)
	(wire
		(pts
			(xy 76.2 153.67) (xy 76.2 156.21)
		)
		(stroke
			(width 0)
			(type default)
		)
	)
	(wire
		(pts
			(xy 270.51 95.25) (xy 276.86 95.25)
		)
		(stroke
			(width 0)
			(type default)
		)
	)
	(wire
		(pts
			(xy 361.95 123.19) (xy 370.84 123.19)
		)
		(stroke
			(width 0)
			(type default)
		)
	)
	(wire
		(pts
			(xy 124.46 199.39) (xy 101.6 199.39)
		)
		(stroke
			(width 0)
			(type default)
		)
	)
	(wire
		(pts
			(xy 299.72 91.44) (xy 299.72 93.98)
		)
		(stroke
			(width 0)
			(type default)
		)
	)
	(wire
		(pts
			(xy 293.37 66.04) (xy 299.72 66.04)
		)
		(stroke
			(width 0)
			(type default)
		)
	)
	(wire
		(pts
			(xy 270.51 135.89) (xy 270.51 138.43)
		)
		(stroke
			(width 0)
			(type default)
		)
	)
	(wire
		(pts
			(xy 142.24 44.45) (xy 151.13 44.45)
		)
		(stroke
			(width 0)
			(type default)
		)
	)
	(wire
		(pts
			(xy 299.72 44.45) (xy 308.61 44.45)
		)
		(stroke
			(width 0)
			(type default)
		)
	)
	(wire
		(pts
			(xy 214.63 100.33) (xy 214.63 97.79)
		)
		(stroke
			(width 0)
			(type default)
		)
	)
	(wire
		(pts
			(xy 308.61 130.81) (xy 308.61 133.35)
		)
		(stroke
			(width 0)
			(type default)
		)
	)
	(wire
		(pts
			(xy 151.13 121.92) (xy 151.13 119.38)
		)
		(stroke
			(width 0)
			(type default)
		)
	)
	(wire
		(pts
			(xy 151.13 44.45) (xy 151.13 46.99)
		)
		(stroke
			(width 0)
			(type default)
		)
	)
	(wire
		(pts
			(xy 270.51 138.43) (xy 270.51 140.97)
		)
		(stroke
			(width 0)
			(type default)
		)
	)
	(wire
		(pts
			(xy 326.39 68.58) (xy 326.39 66.04)
		)
		(stroke
			(width 0)
			(type default)
		)
	)
	(wire
		(pts
			(xy 388.62 66.04) (xy 397.51 66.04)
		)
		(stroke
			(width 0)
			(type default)
		)
	)
	(wire
		(pts
			(xy 67.31 180.34) (xy 67.31 182.88)
		)
		(stroke
			(width 0)
			(type default)
		)
	)
	(wire
		(pts
			(xy 48.26 153.67) (xy 48.26 156.21)
		)
		(stroke
			(width 0)
			(type default)
		)
	)
	(wire
		(pts
			(xy 124.46 146.05) (xy 133.35 146.05)
		)
		(stroke
			(width 0)
			(type default)
		)
	)
	(wire
		(pts
			(xy 77.47 172.72) (xy 81.28 172.72)
		)
		(stroke
			(width 0)
			(type default)
		)
	)
	(wire
		(pts
			(xy 326.39 83.82) (xy 335.28 83.82)
		)
		(stroke
			(width 0)
			(type default)
		)
	)
	(wire
		(pts
			(xy 124.46 76.2) (xy 124.46 73.66)
		)
		(stroke
			(width 0)
			(type default)
		)
	)
	(wire
		(pts
			(xy 101.6 119.38) (xy 115.57 119.38)
		)
		(stroke
			(width 0)
			(type default)
		)
	)
	(wire
		(pts
			(xy 151.13 52.07) (xy 151.13 54.61)
		)
		(stroke
			(width 0)
			(type default)
		)
	)
	(wire
		(pts
			(xy 379.73 130.81) (xy 379.73 133.35)
		)
		(stroke
			(width 0)
			(type default)
		)
	)
	(wire
		(pts
			(xy 97.79 127) (xy 97.79 129.54)
		)
		(stroke
			(width 0)
			(type default)
		)
	)
	(wire
		(pts
			(xy 101.6 171.45) (xy 101.6 172.72)
		)
		(stroke
			(width 0)
			(type default)
		)
	)
	(wire
		(pts
			(xy 151.13 127) (xy 151.13 129.54)
		)
		(stroke
			(width 0)
			(type default)
		)
	)
	(wire
		(pts
			(xy 46.99 52.07) (xy 46.99 54.61)
		)
		(stroke
			(width 0)
			(type default)
		)
	)
	(wire
		(pts
			(xy 133.35 148.59) (xy 133.35 146.05)
		)
		(stroke
			(width 0)
			(type default)
		)
	)
	(wire
		(pts
			(xy 90.17 226.06) (xy 101.6 226.06)
		)
		(stroke
			(width 0)
			(type default)
		)
	)
	(wire
		(pts
			(xy 370.84 125.73) (xy 370.84 123.19)
		)
		(stroke
			(width 0)
			(type default)
		)
	)
	(wire
		(pts
			(xy 151.13 44.45) (xy 163.83 44.45)
		)
		(stroke
			(width 0)
			(type default)
		)
	)
	(wire
		(pts
			(xy 30.48 148.59) (xy 30.48 146.05)
		)
		(stroke
			(width 0)
			(type default)
		)
	)
	(wire
		(pts
			(xy 344.17 46.99) (xy 344.17 44.45)
		)
		(stroke
			(width 0)
			(type default)
		)
	)
	(wire
		(pts
			(xy 151.13 199.39) (xy 142.24 199.39)
		)
		(stroke
			(width 0)
			(type default)
		)
	)
	(wire
		(pts
			(xy 388.62 52.07) (xy 388.62 54.61)
		)
		(stroke
			(width 0)
			(type default)
		)
	)
	(wire
		(pts
			(xy 86.36 172.72) (xy 88.9 172.72)
		)
		(stroke
			(width 0)
			(type default)
		)
	)
	(wire
		(pts
			(xy 115.57 119.38) (xy 124.46 119.38)
		)
		(stroke
			(width 0)
			(type default)
		)
	)
	(wire
		(pts
			(xy 115.57 148.59) (xy 115.57 146.05)
		)
		(stroke
			(width 0)
			(type default)
		)
	)
	(wire
		(pts
			(xy 270.51 133.35) (xy 270.51 135.89)
		)
		(stroke
			(width 0)
			(type default)
		)
	)
	(wire
		(pts
			(xy 97.79 121.92) (xy 97.79 119.38)
		)
		(stroke
			(width 0)
			(type default)
		)
	)
	(wire
		(pts
			(xy 344.17 44.45) (xy 353.06 44.45)
		)
		(stroke
			(width 0)
			(type default)
		)
	)
	(wire
		(pts
			(xy 270.51 90.17) (xy 290.83 90.17)
		)
		(stroke
			(width 0)
			(type default)
		)
	)
	(wire
		(pts
			(xy 189.23 130.81) (xy 189.23 116.84)
		)
		(stroke
			(width 0)
			(type default)
		)
	)
	(wire
		(pts
			(xy 97.79 68.58) (xy 97.79 66.04)
		)
		(stroke
			(width 0)
			(type default)
		)
	)
	(wire
		(pts
			(xy 97.79 172.72) (xy 101.6 172.72)
		)
		(stroke
			(width 0)
			(type default)
		)
	)
	(wire
		(pts
			(xy 344.17 68.58) (xy 344.17 66.04)
		)
		(stroke
			(width 0)
			(type default)
		)
	)
	(wire
		(pts
			(xy 151.13 146.05) (xy 161.29 146.05)
		)
		(stroke
			(width 0)
			(type default)
		)
	)
	(wire
		(pts
			(xy 142.24 175.26) (xy 142.24 172.72)
		)
		(stroke
			(width 0)
			(type default)
		)
	)
	(wire
		(pts
			(xy 81.28 44.45) (xy 90.17 44.45)
		)
		(stroke
			(width 0)
			(type default)
		)
	)
	(wire
		(pts
			(xy 217.17 140.97) (xy 171.45 140.97)
		)
		(stroke
			(width 0)
			(type default)
		)
	)
	(wire
		(pts
			(xy 326.39 125.73) (xy 326.39 123.19)
		)
		(stroke
			(width 0)
			(type default)
		)
	)
	(wire
		(pts
			(xy 267.97 107.95) (xy 270.51 107.95)
		)
		(stroke
			(width 0)
			(type default)
		)
	)
	(wire
		(pts
			(xy 26.67 170.18) (xy 26.67 172.72)
		)
		(stroke
			(width 0)
			(type default)
		)
	)
	(wire
		(pts
			(xy 161.29 95.25) (xy 208.28 95.25)
		)
		(stroke
			(width 0)
			(type default)
		)
	)
	(wire
		(pts
			(xy 66.04 146.05) (xy 66.04 148.59)
		)
		(stroke
			(width 0)
			(type default)
		)
	)
	(wire
		(pts
			(xy 335.28 66.04) (xy 326.39 66.04)
		)
		(stroke
			(width 0)
			(type default)
		)
	)
	(wire
		(pts
			(xy 317.5 105.41) (xy 326.39 105.41)
		)
		(stroke
			(width 0)
			(type default)
		)
	)
	(wire
		(pts
			(xy 124.46 172.72) (xy 133.35 172.72)
		)
		(stroke
			(width 0)
			(type default)
		)
	)
	(wire
		(pts
			(xy 90.17 207.01) (xy 90.17 209.55)
		)
		(stroke
			(width 0)
			(type default)
		)
	)
	(wire
		(pts
			(xy 217.17 120.65) (xy 208.28 120.65)
		)
		(stroke
			(width 0)
			(type default)
		)
	)
	(wire
		(pts
			(xy 308.61 123.19) (xy 317.5 123.19)
		)
		(stroke
			(width 0)
			(type default)
		)
	)
	(wire
		(pts
			(xy 214.63 97.79) (xy 214.63 95.25)
		)
		(stroke
			(width 0)
			(type default)
		)
	)
	(wire
		(pts
			(xy 361.95 113.03) (xy 361.95 115.57)
		)
		(stroke
			(width 0)
			(type default)
		)
	)
	(wire
		(pts
			(xy 168.91 135.89) (xy 180.34 135.89)
		)
		(stroke
			(width 0)
			(type default)
		)
	)
	(wire
		(pts
			(xy 180.34 135.89) (xy 217.17 135.89)
		)
		(stroke
			(width 0)
			(type default)
		)
	)
	(wire
		(pts
			(xy 30.48 146.05) (xy 39.37 146.05)
		)
		(stroke
			(width 0)
			(type default)
		)
	)
	(wire
		(pts
			(xy 379.73 66.04) (xy 388.62 66.04)
		)
		(stroke
			(width 0)
			(type default)
		)
	)
	(wire
		(pts
			(xy 299.72 130.81) (xy 299.72 133.35)
		)
		(stroke
			(width 0)
			(type default)
		)
	)
	(wire
		(pts
			(xy 379.73 125.73) (xy 379.73 123.19)
		)
		(stroke
			(width 0)
			(type default)
		)
	)
	(wire
		(pts
			(xy 77.47 172.72) (xy 67.31 172.72)
		)
		(stroke
			(width 0)
			(type default)
		)
	)
	(wire
		(pts
			(xy 77.47 100.33) (xy 77.47 102.87)
		)
		(stroke
			(width 0)
			(type default)
		)
	)
	(wire
		(pts
			(xy 270.51 105.41) (xy 267.97 105.41)
		)
		(stroke
			(width 0)
			(type default)
		)
	)
	(wire
		(pts
			(xy 39.37 153.67) (xy 39.37 156.21)
		)
		(stroke
			(width 0)
			(type default)
		)
	)
	(wire
		(pts
			(xy 344.17 107.95) (xy 344.17 105.41)
		)
		(stroke
			(width 0)
			(type default)
		)
	)
	(wire
		(pts
			(xy 133.35 73.66) (xy 133.35 76.2)
		)
		(stroke
			(width 0)
			(type default)
		)
	)
	(wire
		(pts
			(xy 361.95 52.07) (xy 361.95 54.61)
		)
		(stroke
			(width 0)
			(type default)
		)
	)
	(wire
		(pts
			(xy 171.45 140.97) (xy 171.45 252.73)
		)
		(stroke
			(width 0)
			(type default)
		)
	)
	(wire
		(pts
			(xy 299.72 123.19) (xy 299.72 125.73)
		)
		(stroke
			(width 0)
			(type default)
		)
	)
	(wire
		(pts
			(xy 151.13 119.38) (xy 160.02 119.38)
		)
		(stroke
			(width 0)
			(type default)
		)
	)
	(wire
		(pts
			(xy 283.21 142.24) (xy 289.56 142.24)
		)
		(stroke
			(width 0)
			(type default)
		)
	)
	(wire
		(pts
			(xy 267.97 118.11) (xy 273.05 118.11)
		)
		(stroke
			(width 0)
			(type default)
		)
	)
	(wire
		(pts
			(xy 115.57 153.67) (xy 115.57 156.21)
		)
		(stroke
			(width 0)
			(type default)
		)
	)
	(wire
		(pts
			(xy 353.06 52.07) (xy 353.06 54.61)
		)
		(stroke
			(width 0)
			(type default)
		)
	)
	(wire
		(pts
			(xy 77.47 92.71) (xy 81.28 92.71)
		)
		(stroke
			(width 0)
			(type default)
		)
	)
	(wire
		(pts
			(xy 90.17 199.39) (xy 90.17 201.93)
		)
		(stroke
			(width 0)
			(type default)
		)
	)
	(wire
		(pts
			(xy 344.17 73.66) (xy 344.17 76.2)
		)
		(stroke
			(width 0)
			(type default)
		)
	)
	(wire
		(pts
			(xy 326.39 46.99) (xy 326.39 44.45)
		)
		(stroke
			(width 0)
			(type default)
		)
	)
	(wire
		(pts
			(xy 76.2 148.59) (xy 76.2 146.05)
		)
		(stroke
			(width 0)
			(type default)
		)
	)
	(wire
		(pts
			(xy 299.72 83.82) (xy 308.61 83.82)
		)
		(stroke
			(width 0)
			(type default)
		)
	)
	(wire
		(pts
			(xy 344.17 52.07) (xy 344.17 54.61)
		)
		(stroke
			(width 0)
			(type default)
		)
	)
	(wire
		(pts
			(xy 292.1 142.24) (xy 300.99 142.24)
		)
		(stroke
			(width 0)
			(type default)
		)
	)
	(wire
		(pts
			(xy 270.51 107.95) (xy 270.51 105.41)
		)
		(stroke
			(width 0)
			(type default)
		)
	)
	(wire
		(pts
			(xy 267.97 143.51) (xy 270.51 143.51)
		)
		(stroke
			(width 0)
			(type default)
		)
	)
	(wire
		(pts
			(xy 74.93 233.68) (xy 74.93 236.22)
		)
		(stroke
			(width 0)
			(type default)
		)
	)
	(wire
		(pts
			(xy 326.39 73.66) (xy 326.39 76.2)
		)
		(stroke
			(width 0)
			(type default)
		)
	)
	(wire
		(pts
			(xy 308.61 91.44) (xy 308.61 93.98)
		)
		(stroke
			(width 0)
			(type default)
		)
	)
	(wire
		(pts
			(xy 180.34 116.84) (xy 180.34 135.89)
		)
		(stroke
			(width 0)
			(type default)
		)
	)
	(wire
		(pts
			(xy 214.63 90.17) (xy 217.17 90.17)
		)
		(stroke
			(width 0)
			(type default)
		)
	)
	(wire
		(pts
			(xy 133.35 121.92) (xy 133.35 119.38)
		)
		(stroke
			(width 0)
			(type default)
		)
	)
	(wire
		(pts
			(xy 151.13 226.06) (xy 168.91 226.06)
		)
		(stroke
			(width 0)
			(type default)
		)
	)
	(wire
		(pts
			(xy 55.88 44.45) (xy 46.99 44.45)
		)
		(stroke
			(width 0)
			(type default)
		)
	)
	(wire
		(pts
			(xy 161.29 66.04) (xy 161.29 95.25)
		)
		(stroke
			(width 0)
			(type default)
		)
	)
	(wire
		(pts
			(xy 270.51 90.17) (xy 267.97 90.17)
		)
		(stroke
			(width 0)
			(type default)
		)
	)
	(wire
		(pts
			(xy 88.9 180.34) (xy 88.9 182.88)
		)
		(stroke
			(width 0)
			(type default)
		)
	)
	(wire
		(pts
			(xy 26.67 250.19) (xy 26.67 252.73)
		)
		(stroke
			(width 0)
			(type default)
		)
	)
	(wire
		(pts
			(xy 379.73 123.19) (xy 388.62 123.19)
		)
		(stroke
			(width 0)
			(type default)
		)
	)
	(wire
		(pts
			(xy 142.24 119.38) (xy 151.13 119.38)
		)
		(stroke
			(width 0)
			(type default)
		)
	)
	(wire
		(pts
			(xy 335.28 44.45) (xy 344.17 44.45)
		)
		(stroke
			(width 0)
			(type default)
		)
	)
	(wire
		(pts
			(xy 86.36 146.05) (xy 90.17 146.05)
		)
		(stroke
			(width 0)
			(type default)
		)
	)
	(wire
		(pts
			(xy 97.79 146.05) (xy 97.79 148.59)
		)
		(stroke
			(width 0)
			(type default)
		)
	)
	(wire
		(pts
			(xy 133.35 46.99) (xy 133.35 44.45)
		)
		(stroke
			(width 0)
			(type default)
		)
	)
	(wire
		(pts
			(xy 151.13 180.34) (xy 151.13 182.88)
		)
		(stroke
			(width 0)
			(type default)
		)
	)
	(wire
		(pts
			(xy 142.24 148.59) (xy 142.24 146.05)
		)
		(stroke
			(width 0)
			(type default)
		)
	)
	(wire
		(pts
			(xy 300.99 152.4) (xy 300.99 149.86)
		)
		(stroke
			(width 0)
			(type default)
		)
	)
	(wire
		(pts
			(xy 26.67 116.84) (xy 26.67 119.38)
		)
		(stroke
			(width 0)
			(type default)
		)
	)
	(wire
		(pts
			(xy 361.95 105.41) (xy 370.84 105.41)
		)
		(stroke
			(width 0)
			(type default)
		)
	)
	(wire
		(pts
			(xy 283.21 105.41) (xy 293.37 105.41)
		)
		(stroke
			(width 0)
			(type default)
		)
	)
	(wire
		(pts
			(xy 267.97 95.25) (xy 270.51 95.25)
		)
		(stroke
			(width 0)
			(type default)
		)
	)
	(wire
		(pts
			(xy 171.45 252.73) (xy 101.6 252.73)
		)
		(stroke
			(width 0)
			(type default)
		)
	)
	(wire
		(pts
			(xy 97.79 66.04) (xy 124.46 66.04)
		)
		(stroke
			(width 0)
			(type default)
		)
	)
	(wire
		(pts
			(xy 88.9 119.38) (xy 88.9 121.92)
		)
		(stroke
			(width 0)
			(type default)
		)
	)
	(wire
		(pts
			(xy 379.73 86.36) (xy 379.73 83.82)
		)
		(stroke
			(width 0)
			(type default)
		)
	)
	(wire
		(pts
			(xy 142.24 172.72) (xy 133.35 172.72)
		)
		(stroke
			(width 0)
			(type default)
		)
	)
	(wire
		(pts
			(xy 88.9 100.33) (xy 88.9 102.87)
		)
		(stroke
			(width 0)
			(type default)
		)
	)
	(wire
		(pts
			(xy 326.39 113.03) (xy 326.39 115.57)
		)
		(stroke
			(width 0)
			(type default)
		)
	)
	(wire
		(pts
			(xy 85.09 199.39) (xy 90.17 199.39)
		)
		(stroke
			(width 0)
			(type default)
		)
	)
	(wire
		(pts
			(xy 85.09 226.06) (xy 90.17 226.06)
		)
		(stroke
			(width 0)
			(type default)
		)
	)
	(wire
		(pts
			(xy 86.36 119.38) (xy 88.9 119.38)
		)
		(stroke
			(width 0)
			(type default)
		)
	)
	(wire
		(pts
			(xy 344.17 113.03) (xy 344.17 115.57)
		)
		(stroke
			(width 0)
			(type default)
		)
	)
	(wire
		(pts
			(xy 86.36 153.67) (xy 86.36 156.21)
		)
		(stroke
			(width 0)
			(type default)
		)
	)
	(wire
		(pts
			(xy 335.28 107.95) (xy 335.28 105.41)
		)
		(stroke
			(width 0)
			(type default)
		)
	)
	(wire
		(pts
			(xy 142.24 46.99) (xy 142.24 44.45)
		)
		(stroke
			(width 0)
			(type default)
		)
	)
	(wire
		(pts
			(xy 300.99 142.24) (xy 309.88 142.24)
		)
		(stroke
			(width 0)
			(type default)
		)
	)
	(wire
		(pts
			(xy 370.84 52.07) (xy 370.84 54.61)
		)
		(stroke
			(width 0)
			(type default)
		)
	)
	(wire
		(pts
			(xy 90.17 44.45) (xy 99.06 44.45)
		)
		(stroke
			(width 0)
			(type default)
		)
	)
	(wire
		(pts
			(xy 85.09 252.73) (xy 90.17 252.73)
		)
		(stroke
			(width 0)
			(type default)
		)
	)
	(wire
		(pts
			(xy 30.48 153.67) (xy 30.48 156.21)
		)
		(stroke
			(width 0)
			(type default)
		)
	)
	(wire
		(pts
			(xy 171.45 140.97) (xy 171.45 116.84)
		)
		(stroke
			(width 0)
			(type default)
		)
	)
	(wire
		(pts
			(xy 214.63 110.49) (xy 217.17 110.49)
		)
		(stroke
			(width 0)
			(type default)
		)
	)
	(wire
		(pts
			(xy 88.9 127) (xy 88.9 129.54)
		)
		(stroke
			(width 0)
			(type default)
		)
	)
	(wire
		(pts
			(xy 270.51 143.51) (xy 270.51 152.4)
		)
		(stroke
			(width 0)
			(type default)
		)
	)
	(wire
		(pts
			(xy 151.13 228.6) (xy 151.13 226.06)
		)
		(stroke
			(width 0)
			(type default)
		)
	)
	(wire
		(pts
			(xy 397.51 52.07) (xy 397.51 54.61)
		)
		(stroke
			(width 0)
			(type default)
		)
	)
	(wire
		(pts
			(xy 99.06 44.45) (xy 115.57 44.45)
		)
		(stroke
			(width 0)
			(type default)
		)
	)
	(wire
		(pts
			(xy 64.77 52.07) (xy 64.77 54.61)
		)
		(stroke
			(width 0)
			(type default)
		)
	)
	(wire
		(pts
			(xy 110.49 144.78) (xy 110.49 146.05)
		)
		(stroke
			(width 0)
			(type default)
		)
	)
	(wire
		(pts
			(xy 142.24 66.04) (xy 151.13 66.04)
		)
		(stroke
			(width 0)
			(type default)
		)
	)
	(wire
		(pts
			(xy 397.51 91.44) (xy 397.51 93.98)
		)
		(stroke
			(width 0)
			(type default)
		)
	)
	(wire
		(pts
			(xy 317.5 66.04) (xy 326.39 66.04)
		)
		(stroke
			(width 0)
			(type default)
		)
	)
	(wire
		(pts
			(xy 353.06 113.03) (xy 353.06 115.57)
		)
		(stroke
			(width 0)
			(type default)
		)
	)
	(wire
		(pts
			(xy 353.06 83.82) (xy 361.95 83.82)
		)
		(stroke
			(width 0)
			(type default)
		)
	)
	(wire
		(pts
			(xy 142.24 180.34) (xy 142.24 182.88)
		)
		(stroke
			(width 0)
			(type default)
		)
	)
	(wire
		(pts
			(xy 267.97 133.35) (xy 270.51 133.35)
		)
		(stroke
			(width 0)
			(type default)
		)
	)
	(wire
		(pts
			(xy 299.72 52.07) (xy 299.72 54.61)
		)
		(stroke
			(width 0)
			(type default)
		)
	)
	(wire
		(pts
			(xy 267.97 97.79) (xy 270.51 97.79)
		)
		(stroke
			(width 0)
			(type default)
		)
	)
	(wire
		(pts
			(xy 335.28 73.66) (xy 335.28 76.2)
		)
		(stroke
			(width 0)
			(type default)
		)
	)
	(wire
		(pts
			(xy 86.36 92.71) (xy 88.9 92.71)
		)
		(stroke
			(width 0)
			(type default)
		)
	)
	(wire
		(pts
			(xy 106.68 153.67) (xy 106.68 156.21)
		)
		(stroke
			(width 0)
			(type default)
		)
	)
	(wire
		(pts
			(xy 317.5 125.73) (xy 317.5 123.19)
		)
		(stroke
			(width 0)
			(type default)
		)
	)
	(wire
		(pts
			(xy 163.83 125.73) (xy 198.12 125.73)
		)
		(stroke
			(width 0)
			(type default)
		)
	)
	(wire
		(pts
			(xy 133.35 207.01) (xy 133.35 209.55)
		)
		(stroke
			(width 0)
			(type default)
		)
	)
	(wire
		(pts
			(xy 97.79 66.04) (xy 88.9 66.04)
		)
		(stroke
			(width 0)
			(type default)
		)
	)
	(wire
		(pts
			(xy 388.62 44.45) (xy 397.51 44.45)
		)
		(stroke
			(width 0)
			(type default)
		)
	)
	(wire
		(pts
			(xy 317.5 113.03) (xy 317.5 115.57)
		)
		(stroke
			(width 0)
			(type default)
		)
	)
	(wire
		(pts
			(xy 317.5 68.58) (xy 317.5 66.04)
		)
		(stroke
			(width 0)
			(type default)
		)
	)
	(wire
		(pts
			(xy 370.84 130.81) (xy 370.84 133.35)
		)
		(stroke
			(width 0)
			(type default)
		)
	)
	(wire
		(pts
			(xy 293.37 105.41) (xy 299.72 105.41)
		)
		(stroke
			(width 0)
			(type default)
		)
	)
	(wire
		(pts
			(xy 90.17 46.99) (xy 90.17 44.45)
		)
		(stroke
			(width 0)
			(type default)
		)
	)
	(wire
		(pts
			(xy 361.95 125.73) (xy 361.95 123.19)
		)
		(stroke
			(width 0)
			(type default)
		)
	)
	(wire
		(pts
			(xy 88.9 172.72) (xy 88.9 175.26)
		)
		(stroke
			(width 0)
			(type default)
		)
	)
	(wire
		(pts
			(xy 326.39 107.95) (xy 326.39 105.41)
		)
		(stroke
			(width 0)
			(type default)
		)
	)
	(wire
		(pts
			(xy 88.9 66.04) (xy 88.9 68.58)
		)
		(stroke
			(width 0)
			(type default)
		)
	)
	(wire
		(pts
			(xy 293.37 123.19) (xy 293.37 105.41)
		)
		(stroke
			(width 0)
			(type default)
		)
	)
	(wire
		(pts
			(xy 289.56 139.7) (xy 289.56 142.24)
		)
		(stroke
			(width 0)
			(type default)
		)
	)
	(wire
		(pts
			(xy 199.39 110.49) (xy 214.63 110.49)
		)
		(stroke
			(width 0)
			(type default)
		)
	)
	(wire
		(pts
			(xy 317.5 66.04) (xy 308.61 66.04)
		)
		(stroke
			(width 0)
			(type default)
		)
	)
	(wire
		(pts
			(xy 283.21 118.11) (xy 283.21 142.24)
		)
		(stroke
			(width 0)
			(type default)
		)
	)
	(wire
		(pts
			(xy 160.02 119.38) (xy 160.02 110.49)
		)
		(stroke
			(width 0)
			(type default)
		)
	)
	(wire
		(pts
			(xy 81.28 52.07) (xy 81.28 54.61)
		)
		(stroke
			(width 0)
			(type default)
		)
	)
	(wire
		(pts
			(xy 214.63 87.63) (xy 214.63 90.17)
		)
		(stroke
			(width 0)
			(type default)
		)
	)
	(wire
		(pts
			(xy 353.06 86.36) (xy 353.06 83.82)
		)
		(stroke
			(width 0)
			(type default)
		)
	)
	(wire
		(pts
			(xy 379.73 73.66) (xy 379.73 76.2)
		)
		(stroke
			(width 0)
			(type default)
		)
	)
	(wire
		(pts
			(xy 124.46 121.92) (xy 124.46 119.38)
		)
		(stroke
			(width 0)
			(type default)
		)
	)
	(wire
		(pts
			(xy 317.5 107.95) (xy 317.5 105.41)
		)
		(stroke
			(width 0)
			(type default)
		)
	)
	(wire
		(pts
			(xy 308.61 83.82) (xy 317.5 83.82)
		)
		(stroke
			(width 0)
			(type default)
		)
	)
	(wire
		(pts
			(xy 142.24 119.38) (xy 142.24 121.92)
		)
		(stroke
			(width 0)
			(type default)
		)
	)
	(wire
		(pts
			(xy 270.51 140.97) (xy 270.51 143.51)
		)
		(stroke
			(width 0)
			(type default)
		)
	)
	(wire
		(pts
			(xy 397.51 68.58) (xy 397.51 66.04)
		)
		(stroke
			(width 0)
			(type default)
		)
	)
	(wire
		(pts
			(xy 299.72 123.19) (xy 308.61 123.19)
		)
		(stroke
			(width 0)
			(type default)
		)
	)
	(wire
		(pts
			(xy 299.72 105.41) (xy 299.72 107.95)
		)
		(stroke
			(width 0)
			(type default)
		)
	)
	(wire
		(pts
			(xy 124.46 175.26) (xy 124.46 172.72)
		)
		(stroke
			(width 0)
			(type default)
		)
	)
	(wire
		(pts
			(xy 353.06 105.41) (xy 361.95 105.41)
		)
		(stroke
			(width 0)
			(type default)
		)
	)
	(wire
		(pts
			(xy 214.63 95.25) (xy 217.17 95.25)
		)
		(stroke
			(width 0)
			(type default)
		)
	)
	(wire
		(pts
			(xy 388.62 130.81) (xy 388.62 133.35)
		)
		(stroke
			(width 0)
			(type default)
		)
	)
	(wire
		(pts
			(xy 57.15 153.67) (xy 57.15 156.21)
		)
		(stroke
			(width 0)
			(type default)
		)
	)
	(wire
		(pts
			(xy 74.93 252.73) (xy 74.93 255.27)
		)
		(stroke
			(width 0)
			(type default)
		)
	)
	(wire
		(pts
			(xy 74.93 260.35) (xy 74.93 262.89)
		)
		(stroke
			(width 0)
			(type default)
		)
	)
	(wire
		(pts
			(xy 76.2 146.05) (xy 86.36 146.05)
		)
		(stroke
			(width 0)
			(type default)
		)
	)
	(wire
		(pts
			(xy 151.13 146.05) (xy 142.24 146.05)
		)
		(stroke
			(width 0)
			(type default)
		)
	)
	(wire
		(pts
			(xy 124.46 46.99) (xy 124.46 44.45)
		)
		(stroke
			(width 0)
			(type default)
		)
	)
	(wire
		(pts
			(xy 97.79 146.05) (xy 106.68 146.05)
		)
		(stroke
			(width 0)
			(type default)
		)
	)
	(wire
		(pts
			(xy 308.61 52.07) (xy 308.61 54.61)
		)
		(stroke
			(width 0)
			(type default)
		)
	)
	(wire
		(pts
			(xy 95.25 146.05) (xy 97.79 146.05)
		)
		(stroke
			(width 0)
			(type default)
		)
	)
	(wire
		(pts
			(xy 270.51 115.57) (xy 270.51 110.49)
		)
		(stroke
			(width 0)
			(type default)
		)
	)
	(wire
		(pts
			(xy 64.77 44.45) (xy 73.66 44.45)
		)
		(stroke
			(width 0)
			(type default)
		)
	)
	(wire
		(pts
			(xy 317.5 46.99) (xy 317.5 44.45)
		)
		(stroke
			(width 0)
			(type default)
		)
	)
	(wire
		(pts
			(xy 74.93 199.39) (xy 74.93 201.93)
		)
		(stroke
			(width 0)
			(type default)
		)
	)
	(wire
		(pts
			(xy 88.9 92.71) (xy 102.87 92.71)
		)
		(stroke
			(width 0)
			(type default)
		)
	)
	(wire
		(pts
			(xy 397.51 44.45) (xy 397.51 46.99)
		)
		(stroke
			(width 0)
			(type default)
		)
	)
	(wire
		(pts
			(xy 283.21 144.78) (xy 283.21 142.24)
		)
		(stroke
			(width 0)
			(type default)
		)
	)
	(wire
		(pts
			(xy 326.39 130.81) (xy 326.39 133.35)
		)
		(stroke
			(width 0)
			(type default)
		)
	)
	(wire
		(pts
			(xy 124.46 44.45) (xy 133.35 44.45)
		)
		(stroke
			(width 0)
			(type default)
		)
	)
	(wire
		(pts
			(xy 133.35 146.05) (xy 142.24 146.05)
		)
		(stroke
			(width 0)
			(type default)
		)
	)
	(wire
		(pts
			(xy 344.17 130.81) (xy 344.17 133.35)
		)
		(stroke
			(width 0)
			(type default)
		)
	)
	(wire
		(pts
			(xy 133.35 127) (xy 133.35 129.54)
		)
		(stroke
			(width 0)
			(type default)
		)
	)
	(wire
		(pts
			(xy 57.15 146.05) (xy 57.15 148.59)
		)
		(stroke
			(width 0)
			(type default)
		)
	)
	(wire
		(pts
			(xy 86.36 146.05) (xy 86.36 148.59)
		)
		(stroke
			(width 0)
			(type default)
		)
	)
	(wire
		(pts
			(xy 388.62 46.99) (xy 388.62 44.45)
		)
		(stroke
			(width 0)
			(type default)
		)
	)
	(wire
		(pts
			(xy 326.39 91.44) (xy 326.39 93.98)
		)
		(stroke
			(width 0)
			(type default)
		)
	)
	(wire
		(pts
			(xy 142.24 127) (xy 142.24 129.54)
		)
		(stroke
			(width 0)
			(type default)
		)
	)
	(wire
		(pts
			(xy 102.87 105.41) (xy 208.28 105.41)
		)
		(stroke
			(width 0)
			(type default)
		)
	)
	(wire
		(pts
			(xy 353.06 125.73) (xy 353.06 123.19)
		)
		(stroke
			(width 0)
			(type default)
		)
	)
	(wire
		(pts
			(xy 64.77 44.45) (xy 55.88 44.45)
		)
		(stroke
			(width 0)
			(type default)
		)
	)
	(wire
		(pts
			(xy 77.47 180.34) (xy 77.47 182.88)
		)
		(stroke
			(width 0)
			(type default)
		)
	)
	(wire
		(pts
			(xy 124.46 153.67) (xy 124.46 156.21)
		)
		(stroke
			(width 0)
			(type default)
		)
	)
	(wire
		(pts
			(xy 379.73 83.82) (xy 388.62 83.82)
		)
		(stroke
			(width 0)
			(type default)
		)
	)
	(wire
		(pts
			(xy 74.93 199.39) (xy 80.01 199.39)
		)
		(stroke
			(width 0)
			(type default)
		)
	)
	(wire
		(pts
			(xy 161.29 120.65) (xy 208.28 120.65)
		)
		(stroke
			(width 0)
			(type default)
		)
	)
	(wire
		(pts
			(xy 151.13 153.67) (xy 151.13 156.21)
		)
		(stroke
			(width 0)
			(type default)
		)
	)
	(wire
		(pts
			(xy 293.37 83.82) (xy 299.72 83.82)
		)
		(stroke
			(width 0)
			(type default)
		)
	)
	(wire
		(pts
			(xy 299.72 113.03) (xy 299.72 115.57)
		)
		(stroke
			(width 0)
			(type default)
		)
	)
	(wire
		(pts
			(xy 293.37 95.25) (xy 293.37 83.82)
		)
		(stroke
			(width 0)
			(type default)
		)
	)
	(wire
		(pts
			(xy 361.95 86.36) (xy 361.95 83.82)
		)
		(stroke
			(width 0)
			(type default)
		)
	)
	(wire
		(pts
			(xy 124.46 148.59) (xy 124.46 146.05)
		)
		(stroke
			(width 0)
			(type default)
		)
	)
	(wire
		(pts
			(xy 48.26 146.05) (xy 57.15 146.05)
		)
		(stroke
			(width 0)
			(type default)
		)
	)
	(wire
		(pts
			(xy 151.13 199.39) (xy 151.13 201.93)
		)
		(stroke
			(width 0)
			(type default)
		)
	)
	(wire
		(pts
			(xy 370.84 68.58) (xy 370.84 66.04)
		)
		(stroke
			(width 0)
			(type default)
		)
	)
	(wire
		(pts
			(xy 234.95 179.07) (xy 238.76 179.07)
		)
		(stroke
			(width 0)
			(type default)
		)
	)
	(wire
		(pts
			(xy 106.68 146.05) (xy 106.68 148.59)
		)
		(stroke
			(width 0)
			(type default)
		)
	)
	(wire
		(pts
			(xy 299.72 123.19) (xy 293.37 123.19)
		)
		(stroke
			(width 0)
			(type default)
		)
	)
	(wire
		(pts
			(xy 361.95 68.58) (xy 361.95 66.04)
		)
		(stroke
			(width 0)
			(type default)
		)
	)
	(wire
		(pts
			(xy 38.1 44.45) (xy 38.1 46.99)
		)
		(stroke
			(width 0)
			(type default)
		)
	)
	(wire
		(pts
			(xy 361.95 91.44) (xy 361.95 93.98)
		)
		(stroke
			(width 0)
			(type default)
		)
	)
	(wire
		(pts
			(xy 214.63 97.79) (xy 217.17 97.79)
		)
		(stroke
			(width 0)
			(type default)
		)
	)
	(wire
		(pts
			(xy 198.12 116.84) (xy 198.12 125.73)
		)
		(stroke
			(width 0)
			(type default)
		)
	)
	(wire
		(pts
			(xy 335.28 46.99) (xy 335.28 44.45)
		)
		(stroke
			(width 0)
			(type default)
		)
	)
	(wire
		(pts
			(xy 151.13 146.05) (xy 151.13 148.59)
		)
		(stroke
			(width 0)
			(type default)
		)
	)
	(wire
		(pts
			(xy 283.21 115.57) (xy 283.21 118.11)
		)
		(stroke
			(width 0)
			(type default)
		)
	)
	(wire
		(pts
			(xy 370.84 91.44) (xy 370.84 93.98)
		)
		(stroke
			(width 0)
			(type default)
		)
	)
	(wire
		(pts
			(xy 388.62 68.58) (xy 388.62 66.04)
		)
		(stroke
			(width 0)
			(type default)
		)
	)
	(wire
		(pts
			(xy 353.06 130.81) (xy 353.06 133.35)
		)
		(stroke
			(width 0)
			(type default)
		)
	)
	(wire
		(pts
			(xy 208.28 104.14) (xy 208.28 105.41)
		)
		(stroke
			(width 0)
			(type default)
		)
	)
	(wire
		(pts
			(xy 335.28 113.03) (xy 335.28 115.57)
		)
		(stroke
			(width 0)
			(type default)
		)
	)
	(wire
		(pts
			(xy 283.21 78.74) (xy 283.21 105.41)
		)
		(stroke
			(width 0)
			(type default)
		)
	)
	(wire
		(pts
			(xy 217.17 100.33) (xy 214.63 100.33)
		)
		(stroke
			(width 0)
			(type default)
		)
	)
	(wire
		(pts
			(xy 110.49 146.05) (xy 115.57 146.05)
		)
		(stroke
			(width 0)
			(type default)
		)
	)
	(wire
		(pts
			(xy 106.68 180.34) (xy 106.68 182.88)
		)
		(stroke
			(width 0)
			(type default)
		)
	)
	(wire
		(pts
			(xy 133.35 199.39) (xy 124.46 199.39)
		)
		(stroke
			(width 0)
			(type default)
		)
	)
	(wire
		(pts
			(xy 370.84 73.66) (xy 370.84 76.2)
		)
		(stroke
			(width 0)
			(type default)
		)
	)
	(wire
		(pts
			(xy 124.46 119.38) (xy 133.35 119.38)
		)
		(stroke
			(width 0)
			(type default)
		)
	)
	(wire
		(pts
			(xy 77.47 92.71) (xy 77.47 95.25)
		)
		(stroke
			(width 0)
			(type default)
		)
	)
	(wire
		(pts
			(xy 267.97 135.89) (xy 270.51 135.89)
		)
		(stroke
			(width 0)
			(type default)
		)
	)
	(wire
		(pts
			(xy 66.04 146.05) (xy 76.2 146.05)
		)
		(stroke
			(width 0)
			(type default)
		)
	)
	(wire
		(pts
			(xy 335.28 91.44) (xy 335.28 93.98)
		)
		(stroke
			(width 0)
			(type default)
		)
	)
	(wire
		(pts
			(xy 101.6 172.72) (xy 106.68 172.72)
		)
		(stroke
			(width 0)
			(type default)
		)
	)
	(wire
		(pts
			(xy 106.68 175.26) (xy 106.68 172.72)
		)
		(stroke
			(width 0)
			(type default)
		)
	)
	(wire
		(pts
			(xy 344.17 123.19) (xy 353.06 123.19)
		)
		(stroke
			(width 0)
			(type default)
		)
	)
	(wire
		(pts
			(xy 97.79 172.72) (xy 88.9 172.72)
		)
		(stroke
			(width 0)
			(type default)
		)
	)
	(wire
		(pts
			(xy 26.67 90.17) (xy 26.67 92.71)
		)
		(stroke
			(width 0)
			(type default)
		)
	)
	(wire
		(pts
			(xy 326.39 123.19) (xy 344.17 123.19)
		)
		(stroke
			(width 0)
			(type default)
		)
	)
	(wire
		(pts
			(xy 217.17 130.81) (xy 189.23 130.81)
		)
		(stroke
			(width 0)
			(type default)
		)
	)
	(wire
		(pts
			(xy 77.47 172.72) (xy 77.47 175.26)
		)
		(stroke
			(width 0)
			(type default)
		)
	)
	(wire
		(pts
			(xy 276.86 95.25) (xy 293.37 95.25)
		)
		(stroke
			(width 0)
			(type default)
		)
	)
	(wire
		(pts
			(xy 133.35 119.38) (xy 142.24 119.38)
		)
		(stroke
			(width 0)
			(type default)
		)
	)
	(wire
		(pts
			(xy 361.95 66.04) (xy 353.06 66.04)
		)
		(stroke
			(width 0)
			(type default)
		)
	)
	(wire
		(pts
			(xy 370.84 113.03) (xy 370.84 115.57)
		)
		(stroke
			(width 0)
			(type default)
		)
	)
	(wire
		(pts
			(xy 388.62 83.82) (xy 397.51 83.82)
		)
		(stroke
			(width 0)
			(type default)
		)
	)
	(wire
		(pts
			(xy 370.84 83.82) (xy 379.73 83.82)
		)
		(stroke
			(width 0)
			(type default)
		)
	)
	(wire
		(pts
			(xy 73.66 52.07) (xy 73.66 54.61)
		)
		(stroke
			(width 0)
			(type default)
		)
	)
	(wire
		(pts
			(xy 133.35 180.34) (xy 133.35 182.88)
		)
		(stroke
			(width 0)
			(type default)
		)
	)
	(wire
		(pts
			(xy 361.95 46.99) (xy 361.95 44.45)
		)
		(stroke
			(width 0)
			(type default)
		)
	)
	(wire
		(pts
			(xy 353.06 123.19) (xy 361.95 123.19)
		)
		(stroke
			(width 0)
			(type default)
		)
	)
	(wire
		(pts
			(xy 101.6 226.06) (xy 151.13 226.06)
		)
		(stroke
			(width 0)
			(type default)
		)
	)
	(wire
		(pts
			(xy 278.13 118.11) (xy 283.21 118.11)
		)
		(stroke
			(width 0)
			(type default)
		)
	)
	(wire
		(pts
			(xy 26.67 146.05) (xy 30.48 146.05)
		)
		(stroke
			(width 0)
			(type default)
		)
	)
	(wire
		(pts
			(xy 48.26 146.05) (xy 48.26 148.59)
		)
		(stroke
			(width 0)
			(type default)
		)
	)
	(wire
		(pts
			(xy 270.51 78.74) (xy 270.51 90.17)
		)
		(stroke
			(width 0)
			(type default)
		)
	)
	(wire
		(pts
			(xy 97.79 153.67) (xy 97.79 156.21)
		)
		(stroke
			(width 0)
			(type default)
		)
	)
	(wire
		(pts
			(xy 101.6 118.11) (xy 101.6 119.38)
		)
		(stroke
			(width 0)
			(type default)
		)
	)
	(wire
		(pts
			(xy 283.21 152.4) (xy 283.21 149.86)
		)
		(stroke
			(width 0)
			(type default)
		)
	)
	(wire
		(pts
			(xy 142.24 172.72) (xy 151.13 172.72)
		)
		(stroke
			(width 0)
			(type default)
		)
	)
	(wire
		(pts
			(xy 353.06 68.58) (xy 353.06 66.04)
		)
		(stroke
			(width 0)
			(type default)
		)
	)
	(wire
		(pts
			(xy 39.37 146.05) (xy 48.26 146.05)
		)
		(stroke
			(width 0)
			(type default)
		)
	)
	(wire
		(pts
			(xy 326.39 44.45) (xy 335.28 44.45)
		)
		(stroke
			(width 0)
			(type default)
		)
	)
	(wire
		(pts
			(xy 124.46 127) (xy 124.46 129.54)
		)
		(stroke
			(width 0)
			(type default)
		)
	)
	(wire
		(pts
			(xy 353.06 73.66) (xy 353.06 76.2)
		)
		(stroke
			(width 0)
			(type default)
		)
	)
	(wire
		(pts
			(xy 290.83 44.45) (xy 290.83 90.17)
		)
		(stroke
			(width 0)
			(type default)
		)
	)
	(wire
		(pts
			(xy 124.46 66.04) (xy 133.35 66.04)
		)
		(stroke
			(width 0)
			(type default)
		)
	)
	(wire
		(pts
			(xy 317.5 73.66) (xy 317.5 76.2)
		)
		(stroke
			(width 0)
			(type default)
		)
	)
	(wire
		(pts
			(xy 397.51 73.66) (xy 397.51 76.2)
		)
		(stroke
			(width 0)
			(type default)
		)
	)
	(wire
		(pts
			(xy 151.13 66.04) (xy 161.29 66.04)
		)
		(stroke
			(width 0)
			(type default)
		)
	)
	(wire
		(pts
			(xy 267.97 115.57) (xy 270.51 115.57)
		)
		(stroke
			(width 0)
			(type default)
		)
	)
	(wire
		(pts
			(xy 270.51 130.81) (xy 270.51 133.35)
		)
		(stroke
			(width 0)
			(type default)
		)
	)
	(wire
		(pts
			(xy 335.28 86.36) (xy 335.28 83.82)
		)
		(stroke
			(width 0)
			(type default)
		)
	)
	(wire
		(pts
			(xy 124.46 207.01) (xy 124.46 209.55)
		)
		(stroke
			(width 0)
			(type default)
		)
	)
	(wire
		(pts
			(xy 344.17 66.04) (xy 353.06 66.04)
		)
		(stroke
			(width 0)
			(type default)
		)
	)
	(wire
		(pts
			(xy 208.28 95.25) (xy 214.63 95.25)
		)
		(stroke
			(width 0)
			(type default)
		)
	)
	(wire
		(pts
			(xy 397.51 86.36) (xy 397.51 83.82)
		)
		(stroke
			(width 0)
			(type default)
		)
	)
	(wire
		(pts
			(xy 73.66 44.45) (xy 81.28 44.45)
		)
		(stroke
			(width 0)
			(type default)
		)
	)
	(wire
		(pts
			(xy 214.63 110.49) (xy 214.63 113.03)
		)
		(stroke
			(width 0)
			(type default)
		)
	)
	(wire
		(pts
			(xy 299.72 46.99) (xy 299.72 44.45)
		)
		(stroke
			(width 0)
			(type default)
		)
	)
	(wire
		(pts
			(xy 67.31 172.72) (xy 26.67 172.72)
		)
		(stroke
			(width 0)
			(type default)
		)
	)
	(wire
		(pts
			(xy 217.17 115.57) (xy 214.63 115.57)
		)
		(stroke
			(width 0)
			(type default)
		)
	)
	(wire
		(pts
			(xy 361.95 66.04) (xy 370.84 66.04)
		)
		(stroke
			(width 0)
			(type default)
		)
	)
	(wire
		(pts
			(xy 299.72 86.36) (xy 299.72 83.82)
		)
		(stroke
			(width 0)
			(type default)
		)
	)
	(wire
		(pts
			(xy 142.24 199.39) (xy 133.35 199.39)
		)
		(stroke
			(width 0)
			(type default)
		)
	)
	(wire
		(pts
			(xy 344.17 66.04) (xy 335.28 66.04)
		)
		(stroke
			(width 0)
			(type default)
		)
	)
	(wire
		(pts
			(xy 55.88 44.45) (xy 55.88 46.99)
		)
		(stroke
			(width 0)
			(type default)
		)
	)
	(wire
		(pts
			(xy 161.29 120.65) (xy 161.29 146.05)
		)
		(stroke
			(width 0)
			(type default)
		)
	)
	(wire
		(pts
			(xy 142.24 52.07) (xy 142.24 54.61)
		)
		(stroke
			(width 0)
			(type default)
		)
	)
	(wire
		(pts
			(xy 317.5 130.81) (xy 317.5 133.35)
		)
		(stroke
			(width 0)
			(type default)
		)
	)
	(wire
		(pts
			(xy 26.67 119.38) (xy 77.47 119.38)
		)
		(stroke
			(width 0)
			(type default)
		)
	)
	(wire
		(pts
			(xy 309.88 142.24) (xy 309.88 144.78)
		)
		(stroke
			(width 0)
			(type default)
		)
	)
	(wire
		(pts
			(xy 370.84 123.19) (xy 379.73 123.19)
		)
		(stroke
			(width 0)
			(type default)
		)
	)
	(wire
		(pts
			(xy 106.68 146.05) (xy 110.49 146.05)
		)
		(stroke
			(width 0)
			(type default)
		)
	)
	(wire
		(pts
			(xy 353.06 107.95) (xy 353.06 105.41)
		)
		(stroke
			(width 0)
			(type default)
		)
	)
	(wire
		(pts
			(xy 308.61 46.99) (xy 308.61 44.45)
		)
		(stroke
			(width 0)
			(type default)
		)
	)
	(wire
		(pts
			(xy 151.13 233.68) (xy 151.13 236.22)
		)
		(stroke
			(width 0)
			(type default)
		)
	)
	(wire
		(pts
			(xy 57.15 146.05) (xy 66.04 146.05)
		)
		(stroke
			(width 0)
			(type default)
		)
	)
	(wire
		(pts
			(xy 308.61 125.73) (xy 308.61 123.19)
		)
		(stroke
			(width 0)
			(type default)
		)
	)
	(wire
		(pts
			(xy 292.1 142.24) (xy 292.1 144.78)
		)
		(stroke
			(width 0)
			(type default)
		)
	)
	(wire
		(pts
			(xy 326.39 86.36) (xy 326.39 83.82)
		)
		(stroke
			(width 0)
			(type default)
		)
	)
	(wire
		(pts
			(xy 26.67 252.73) (xy 74.93 252.73)
		)
		(stroke
			(width 0)
			(type default)
		)
	)
	(wire
		(pts
			(xy 335.28 68.58) (xy 335.28 66.04)
		)
		(stroke
			(width 0)
			(type default)
		)
	)
	(wire
		(pts
			(xy 133.35 66.04) (xy 142.24 66.04)
		)
		(stroke
			(width 0)
			(type default)
		)
	)
	(wire
		(pts
			(xy 326.39 52.07) (xy 326.39 54.61)
		)
		(stroke
			(width 0)
			(type default)
		)
	)
	(wire
		(pts
			(xy 299.72 44.45) (xy 290.83 44.45)
		)
		(stroke
			(width 0)
			(type default)
		)
	)
	(wire
		(pts
			(xy 326.39 105.41) (xy 335.28 105.41)
		)
		(stroke
			(width 0)
			(type default)
		)
	)
	(wire
		(pts
			(xy 299.72 105.41) (xy 317.5 105.41)
		)
		(stroke
			(width 0)
			(type default)
		)
	)
	(wire
		(pts
			(xy 81.28 46.99) (xy 81.28 44.45)
		)
		(stroke
			(width 0)
			(type default)
		)
	)
	(wire
		(pts
			(xy 300.99 144.78) (xy 300.99 142.24)
		)
		(stroke
			(width 0)
			(type default)
		)
	)
	(wire
		(pts
			(xy 289.56 142.24) (xy 292.1 142.24)
		)
		(stroke
			(width 0)
			(type default)
		)
	)
	(wire
		(pts
			(xy 308.61 73.66) (xy 308.61 76.2)
		)
		(stroke
			(width 0)
			(type default)
		)
	)
	(wire
		(pts
			(xy 90.17 260.35) (xy 90.17 262.89)
		)
		(stroke
			(width 0)
			(type default)
		)
	)
	(wire
		(pts
			(xy 133.35 44.45) (xy 142.24 44.45)
		)
		(stroke
			(width 0)
			(type default)
		)
	)
	(wire
		(pts
			(xy 379.73 46.99) (xy 379.73 44.45)
		)
		(stroke
			(width 0)
			(type default)
		)
	)
	(wire
		(pts
			(xy 115.57 127) (xy 115.57 129.54)
		)
		(stroke
			(width 0)
			(type default)
		)
	)
	(wire
		(pts
			(xy 370.84 44.45) (xy 379.73 44.45)
		)
		(stroke
			(width 0)
			(type default)
		)
	)
	(wire
		(pts
			(xy 317.5 123.19) (xy 326.39 123.19)
		)
		(stroke
			(width 0)
			(type default)
		)
	)
	(wire
		(pts
			(xy 46.99 44.45) (xy 46.99 46.99)
		)
		(stroke
			(width 0)
			(type default)
		)
	)
	(wire
		(pts
			(xy 361.95 73.66) (xy 361.95 76.2)
		)
		(stroke
			(width 0)
			(type default)
		)
	)
	(wire
		(pts
			(xy 26.67 92.71) (xy 77.47 92.71)
		)
		(stroke
			(width 0)
			(type default)
		)
	)
	(wire
		(pts
			(xy 97.79 180.34) (xy 97.79 182.88)
		)
		(stroke
			(width 0)
			(type default)
		)
	)
	(wire
		(pts
			(xy 208.28 105.41) (xy 217.17 105.41)
		)
		(stroke
			(width 0)
			(type default)
		)
	)
	(wire
		(pts
			(xy 101.6 251.46) (xy 101.6 252.73)
		)
		(stroke
			(width 0)
			(type default)
		)
	)
	(wire
		(pts
			(xy 361.95 83.82) (xy 370.84 83.82)
		)
		(stroke
			(width 0)
			(type default)
		)
	)
	(wire
		(pts
			(xy 199.39 104.14) (xy 199.39 110.49)
		)
		(stroke
			(width 0)
			(type default)
		)
	)
	(wire
		(pts
			(xy 335.28 52.07) (xy 335.28 54.61)
		)
		(stroke
			(width 0)
			(type default)
		)
	)
	(wire
		(pts
			(xy 133.35 153.67) (xy 133.35 156.21)
		)
		(stroke
			(width 0)
			(type default)
		)
	)
	(wire
		(pts
			(xy 101.6 199.39) (xy 90.17 199.39)
		)
		(stroke
			(width 0)
			(type default)
		)
	)
	(wire
		(pts
			(xy 379.73 91.44) (xy 379.73 93.98)
		)
		(stroke
			(width 0)
			(type default)
		)
	)
	(wire
		(pts
			(xy 142.24 201.93) (xy 142.24 199.39)
		)
		(stroke
			(width 0)
			(type default)
		)
	)
	(wire
		(pts
			(xy 90.17 255.27) (xy 90.17 252.73)
		)
		(stroke
			(width 0)
			(type default)
		)
	)
	(wire
		(pts
			(xy 90.17 228.6) (xy 90.17 226.06)
		)
		(stroke
			(width 0)
			(type default)
		)
	)
	(wire
		(pts
			(xy 55.88 52.07) (xy 55.88 54.61)
		)
		(stroke
			(width 0)
			(type default)
		)
	)
	(wire
		(pts
			(xy 270.51 110.49) (xy 270.51 107.95)
		)
		(stroke
			(width 0)
			(type default)
		)
	)
	(wire
		(pts
			(xy 67.31 175.26) (xy 67.31 172.72)
		)
		(stroke
			(width 0)
			(type default)
		)
	)
	(wire
		(pts
			(xy 102.87 105.41) (xy 102.87 92.71)
		)
		(stroke
			(width 0)
			(type default)
		)
	)
	(wire
		(pts
			(xy 267.97 100.33) (xy 270.51 100.33)
		)
		(stroke
			(width 0)
			(type default)
		)
	)
	(wire
		(pts
			(xy 74.93 252.73) (xy 80.01 252.73)
		)
		(stroke
			(width 0)
			(type default)
		)
	)
	(wire
		(pts
			(xy 379.73 52.07) (xy 379.73 54.61)
		)
		(stroke
			(width 0)
			(type default)
		)
	)
	(wire
		(pts
			(xy 267.97 138.43) (xy 270.51 138.43)
		)
		(stroke
			(width 0)
			(type default)
		)
	)
	(wire
		(pts
			(xy 106.68 172.72) (xy 124.46 172.72)
		)
		(stroke
			(width 0)
			(type default)
		)
	)
	(wire
		(pts
			(xy 124.46 201.93) (xy 124.46 199.39)
		)
		(stroke
			(width 0)
			(type default)
		)
	)
	(wire
		(pts
			(xy 198.12 125.73) (xy 217.17 125.73)
		)
		(stroke
			(width 0)
			(type default)
		)
	)
	(wire
		(pts
			(xy 353.06 46.99) (xy 353.06 44.45)
		)
		(stroke
			(width 0)
			(type default)
		)
	)
	(wire
		(pts
			(xy 299.72 68.58) (xy 299.72 66.04)
		)
		(stroke
			(width 0)
			(type default)
		)
	)
	(wire
		(pts
			(xy 344.17 125.73) (xy 344.17 123.19)
		)
		(stroke
			(width 0)
			(type default)
		)
	)
	(wire
		(pts
			(xy 166.37 130.81) (xy 189.23 130.81)
		)
		(stroke
			(width 0)
			(type default)
		)
	)
	(wire
		(pts
			(xy 90.17 52.07) (xy 90.17 54.61)
		)
		(stroke
			(width 0)
			(type default)
		)
	)
	(wire
		(pts
			(xy 270.51 97.79) (xy 270.51 95.25)
		)
		(stroke
			(width 0)
			(type default)
		)
	)
	(wire
		(pts
			(xy 124.46 68.58) (xy 124.46 66.04)
		)
		(stroke
			(width 0)
			(type default)
		)
	)
	(wire
		(pts
			(xy 361.95 105.41) (xy 361.95 107.95)
		)
		(stroke
			(width 0)
			(type default)
		)
	)
	(wire
		(pts
			(xy 388.62 73.66) (xy 388.62 76.2)
		)
		(stroke
			(width 0)
			(type default)
		)
	)
	(wire
		(pts
			(xy 267.97 130.81) (xy 270.51 130.81)
		)
		(stroke
			(width 0)
			(type default)
		)
	)
	(wire
		(pts
			(xy 97.79 73.66) (xy 97.79 76.2)
		)
		(stroke
			(width 0)
			(type default)
		)
	)
	(wire
		(pts
			(xy 308.61 86.36) (xy 308.61 83.82)
		)
		(stroke
			(width 0)
			(type default)
		)
	)
	(wire
		(pts
			(xy 38.1 52.07) (xy 38.1 54.61)
		)
		(stroke
			(width 0)
			(type default)
		)
	)
	(wire
		(pts
			(xy 317.5 44.45) (xy 326.39 44.45)
		)
		(stroke
			(width 0)
			(type default)
		)
	)
	(wire
		(pts
			(xy 66.04 153.67) (xy 66.04 156.21)
		)
		(stroke
			(width 0)
			(type default)
		)
	)
	(wire
		(pts
			(xy 115.57 52.07) (xy 115.57 54.61)
		)
		(stroke
			(width 0)
			(type default)
		)
	)
	(wire
		(pts
			(xy 88.9 73.66) (xy 88.9 76.2)
		)
		(stroke
			(width 0)
			(type default)
		)
	)
	(wire
		(pts
			(xy 101.6 224.79) (xy 101.6 226.06)
		)
		(stroke
			(width 0)
			(type default)
		)
	)
	(wire
		(pts
			(xy 124.46 180.34) (xy 124.46 182.88)
		)
		(stroke
			(width 0)
			(type default)
		)
	)
	(wire
		(pts
			(xy 77.47 127) (xy 77.47 129.54)
		)
		(stroke
			(width 0)
			(type default)
		)
	)
	(wire
		(pts
			(xy 335.28 83.82) (xy 353.06 83.82)
		)
		(stroke
			(width 0)
			(type default)
		)
	)
	(wire
		(pts
			(xy 74.93 207.01) (xy 74.93 209.55)
		)
		(stroke
			(width 0)
			(type default)
		)
	)
	(wire
		(pts
			(xy 133.35 175.26) (xy 133.35 172.72)
		)
		(stroke
			(width 0)
			(type default)
		)
	)
	(wire
		(pts
			(xy 99.06 52.07) (xy 99.06 54.61)
		)
		(stroke
			(width 0)
			(type default)
		)
	)
	(wire
		(pts
			(xy 151.13 207.01) (xy 151.13 209.55)
		)
		(stroke
			(width 0)
			(type default)
		)
	)
	(wire
		(pts
			(xy 299.72 73.66) (xy 299.72 76.2)
		)
		(stroke
			(width 0)
			(type default)
		)
	)
	(wire
		(pts
			(xy 97.79 175.26) (xy 97.79 172.72)
		)
		(stroke
			(width 0)
			(type default)
		)
	)
	(wire
		(pts
			(xy 308.61 68.58) (xy 308.61 66.04)
		)
		(stroke
			(width 0)
			(type default)
		)
	)
	(wire
		(pts
			(xy 309.88 152.4) (xy 309.88 149.86)
		)
		(stroke
			(width 0)
			(type default)
		)
	)
	(wire
		(pts
			(xy 133.35 52.07) (xy 133.35 54.61)
		)
		(stroke
			(width 0)
			(type default)
		)
	)
	(wire
		(pts
			(xy 101.6 252.73) (xy 90.17 252.73)
		)
		(stroke
			(width 0)
			(type default)
		)
	)
	(wire
		(pts
			(xy 142.24 207.01) (xy 142.24 209.55)
		)
		(stroke
			(width 0)
			(type default)
		)
	)
	(wire
		(pts
			(xy 214.63 113.03) (xy 217.17 113.03)
		)
		(stroke
			(width 0)
			(type default)
		)
	)
	(wire
		(pts
			(xy 124.46 52.07) (xy 124.46 54.61)
		)
		(stroke
			(width 0)
			(type default)
		)
	)
	(wire
		(pts
			(xy 151.13 73.66) (xy 151.13 76.2)
		)
		(stroke
			(width 0)
			(type default)
		)
	)
	(wire
		(pts
			(xy 168.91 135.89) (xy 168.91 226.06)
		)
		(stroke
			(width 0)
			(type default)
		)
	)
	(wire
		(pts
			(xy 77.47 119.38) (xy 81.28 119.38)
		)
		(stroke
			(width 0)
			(type default)
		)
	)
	(wire
		(pts
			(xy 370.84 46.99) (xy 370.84 44.45)
		)
		(stroke
			(width 0)
			(type default)
		)
	)
	(wire
		(pts
			(xy 160.02 110.49) (xy 199.39 110.49)
		)
		(stroke
			(width 0)
			(type default)
		)
	)
	(wire
		(pts
			(xy 317.5 86.36) (xy 317.5 83.82)
		)
		(stroke
			(width 0)
			(type default)
		)
	)
	(symbol
		(lib_id "antmicropower:GND")
		(at 48.26 156.21 0)
		(unit 1)
		(exclude_from_sim no)
		(in_bom yes)
		(on_board yes)
		(dnp no)
		(property "Reference" "#PWR0499"
			(at 57.15 158.75 0)
			(effects
				(font
					(size 1.27 1.27)
					(thickness 0.15)
				)
				(justify left bottom)
				(hide yes)
			)
		)
		(property "Value" "GND"
			(at 48.26 160.02 0)
			(effects
				(font
					(size 1.27 1.27)
					(thickness 0.15)
				)
			)
		)
		(property "Footprint" ""
			(at 57.15 163.83 0)
			(effects
				(font
					(size 1.27 1.27)
					(thickness 0.15)
				)
				(justify left bottom)
				(hide yes)
			)
		)
		(property "Datasheet" ""
			(at 57.15 168.91 0)
			(effects
				(font
					(size 1.27 1.27)
					(thickness 0.15)
				)
				(justify left bottom)
				(hide yes)
			)
		)
		(property "Description" ""
			(at 48.26 156.21 0)
			(effects
				(font
					(size 1.27 1.27)
				)
				(hide yes)
			)
		)
		(property "Author" "Antmicro"
			(at 57.15 163.83 0)
			(effects
				(font
					(size 1.27 1.27)
					(thickness 0.15)
				)
				(justify left bottom)
				(hide yes)
			)
		)
		(property "License" "Apache-2.0"
			(at 57.15 166.37 0)
			(effects
				(font
					(size 1.27 1.27)
					(thickness 0.15)
				)
				(justify left bottom)
				(hide yes)
			)
		)
		(pin "1"
		)
		(instances
			(project "thunderbolt-to-10gbe-adapter"
				(path ""
					(reference "#PWR0499")
					(unit 1)
				)
			)
		)
	)
	(symbol
		(lib_id "antmicropower:GND")
		(at 74.93 236.22 0)
		(unit 1)
		(exclude_from_sim no)
		(in_bom yes)
		(on_board yes)
		(dnp no)
		(property "Reference" "#PWR0230"
			(at 83.82 238.76 0)
			(effects
				(font
					(size 1.27 1.27)
					(thickness 0.15)
				)
				(justify left bottom)
				(hide yes)
			)
		)
		(property "Value" "GND"
			(at 74.93 240.03 0)
			(effects
				(font
					(size 1.27 1.27)
					(thickness 0.15)
				)
			)
		)
		(property "Footprint" ""
			(at 83.82 243.84 0)
			(effects
				(font
					(size 1.27 1.27)
					(thickness 0.15)
				)
				(justify left bottom)
				(hide yes)
			)
		)
		(property "Datasheet" ""
			(at 83.82 248.92 0)
			(effects
				(font
					(size 1.27 1.27)
					(thickness 0.15)
				)
				(justify left bottom)
				(hide yes)
			)
		)
		(property "Description" ""
			(at 74.93 236.22 0)
			(effects
				(font
					(size 1.27 1.27)
				)
				(hide yes)
			)
		)
		(property "Author" "Antmicro"
			(at 83.82 243.84 0)
			(effects
				(font
					(size 1.27 1.27)
					(thickness 0.15)
				)
				(justify left bottom)
				(hide yes)
			)
		)
		(property "License" "Apache-2.0"
			(at 83.82 246.38 0)
			(effects
				(font
					(size 1.27 1.27)
					(thickness 0.15)
				)
				(justify left bottom)
				(hide yes)
			)
		)
		(pin "1"
		)
		(instances
			(project "OCuLink to 10GbE adapter"
				(path ""
					(reference "#PWR0239")
					(unit 1)
				)
			)
			(project "thunderbolt-to-10gbe-adapter"
				(path ""
					(reference "#PWR0230")
					(unit 1)
				)
			)
		)
	)
	(symbol
		(lib_id "antmicropower:GND")
		(at 30.48 156.21 0)
		(unit 1)
		(exclude_from_sim no)
		(in_bom yes)
		(on_board yes)
		(dnp no)
		(property "Reference" "#PWR0501"
			(at 39.37 158.75 0)
			(effects
				(font
					(size 1.27 1.27)
					(thickness 0.15)
				)
				(justify left bottom)
				(hide yes)
			)
		)
		(property "Value" "GND"
			(at 30.48 160.02 0)
			(effects
				(font
					(size 1.27 1.27)
					(thickness 0.15)
				)
			)
		)
		(property "Footprint" ""
			(at 39.37 163.83 0)
			(effects
				(font
					(size 1.27 1.27)
					(thickness 0.15)
				)
				(justify left bottom)
				(hide yes)
			)
		)
		(property "Datasheet" ""
			(at 39.37 168.91 0)
			(effects
				(font
					(size 1.27 1.27)
					(thickness 0.15)
				)
				(justify left bottom)
				(hide yes)
			)
		)
		(property "Description" ""
			(at 30.48 156.21 0)
			(effects
				(font
					(size 1.27 1.27)
				)
				(hide yes)
			)
		)
		(property "Author" "Antmicro"
			(at 39.37 163.83 0)
			(effects
				(font
					(size 1.27 1.27)
					(thickness 0.15)
				)
				(justify left bottom)
				(hide yes)
			)
		)
		(property "License" "Apache-2.0"
			(at 39.37 166.37 0)
			(effects
				(font
					(size 1.27 1.27)
					(thickness 0.15)
				)
				(justify left bottom)
				(hide yes)
			)
		)
		(pin "1"
		)
		(instances
			(project "thunderbolt-to-10gbe-adapter"
				(path ""
					(reference "#PWR0501")
					(unit 1)
				)
			)
		)
	)
	(symbol
		(lib_id "antmicroFixedInductors:L_1u_10A_Bourns-SRP4021HMT")
		(at 273.05 118.11 0)
		(unit 1)
		(exclude_from_sim no)
		(in_bom yes)
		(on_board yes)
		(dnp no)
		(fields_autoplaced yes)
		(property "Reference" "L11"
			(at 275.59 113.03 0)
			(effects
				(font
					(size 1.27 1.27)
					(thickness 0.15)
				)
			)
		)
		(property "Value" "L_1u_10A_Bourns-SRP4021HMT"
			(at 288.29 128.27 0)
			(effects
				(font
					(size 1.27 1.27)
					(thickness 0.15)
				)
				(justify left bottom)
				(hide yes)
			)
		)
		(property "Footprint" "antmicro-footprints:L_Bourns-SRP4021HMT"
			(at 288.29 130.81 0)
			(effects
				(font
					(size 1.27 1.27)
					(thickness 0.15)
				)
				(justify left bottom)
				(hide yes)
			)
		)
		(property "Datasheet" "https://www.mouser.com/datasheet/2/54/Bourns_04_01_2025_SRP4021HMT_Datasheet-3580094.pdf"
			(at 288.29 133.35 0)
			(effects
				(font
					(size 1.27 1.27)
					(thickness 0.15)
				)
				(justify left bottom)
				(hide yes)
			)
		)
		(property "Description" "Power Inductors - SMD Ind,4.1x4.2x1.9mm,1uH+/-20%,10A, Shielded"
			(at 288.29 135.89 0)
			(effects
				(font
					(size 1.27 1.27)
					(thickness 0.15)
				)
				(justify left bottom)
				(hide yes)
			)
		)
		(property "Val" "1u/10A"
			(at 275.59 115.57 0)
			(effects
				(font
					(size 1.27 1.27)
					(thickness 0.15)
				)
			)
		)
		(property "Manufacturer" "Bourns"
			(at 288.29 138.43 0)
			(effects
				(font
					(size 1.27 1.27)
					(thickness 0.15)
				)
				(justify left bottom)
				(hide yes)
			)
		)
		(property "MPN" "SRP4021HMT-1R0M"
			(at 288.29 140.97 0)
			(effects
				(font
					(size 1.27 1.27)
					(thickness 0.15)
				)
				(justify left bottom)
				(hide yes)
			)
		)
		(property "ISat" ""
			(at 287.02 134.62 0)
			(effects
				(font
					(size 1.27 1.27)
				)
				(justify left)
				(hide yes)
			)
		)
		(property "Isat" "8A"
			(at 288.29 143.51 0)
			(effects
				(font
					(size 1.27 1.27)
					(thickness 0.15)
				)
				(justify left bottom)
				(hide yes)
			)
		)
		(property "IMax" ""
			(at 287.02 138.43 0)
			(effects
				(font
					(size 1.27 1.27)
					(thickness 0.15)
				)
				(justify left bottom)
				(hide yes)
			)
		)
		(property "Imax" "10A"
			(at 288.29 146.05 0)
			(effects
				(font
					(size 1.27 1.27)
					(thickness 0.15)
				)
				(justify left bottom)
				(hide yes)
			)
		)
		(property "Size" "4.2x4.1"
			(at 288.29 148.59 0)
			(effects
				(font
					(size 1.27 1.27)
					(thickness 0.15)
				)
				(justify left bottom)
				(hide yes)
			)
		)
		(property "Author" "Antmicro"
			(at 288.29 151.13 0)
			(effects
				(font
					(size 1.27 1.27)
					(thickness 0.15)
				)
				(justify left bottom)
				(hide yes)
			)
		)
		(property "License" "Apache-2.0"
			(at 288.29 153.67 0)
			(effects
				(font
					(size 1.27 1.27)
					(thickness 0.15)
				)
				(justify left bottom)
				(hide yes)
			)
		)
		(pin "1"
		)
		(pin "2"
		)
		(instances
			(project "OCuLink to 10GbE adapter"
				(path ""
					(reference "L8")
					(unit 1)
				)
			)
			(project "thunderbolt-to-10gbe-adapter"
				(path ""
					(reference "L11")
					(unit 1)
				)
			)
		)
	)
	(symbol
		(lib_id "antmicroFerriteBeadsandChips:FB_33Z_3A_Murata-BLM18PG_0603")
		(at 81.28 172.72 0)
		(unit 1)
		(exclude_from_sim no)
		(in_bom yes)
		(on_board yes)
		(dnp no)
		(fields_autoplaced yes)
		(property "Reference" "FB7"
			(at 83.7819 166.37 0)
			(effects
				(font
					(size 1.27 1.27)
					(thickness 0.15)
				)
			)
		)
		(property "Value" "FB_33Z_3A_Murata-BLM18PG_0603"
			(at 95.25 175.26 0)
			(effects
				(font
					(size 1.27 1.27)
					(thickness 0.15)
				)
				(justify left bottom)
				(hide yes)
			)
		)
		(property "Footprint" "antmicro-footprints:FB_0603_1608Metric"
			(at 95.25 180.34 0)
			(effects
				(font
					(size 1.27 1.27)
					(thickness 0.15)
				)
				(justify left bottom)
				(hide yes)
			)
		)
		(property "Datasheet" "https://www.murata.com/products/productdata/8796737273886/QNFA9101.pdf?1649080818000"
			(at 95.25 182.88 0)
			(effects
				(font
					(size 1.27 1.27)
					(thickness 0.15)
				)
				(justify left bottom)
				(hide yes)
			)
		)
		(property "Description" "Ferrite Bead, 0603 [1608 Metric], 33 ohm, 3 A, BLM18PG, 0.025 ohm, ± 25%, DC power line"
			(at 81.28 172.72 0)
			(effects
				(font
					(size 1.27 1.27)
				)
				(hide yes)
			)
		)
		(property "Val" "33Z/3A"
			(at 83.7819 168.91 0)
			(effects
				(font
					(size 1.27 1.27)
				)
			)
		)
		(property "MPN" "BLM18PG330SH1D"
			(at 95.25 185.42 0)
			(effects
				(font
					(size 1.27 1.27)
					(thickness 0.15)
				)
				(justify left bottom)
				(hide yes)
			)
		)
		(property "Manufacturer" "Murata"
			(at 95.25 187.96 0)
			(effects
				(font
					(size 1.27 1.27)
					(thickness 0.15)
				)
				(justify left bottom)
				(hide yes)
			)
		)
		(property "Current" ""
			(at 101.6 195.58 0)
			(effects
				(font
					(size 1.27 1.27)
					(thickness 0.15)
				)
				(justify left bottom)
				(hide yes)
			)
		)
		(property "Author" "Antmicro"
			(at 95.25 190.5 0)
			(effects
				(font
					(size 1.27 1.27)
					(thickness 0.15)
				)
				(justify left bottom)
				(hide yes)
			)
		)
		(property "License" "Apache-2.0"
			(at 95.25 193.04 0)
			(effects
				(font
					(size 1.27 1.27)
					(thickness 0.15)
				)
				(justify left bottom)
				(hide yes)
			)
		)
		(pin "2"
		)
		(pin "1"
		)
		(instances
			(project "OCuLink to 10GbE adapter"
				(path ""
					(reference "FB6")
					(unit 1)
				)
			)
			(project "thunderbolt-to-10gbe-adapter"
				(path ""
					(reference "FB7")
					(unit 1)
				)
			)
		)
	)
	(symbol
		(lib_id "antmicropower:+1V8")
		(at 208.28 87.63 0)
		(unit 1)
		(exclude_from_sim no)
		(in_bom yes)
		(on_board yes)
		(dnp no)
		(property "Reference" "#PWR0287"
			(at 223.52 90.17 0)
			(effects
				(font
					(size 1.27 1.27)
					(thickness 0.15)
				)
				(justify left bottom)
				(hide yes)
			)
		)
		(property "Value" "+1V88"
			(at 208.28 83.82 0)
			(effects
				(font
					(size 1.27 1.27)
					(thickness 0.15)
				)
			)
		)
		(property "Footprint" ""
			(at 223.52 95.25 0)
			(effects
				(font
					(size 1.27 1.27)
					(thickness 0.15)
				)
				(justify left bottom)
				(hide yes)
			)
		)
		(property "Datasheet" ""
			(at 223.52 97.79 0)
			(effects
				(font
					(size 1.27 1.27)
					(thickness 0.15)
				)
				(justify left bottom)
				(hide yes)
			)
		)
		(property "Description" ""
			(at 208.28 87.63 0)
			(effects
				(font
					(size 1.27 1.27)
				)
				(hide yes)
			)
		)
		(property "Author" "Antmicro"
			(at 223.52 92.71 0)
			(effects
				(font
					(size 1.27 1.27)
					(thickness 0.15)
				)
				(justify left bottom)
				(hide yes)
			)
		)
		(property "License" "Apache-2.0"
			(at 223.52 95.25 0)
			(effects
				(font
					(size 1.27 1.27)
					(thickness 0.15)
				)
				(justify left bottom)
				(hide yes)
			)
		)
		(pin "1"
		)
		(instances
			(project "OCuLink to 10GbE adapter"
				(path ""
					(reference "#PWR0158")
					(unit 1)
				)
			)
			(project "thunderbolt-to-10gbe-adapter"
				(path ""
					(reference "#PWR0287")
					(unit 1)
				)
			)
		)
	)
	(symbol
		(lib_id "antmicropower:GND")
		(at 97.79 156.21 0)
		(unit 1)
		(exclude_from_sim no)
		(in_bom yes)
		(on_board yes)
		(dnp no)
		(property "Reference" "#PWR0241"
			(at 106.68 158.75 0)
			(effects
				(font
					(size 1.27 1.27)
					(thickness 0.15)
				)
				(justify left bottom)
				(hide yes)
			)
		)
		(property "Value" "GND"
			(at 97.79 160.02 0)
			(effects
				(font
					(size 1.27 1.27)
					(thickness 0.15)
				)
			)
		)
		(property "Footprint" ""
			(at 106.68 163.83 0)
			(effects
				(font
					(size 1.27 1.27)
					(thickness 0.15)
				)
				(justify left bottom)
				(hide yes)
			)
		)
		(property "Datasheet" ""
			(at 106.68 168.91 0)
			(effects
				(font
					(size 1.27 1.27)
					(thickness 0.15)
				)
				(justify left bottom)
				(hide yes)
			)
		)
		(property "Description" ""
			(at 97.79 156.21 0)
			(effects
				(font
					(size 1.27 1.27)
				)
				(hide yes)
			)
		)
		(property "Author" "Antmicro"
			(at 106.68 163.83 0)
			(effects
				(font
					(size 1.27 1.27)
					(thickness 0.15)
				)
				(justify left bottom)
				(hide yes)
			)
		)
		(property "License" "Apache-2.0"
			(at 106.68 166.37 0)
			(effects
				(font
					(size 1.27 1.27)
					(thickness 0.15)
				)
				(justify left bottom)
				(hide yes)
			)
		)
		(pin "1"
		)
		(instances
			(project "OCuLink to 10GbE adapter"
				(path ""
					(reference "#PWR0214")
					(unit 1)
				)
			)
			(project "thunderbolt-to-10gbe-adapter"
				(path ""
					(reference "#PWR0241")
					(unit 1)
				)
			)
		)
	)
	(symbol
		(lib_id "antmicroCapacitors0402:C_1u_25V_0402")
		(at 151.13 73.66 90)
		(unit 1)
		(exclude_from_sim no)
		(in_bom yes)
		(on_board yes)
		(dnp no)
		(property "Reference" "C203"
			(at 153.162 69.85 90)
			(effects
				(font
					(size 1.27 1.27)
					(thickness 0.15)
				)
				(justify right)
			)
		)
		(property "Value" "C_1u_25V_0402"
			(at 161.29 53.34 0)
			(effects
				(font
					(size 1.27 1.27)
					(thickness 0.15)
				)
				(justify left bottom)
				(hide yes)
			)
		)
		(property "Footprint" "antmicro-footprints:C_0402_1005Metric"
			(at 163.83 53.34 0)
			(effects
				(font
					(size 1.27 1.27)
					(thickness 0.15)
				)
				(justify left bottom)
				(hide yes)
			)
		)
		(property "Datasheet" "https://www.murata.com/products/productdetail?partno=GRM155R61E105KE11%23"
			(at 166.37 53.34 0)
			(effects
				(font
					(size 1.27 1.27)
					(thickness 0.15)
				)
				(justify left bottom)
				(hide yes)
			)
		)
		(property "Description" "SMD Multilayer Ceramic Capacitor, 1 µF, 25 V, 0402 [1005 Metric], ± 10%, X5R, GRM Series"
			(at 151.13 73.66 0)
			(effects
				(font
					(size 1.27 1.27)
				)
				(hide yes)
			)
		)
		(property "MPN" "GRM155R61E105KE11J"
			(at 168.91 53.34 0)
			(effects
				(font
					(size 1.27 1.27)
					(thickness 0.15)
				)
				(justify left bottom)
				(hide yes)
			)
		)
		(property "Manufacturer" "Murata"
			(at 171.45 53.34 0)
			(effects
				(font
					(size 1.27 1.27)
					(thickness 0.15)
				)
				(justify left bottom)
				(hide yes)
			)
		)
		(property "License" "Apache-2.0"
			(at 173.99 53.34 0)
			(effects
				(font
					(size 1.27 1.27)
					(thickness 0.15)
				)
				(justify left bottom)
				(hide yes)
			)
		)
		(property "Author" "Antmicro"
			(at 176.53 53.34 0)
			(effects
				(font
					(size 1.27 1.27)
					(thickness 0.15)
				)
				(justify left bottom)
				(hide yes)
			)
		)
		(property "Val" "1u"
			(at 153.162 72.39 90)
			(effects
				(font
					(size 1.27 1.27)
					(thickness 0.15)
				)
				(justify right)
			)
		)
		(property "Voltage" "25V"
			(at 179.07 53.34 0)
			(effects
				(font
					(size 1.27 1.27)
				)
				(justify left bottom)
				(hide yes)
			)
		)
		(property "Dielectric" "X5R"
			(at 181.61 53.34 0)
			(effects
				(font
					(size 1.27 1.27)
				)
				(justify left bottom)
				(hide yes)
			)
		)
		(pin "2"
		)
		(pin "1"
		)
		(instances
			(project "OCuLink to 10GbE adapter"
				(path ""
					(reference "C104")
					(unit 1)
				)
			)
			(project "thunderbolt-to-10gbe-adapter"
				(path ""
					(reference "C203")
					(unit 1)
				)
			)
		)
	)
	(symbol
		(lib_id "antmicroCapacitorspol:C_Pol_100u_6V_KEMET-T490-A")
		(at 39.37 148.59 270)
		(unit 1)
		(exclude_from_sim no)
		(in_bom yes)
		(on_board yes)
		(dnp no)
		(fields_autoplaced yes)
		(property "Reference" "C328"
			(at 41.91 149.3266 90)
			(effects
				(font
					(size 1.27 1.27)
					(thickness 0.15)
				)
				(justify left)
			)
		)
		(property "Value" "C_Pol_100u_6V_KEMET-T490-A"
			(at 36.83 162.56 0)
			(effects
				(font
					(size 1.27 1.27)
					(thickness 0.15)
				)
				(justify left bottom)
				(hide yes)
			)
		)
		(property "Footprint" "antmicro-footprints:C_Pol_EIA-A"
			(at 31.75 162.56 0)
			(effects
				(font
					(size 1.27 1.27)
					(thickness 0.15)
				)
				(justify left bottom)
				(hide yes)
			)
		)
		(property "Datasheet" "https://www.kemet.com/en/us/capacitors/product/T490A107M006ATE800.html"
			(at 29.21 162.56 0)
			(effects
				(font
					(size 1.27 1.27)
					(thickness 0.15)
				)
				(justify left bottom)
				(hide yes)
			)
		)
		(property "Description" "Surface Mount Tantalum Capacitor,  Solid SMD 6V 100uF 1206 20% ESR=800mOhms"
			(at 13.97 162.56 0)
			(effects
				(font
					(size 1.27 1.27)
				)
				(justify left bottom)
				(hide yes)
			)
		)
		(property "Val" "100u"
			(at 41.91 151.8666 90)
			(effects
				(font
					(size 1.27 1.27)
					(thickness 0.15)
				)
				(justify left)
			)
		)
		(property "MPN" "T490A107M006ATE800"
			(at 26.67 162.56 0)
			(effects
				(font
					(size 1.27 1.27)
					(thickness 0.15)
				)
				(justify left bottom)
				(hide yes)
			)
		)
		(property "Manufacturer" "KEMET"
			(at 24.13 162.56 0)
			(effects
				(font
					(size 1.27 1.27)
					(thickness 0.15)
				)
				(justify left bottom)
				(hide yes)
			)
		)
		(property "License" "Apache-2.0"
			(at 21.59 162.56 0)
			(effects
				(font
					(size 1.27 1.27)
					(thickness 0.15)
				)
				(justify left bottom)
				(hide yes)
			)
		)
		(property "Author" "Antmicro"
			(at 19.05 162.56 0)
			(effects
				(font
					(size 1.27 1.27)
					(thickness 0.15)
				)
				(justify left bottom)
				(hide yes)
			)
		)
		(property "Voltage" "6V"
			(at 16.51 162.56 0)
			(effects
				(font
					(size 1.27 1.27)
				)
				(justify left bottom)
				(hide yes)
			)
		)
		(property "Dielectric" "template_dielectric"
			(at 13.97 162.56 0)
			(effects
				(font
					(size 1.27 1.27)
				)
				(justify left bottom)
				(hide yes)
			)
		)
		(pin "2"
		)
		(pin "1"
		)
		(instances
			(project "thunderbolt-to-10gbe-adapter"
				(path ""
					(reference "C328")
					(unit 1)
				)
			)
		)
	)
	(symbol
		(lib_id "antmicropower:GND")
		(at 353.06 93.98 0)
		(unit 1)
		(exclude_from_sim no)
		(in_bom yes)
		(on_board yes)
		(dnp no)
		(property "Reference" "#PWR0328"
			(at 361.95 96.52 0)
			(effects
				(font
					(size 1.27 1.27)
					(thickness 0.15)
				)
				(justify left bottom)
				(hide yes)
			)
		)
		(property "Value" "GND"
			(at 353.06 97.79 0)
			(effects
				(font
					(size 1.27 1.27)
					(thickness 0.15)
				)
			)
		)
		(property "Footprint" ""
			(at 361.95 101.6 0)
			(effects
				(font
					(size 1.27 1.27)
					(thickness 0.15)
				)
				(justify left bottom)
				(hide yes)
			)
		)
		(property "Datasheet" ""
			(at 361.95 106.68 0)
			(effects
				(font
					(size 1.27 1.27)
					(thickness 0.15)
				)
				(justify left bottom)
				(hide yes)
			)
		)
		(property "Description" ""
			(at 353.06 93.98 0)
			(effects
				(font
					(size 1.27 1.27)
				)
				(hide yes)
			)
		)
		(property "Author" "Antmicro"
			(at 361.95 101.6 0)
			(effects
				(font
					(size 1.27 1.27)
					(thickness 0.15)
				)
				(justify left bottom)
				(hide yes)
			)
		)
		(property "License" "Apache-2.0"
			(at 361.95 104.14 0)
			(effects
				(font
					(size 1.27 1.27)
					(thickness 0.15)
				)
				(justify left bottom)
				(hide yes)
			)
		)
		(pin "1"
		)
		(instances
			(project "OCuLink to 10GbE adapter"
				(path ""
					(reference "#PWR0169")
					(unit 1)
				)
			)
			(project "thunderbolt-to-10gbe-adapter"
				(path ""
					(reference "#PWR0328")
					(unit 1)
				)
			)
		)
	)
	(symbol
		(lib_id "antmicroCapacitors0402:C_1u_25V_0402")
		(at 326.39 52.07 90)
		(unit 1)
		(exclude_from_sim no)
		(in_bom yes)
		(on_board yes)
		(dnp no)
		(property "Reference" "C227"
			(at 328.422 48.26 90)
			(effects
				(font
					(size 1.27 1.27)
					(thickness 0.15)
				)
				(justify right)
			)
		)
		(property "Value" "C_1u_25V_0402"
			(at 336.55 31.75 0)
			(effects
				(font
					(size 1.27 1.27)
					(thickness 0.15)
				)
				(justify left bottom)
				(hide yes)
			)
		)
		(property "Footprint" "antmicro-footprints:C_0402_1005Metric"
			(at 339.09 31.75 0)
			(effects
				(font
					(size 1.27 1.27)
					(thickness 0.15)
				)
				(justify left bottom)
				(hide yes)
			)
		)
		(property "Datasheet" "https://www.murata.com/products/productdetail?partno=GRM155R61E105KE11%23"
			(at 341.63 31.75 0)
			(effects
				(font
					(size 1.27 1.27)
					(thickness 0.15)
				)
				(justify left bottom)
				(hide yes)
			)
		)
		(property "Description" "SMD Multilayer Ceramic Capacitor, 1 µF, 25 V, 0402 [1005 Metric], ± 10%, X5R, GRM Series"
			(at 326.39 52.07 0)
			(effects
				(font
					(size 1.27 1.27)
				)
				(hide yes)
			)
		)
		(property "MPN" "GRM155R61E105KE11J"
			(at 344.17 31.75 0)
			(effects
				(font
					(size 1.27 1.27)
					(thickness 0.15)
				)
				(justify left bottom)
				(hide yes)
			)
		)
		(property "Manufacturer" "Murata"
			(at 346.71 31.75 0)
			(effects
				(font
					(size 1.27 1.27)
					(thickness 0.15)
				)
				(justify left bottom)
				(hide yes)
			)
		)
		(property "License" "Apache-2.0"
			(at 349.25 31.75 0)
			(effects
				(font
					(size 1.27 1.27)
					(thickness 0.15)
				)
				(justify left bottom)
				(hide yes)
			)
		)
		(property "Author" "Antmicro"
			(at 351.79 31.75 0)
			(effects
				(font
					(size 1.27 1.27)
					(thickness 0.15)
				)
				(justify left bottom)
				(hide yes)
			)
		)
		(property "Val" "1u"
			(at 328.422 50.8 90)
			(effects
				(font
					(size 1.27 1.27)
					(thickness 0.15)
				)
				(justify right)
			)
		)
		(property "Voltage" "25V"
			(at 354.33 31.75 0)
			(effects
				(font
					(size 1.27 1.27)
				)
				(justify left bottom)
				(hide yes)
			)
		)
		(property "Dielectric" "X5R"
			(at 356.87 31.75 0)
			(effects
				(font
					(size 1.27 1.27)
				)
				(justify left bottom)
				(hide yes)
			)
		)
		(pin "2"
		)
		(pin "1"
		)
		(instances
			(project "OCuLink to 10GbE adapter"
				(path ""
					(reference "C90")
					(unit 1)
				)
			)
			(project "thunderbolt-to-10gbe-adapter"
				(path ""
					(reference "C227")
					(unit 1)
				)
			)
		)
	)
	(symbol
		(lib_id "antmicropower:GND")
		(at 317.5 115.57 0)
		(unit 1)
		(exclude_from_sim no)
		(in_bom yes)
		(on_board yes)
		(dnp no)
		(property "Reference" "#PWR0311"
			(at 326.39 118.11 0)
			(effects
				(font
					(size 1.27 1.27)
					(thickness 0.15)
				)
				(justify left bottom)
				(hide yes)
			)
		)
		(property "Value" "GND"
			(at 317.5 119.38 0)
			(effects
				(font
					(size 1.27 1.27)
					(thickness 0.15)
				)
			)
		)
		(property "Footprint" ""
			(at 326.39 123.19 0)
			(effects
				(font
					(size 1.27 1.27)
					(thickness 0.15)
				)
				(justify left bottom)
				(hide yes)
			)
		)
		(property "Datasheet" ""
			(at 326.39 128.27 0)
			(effects
				(font
					(size 1.27 1.27)
					(thickness 0.15)
				)
				(justify left bottom)
				(hide yes)
			)
		)
		(property "Description" ""
			(at 317.5 115.57 0)
			(effects
				(font
					(size 1.27 1.27)
				)
				(hide yes)
			)
		)
		(property "Author" "Antmicro"
			(at 326.39 123.19 0)
			(effects
				(font
					(size 1.27 1.27)
					(thickness 0.15)
				)
				(justify left bottom)
				(hide yes)
			)
		)
		(property "License" "Apache-2.0"
			(at 326.39 125.73 0)
			(effects
				(font
					(size 1.27 1.27)
					(thickness 0.15)
				)
				(justify left bottom)
				(hide yes)
			)
		)
		(pin "1"
		)
		(instances
			(project "OCuLink to 10GbE adapter"
				(path ""
					(reference "#PWR0179")
					(unit 1)
				)
			)
			(project "thunderbolt-to-10gbe-adapter"
				(path ""
					(reference "#PWR0311")
					(unit 1)
				)
			)
		)
	)
	(symbol
		(lib_id "antmicropower:GND")
		(at 133.35 182.88 0)
		(unit 1)
		(exclude_from_sim no)
		(in_bom yes)
		(on_board yes)
		(dnp no)
		(property "Reference" "#PWR0265"
			(at 142.24 185.42 0)
			(effects
				(font
					(size 1.27 1.27)
					(thickness 0.15)
				)
				(justify left bottom)
				(hide yes)
			)
		)
		(property "Value" "GND"
			(at 133.35 186.69 0)
			(effects
				(font
					(size 1.27 1.27)
					(thickness 0.15)
				)
			)
		)
		(property "Footprint" ""
			(at 142.24 190.5 0)
			(effects
				(font
					(size 1.27 1.27)
					(thickness 0.15)
				)
				(justify left bottom)
				(hide yes)
			)
		)
		(property "Datasheet" ""
			(at 142.24 195.58 0)
			(effects
				(font
					(size 1.27 1.27)
					(thickness 0.15)
				)
				(justify left bottom)
				(hide yes)
			)
		)
		(property "Description" ""
			(at 133.35 182.88 0)
			(effects
				(font
					(size 1.27 1.27)
				)
				(hide yes)
			)
		)
		(property "Author" "Antmicro"
			(at 142.24 190.5 0)
			(effects
				(font
					(size 1.27 1.27)
					(thickness 0.15)
				)
				(justify left bottom)
				(hide yes)
			)
		)
		(property "License" "Apache-2.0"
			(at 142.24 193.04 0)
			(effects
				(font
					(size 1.27 1.27)
					(thickness 0.15)
				)
				(justify left bottom)
				(hide yes)
			)
		)
		(pin "1"
		)
		(instances
			(project "OCuLink to 10GbE adapter"
				(path ""
					(reference "#PWR0228")
					(unit 1)
				)
			)
			(project "thunderbolt-to-10gbe-adapter"
				(path ""
					(reference "#PWR0265")
					(unit 1)
				)
			)
		)
	)
	(symbol
		(lib_id "antmicroCapacitors0402:C_1u_25V_0402")
		(at 361.95 113.03 90)
		(unit 1)
		(exclude_from_sim no)
		(in_bom yes)
		(on_board yes)
		(dnp no)
		(property "Reference" "C248"
			(at 363.982 109.22 90)
			(effects
				(font
					(size 1.27 1.27)
					(thickness 0.15)
				)
				(justify right)
			)
		)
		(property "Value" "C_1u_25V_0402"
			(at 372.11 92.71 0)
			(effects
				(font
					(size 1.27 1.27)
					(thickness 0.15)
				)
				(justify left bottom)
				(hide yes)
			)
		)
		(property "Footprint" "antmicro-footprints:C_0402_1005Metric"
			(at 374.65 92.71 0)
			(effects
				(font
					(size 1.27 1.27)
					(thickness 0.15)
				)
				(justify left bottom)
				(hide yes)
			)
		)
		(property "Datasheet" "https://www.murata.com/products/productdetail?partno=GRM155R61E105KE11%23"
			(at 377.19 92.71 0)
			(effects
				(font
					(size 1.27 1.27)
					(thickness 0.15)
				)
				(justify left bottom)
				(hide yes)
			)
		)
		(property "Description" "SMD Multilayer Ceramic Capacitor, 1 µF, 25 V, 0402 [1005 Metric], ± 10%, X5R, GRM Series"
			(at 361.95 113.03 0)
			(effects
				(font
					(size 1.27 1.27)
				)
				(hide yes)
			)
		)
		(property "MPN" "GRM155R61E105KE11J"
			(at 379.73 92.71 0)
			(effects
				(font
					(size 1.27 1.27)
					(thickness 0.15)
				)
				(justify left bottom)
				(hide yes)
			)
		)
		(property "Manufacturer" "Murata"
			(at 382.27 92.71 0)
			(effects
				(font
					(size 1.27 1.27)
					(thickness 0.15)
				)
				(justify left bottom)
				(hide yes)
			)
		)
		(property "License" "Apache-2.0"
			(at 384.81 92.71 0)
			(effects
				(font
					(size 1.27 1.27)
					(thickness 0.15)
				)
				(justify left bottom)
				(hide yes)
			)
		)
		(property "Author" "Antmicro"
			(at 387.35 92.71 0)
			(effects
				(font
					(size 1.27 1.27)
					(thickness 0.15)
				)
				(justify left bottom)
				(hide yes)
			)
		)
		(property "Val" "1u"
			(at 363.982 111.76 90)
			(effects
				(font
					(size 1.27 1.27)
					(thickness 0.15)
				)
				(justify right)
			)
		)
		(property "Voltage" "25V"
			(at 389.89 92.71 0)
			(effects
				(font
					(size 1.27 1.27)
				)
				(justify left bottom)
				(hide yes)
			)
		)
		(property "Dielectric" "X5R"
			(at 392.43 92.71 0)
			(effects
				(font
					(size 1.27 1.27)
				)
				(justify left bottom)
				(hide yes)
			)
		)
		(pin "2"
		)
		(pin "1"
		)
		(instances
			(project "OCuLink to 10GbE adapter"
				(path ""
					(reference "C136")
					(unit 1)
				)
			)
			(project "thunderbolt-to-10gbe-adapter"
				(path ""
					(reference "C248")
					(unit 1)
				)
			)
		)
	)
	(symbol
		(lib_id "antmicroCapacitors0402:C_1u_25V_0402")
		(at 370.84 73.66 90)
		(unit 1)
		(exclude_from_sim no)
		(in_bom yes)
		(on_board yes)
		(dnp no)
		(property "Reference" "C251"
			(at 372.872 69.85 90)
			(effects
				(font
					(size 1.27 1.27)
					(thickness 0.15)
				)
				(justify right)
			)
		)
		(property "Value" "C_1u_25V_0402"
			(at 381 53.34 0)
			(effects
				(font
					(size 1.27 1.27)
					(thickness 0.15)
				)
				(justify left bottom)
				(hide yes)
			)
		)
		(property "Footprint" "antmicro-footprints:C_0402_1005Metric"
			(at 383.54 53.34 0)
			(effects
				(font
					(size 1.27 1.27)
					(thickness 0.15)
				)
				(justify left bottom)
				(hide yes)
			)
		)
		(property "Datasheet" "https://www.murata.com/products/productdetail?partno=GRM155R61E105KE11%23"
			(at 386.08 53.34 0)
			(effects
				(font
					(size 1.27 1.27)
					(thickness 0.15)
				)
				(justify left bottom)
				(hide yes)
			)
		)
		(property "Description" "SMD Multilayer Ceramic Capacitor, 1 µF, 25 V, 0402 [1005 Metric], ± 10%, X5R, GRM Series"
			(at 370.84 73.66 0)
			(effects
				(font
					(size 1.27 1.27)
				)
				(hide yes)
			)
		)
		(property "MPN" "GRM155R61E105KE11J"
			(at 388.62 53.34 0)
			(effects
				(font
					(size 1.27 1.27)
					(thickness 0.15)
				)
				(justify left bottom)
				(hide yes)
			)
		)
		(property "Manufacturer" "Murata"
			(at 391.16 53.34 0)
			(effects
				(font
					(size 1.27 1.27)
					(thickness 0.15)
				)
				(justify left bottom)
				(hide yes)
			)
		)
		(property "License" "Apache-2.0"
			(at 393.7 53.34 0)
			(effects
				(font
					(size 1.27 1.27)
					(thickness 0.15)
				)
				(justify left bottom)
				(hide yes)
			)
		)
		(property "Author" "Antmicro"
			(at 396.24 53.34 0)
			(effects
				(font
					(size 1.27 1.27)
					(thickness 0.15)
				)
				(justify left bottom)
				(hide yes)
			)
		)
		(property "Val" "1u"
			(at 372.872 72.39 90)
			(effects
				(font
					(size 1.27 1.27)
					(thickness 0.15)
				)
				(justify right)
			)
		)
		(property "Voltage" "25V"
			(at 398.78 53.34 0)
			(effects
				(font
					(size 1.27 1.27)
				)
				(justify left bottom)
				(hide yes)
			)
		)
		(property "Dielectric" "X5R"
			(at 401.32 53.34 0)
			(effects
				(font
					(size 1.27 1.27)
				)
				(justify left bottom)
				(hide yes)
			)
		)
		(pin "2"
		)
		(pin "1"
		)
		(instances
			(project "OCuLink to 10GbE adapter"
				(path ""
					(reference "C113")
					(unit 1)
				)
			)
			(project "thunderbolt-to-10gbe-adapter"
				(path ""
					(reference "C251")
					(unit 1)
				)
			)
		)
	)
	(symbol
		(lib_id "antmicropower:GND")
		(at 106.68 156.21 0)
		(unit 1)
		(exclude_from_sim no)
		(in_bom yes)
		(on_board yes)
		(dnp no)
		(property "Reference" "#PWR0249"
			(at 115.57 158.75 0)
			(effects
				(font
					(size 1.27 1.27)
					(thickness 0.15)
				)
				(justify left bottom)
				(hide yes)
			)
		)
		(property "Value" "GND"
			(at 106.68 160.02 0)
			(effects
				(font
					(size 1.27 1.27)
					(thickness 0.15)
				)
			)
		)
		(property "Footprint" ""
			(at 115.57 163.83 0)
			(effects
				(font
					(size 1.27 1.27)
					(thickness 0.15)
				)
				(justify left bottom)
				(hide yes)
			)
		)
		(property "Datasheet" ""
			(at 115.57 168.91 0)
			(effects
				(font
					(size 1.27 1.27)
					(thickness 0.15)
				)
				(justify left bottom)
				(hide yes)
			)
		)
		(property "Description" ""
			(at 106.68 156.21 0)
			(effects
				(font
					(size 1.27 1.27)
				)
				(hide yes)
			)
		)
		(property "Author" "Antmicro"
			(at 115.57 163.83 0)
			(effects
				(font
					(size 1.27 1.27)
					(thickness 0.15)
				)
				(justify left bottom)
				(hide yes)
			)
		)
		(property "License" "Apache-2.0"
			(at 115.57 166.37 0)
			(effects
				(font
					(size 1.27 1.27)
					(thickness 0.15)
				)
				(justify left bottom)
				(hide yes)
			)
		)
		(pin "1"
		)
		(instances
			(project "OCuLink to 10GbE adapter"
				(path ""
					(reference "#PWR0215")
					(unit 1)
				)
			)
			(project "thunderbolt-to-10gbe-adapter"
				(path ""
					(reference "#PWR0249")
					(unit 1)
				)
			)
		)
	)
	(symbol
		(lib_id "antmicropower:GND")
		(at 353.06 76.2 0)
		(unit 1)
		(exclude_from_sim no)
		(in_bom yes)
		(on_board yes)
		(dnp no)
		(property "Reference" "#PWR0327"
			(at 361.95 78.74 0)
			(effects
				(font
					(size 1.27 1.27)
					(thickness 0.15)
				)
				(justify left bottom)
				(hide yes)
			)
		)
		(property "Value" "GND"
			(at 353.06 80.01 0)
			(effects
				(font
					(size 1.27 1.27)
					(thickness 0.15)
				)
			)
		)
		(property "Footprint" ""
			(at 361.95 83.82 0)
			(effects
				(font
					(size 1.27 1.27)
					(thickness 0.15)
				)
				(justify left bottom)
				(hide yes)
			)
		)
		(property "Datasheet" ""
			(at 361.95 88.9 0)
			(effects
				(font
					(size 1.27 1.27)
					(thickness 0.15)
				)
				(justify left bottom)
				(hide yes)
			)
		)
		(property "Description" ""
			(at 353.06 76.2 0)
			(effects
				(font
					(size 1.27 1.27)
				)
				(hide yes)
			)
		)
		(property "Author" "Antmicro"
			(at 361.95 83.82 0)
			(effects
				(font
					(size 1.27 1.27)
					(thickness 0.15)
				)
				(justify left bottom)
				(hide yes)
			)
		)
		(property "License" "Apache-2.0"
			(at 361.95 86.36 0)
			(effects
				(font
					(size 1.27 1.27)
					(thickness 0.15)
				)
				(justify left bottom)
				(hide yes)
			)
		)
		(pin "1"
		)
		(instances
			(project "OCuLink to 10GbE adapter"
				(path ""
					(reference "#PWR0145")
					(unit 1)
				)
			)
			(project "thunderbolt-to-10gbe-adapter"
				(path ""
					(reference "#PWR0327")
					(unit 1)
				)
			)
		)
	)
	(symbol
		(lib_id "antmicroCapacitors0603:C_10u_10V_X7R_0603")
		(at 97.79 73.66 90)
		(unit 1)
		(exclude_from_sim no)
		(in_bom yes)
		(on_board yes)
		(dnp no)
		(property "Reference" "C176"
			(at 99.568 69.85 90)
			(effects
				(font
					(size 1.27 1.27)
					(thickness 0.15)
				)
				(justify right)
			)
		)
		(property "Value" "C_10u_10V_X7R_0603"
			(at 107.95 58.42 0)
			(effects
				(font
					(size 1.27 1.27)
					(thickness 0.15)
				)
				(justify left bottom)
				(hide yes)
			)
		)
		(property "Footprint" "antmicro-footprints:C_0603_1608Metric"
			(at 110.49 58.42 0)
			(effects
				(font
					(size 1.27 1.27)
					(thickness 0.15)
				)
				(justify left bottom)
				(hide yes)
			)
		)
		(property "Datasheet" "https://www.murata.com/products/productdetail?partno=GRM188Z71A106KA73%23"
			(at 113.03 58.42 0)
			(effects
				(font
					(size 1.27 1.27)
					(thickness 0.15)
				)
				(justify left bottom)
				(hide yes)
			)
		)
		(property "Description" "SMD Multilayer Ceramic Capacitor,  10µF, 10V, 0603, ±10%, X7R"
			(at 97.79 73.66 0)
			(effects
				(font
					(size 1.27 1.27)
				)
				(hide yes)
			)
		)
		(property "MPN" "GRM188Z71A106KA73D"
			(at 115.57 58.42 0)
			(effects
				(font
					(size 1.27 1.27)
					(thickness 0.15)
				)
				(justify left bottom)
				(hide yes)
			)
		)
		(property "Val" "10u"
			(at 99.568 72.39 90)
			(effects
				(font
					(size 1.27 1.27)
					(thickness 0.15)
				)
				(justify right)
			)
		)
		(property "Voltage" "10V"
			(at 118.11 58.42 0)
			(effects
				(font
					(size 1.27 1.27)
					(thickness 0.15)
				)
				(justify left bottom)
				(hide yes)
			)
		)
		(property "Dielectric" "X7R"
			(at 120.65 58.42 0)
			(effects
				(font
					(size 1.27 1.27)
					(thickness 0.15)
				)
				(justify left bottom)
				(hide yes)
			)
		)
		(property "Manufacturer" "Murata"
			(at 123.19 58.42 0)
			(effects
				(font
					(size 1.27 1.27)
					(thickness 0.15)
				)
				(justify left bottom)
				(hide yes)
			)
		)
		(property "License" "Apache-2.0"
			(at 125.73 58.42 0)
			(effects
				(font
					(size 1.27 1.27)
					(thickness 0.15)
				)
				(justify left bottom)
				(hide yes)
			)
		)
		(property "Author" "Antmicro"
			(at 128.27 58.42 0)
			(effects
				(font
					(size 1.27 1.27)
					(thickness 0.15)
				)
				(justify left bottom)
				(hide yes)
			)
		)
		(pin "1"
		)
		(pin "2"
		)
		(instances
			(project "OCuLink to 10GbE adapter"
				(path ""
					(reference "C100")
					(unit 1)
				)
			)
			(project "thunderbolt-to-10gbe-adapter"
				(path ""
					(reference "C176")
					(unit 1)
				)
			)
		)
	)
	(symbol
		(lib_id "antmicropower:GND")
		(at 370.84 133.35 0)
		(unit 1)
		(exclude_from_sim no)
		(in_bom yes)
		(on_board yes)
		(dnp no)
		(property "Reference" "#PWR0340"
			(at 379.73 135.89 0)
			(effects
				(font
					(size 1.27 1.27)
					(thickness 0.15)
				)
				(justify left bottom)
				(hide yes)
			)
		)
		(property "Value" "GND"
			(at 370.84 137.16 0)
			(effects
				(font
					(size 1.27 1.27)
					(thickness 0.15)
				)
			)
		)
		(property "Footprint" ""
			(at 379.73 140.97 0)
			(effects
				(font
					(size 1.27 1.27)
					(thickness 0.15)
				)
				(justify left bottom)
				(hide yes)
			)
		)
		(property "Datasheet" ""
			(at 379.73 146.05 0)
			(effects
				(font
					(size 1.27 1.27)
					(thickness 0.15)
				)
				(justify left bottom)
				(hide yes)
			)
		)
		(property "Description" ""
			(at 370.84 133.35 0)
			(effects
				(font
					(size 1.27 1.27)
				)
				(hide yes)
			)
		)
		(property "Author" "Antmicro"
			(at 379.73 140.97 0)
			(effects
				(font
					(size 1.27 1.27)
					(thickness 0.15)
				)
				(justify left bottom)
				(hide yes)
			)
		)
		(property "License" "Apache-2.0"
			(at 379.73 143.51 0)
			(effects
				(font
					(size 1.27 1.27)
					(thickness 0.15)
				)
				(justify left bottom)
				(hide yes)
			)
		)
		(pin "1"
		)
		(instances
			(project "OCuLink to 10GbE adapter"
				(path ""
					(reference "#PWR0202")
					(unit 1)
				)
			)
			(project "thunderbolt-to-10gbe-adapter"
				(path ""
					(reference "#PWR0340")
					(unit 1)
				)
			)
		)
	)
	(symbol
		(lib_id "antmicroCapacitors0402:C_1u_25V_0402")
		(at 317.5 113.03 90)
		(unit 1)
		(exclude_from_sim no)
		(in_bom yes)
		(on_board yes)
		(dnp no)
		(property "Reference" "C225"
			(at 319.532 109.22 90)
			(effects
				(font
					(size 1.27 1.27)
					(thickness 0.15)
				)
				(justify right)
			)
		)
		(property "Value" "C_1u_25V_0402"
			(at 327.66 92.71 0)
			(effects
				(font
					(size 1.27 1.27)
					(thickness 0.15)
				)
				(justify left bottom)
				(hide yes)
			)
		)
		(property "Footprint" "antmicro-footprints:C_0402_1005Metric"
			(at 330.2 92.71 0)
			(effects
				(font
					(size 1.27 1.27)
					(thickness 0.15)
				)
				(justify left bottom)
				(hide yes)
			)
		)
		(property "Datasheet" "https://www.murata.com/products/productdetail?partno=GRM155R61E105KE11%23"
			(at 332.74 92.71 0)
			(effects
				(font
					(size 1.27 1.27)
					(thickness 0.15)
				)
				(justify left bottom)
				(hide yes)
			)
		)
		(property "Description" "SMD Multilayer Ceramic Capacitor, 1 µF, 25 V, 0402 [1005 Metric], ± 10%, X5R, GRM Series"
			(at 317.5 113.03 0)
			(effects
				(font
					(size 1.27 1.27)
				)
				(hide yes)
			)
		)
		(property "MPN" "GRM155R61E105KE11J"
			(at 335.28 92.71 0)
			(effects
				(font
					(size 1.27 1.27)
					(thickness 0.15)
				)
				(justify left bottom)
				(hide yes)
			)
		)
		(property "Manufacturer" "Murata"
			(at 337.82 92.71 0)
			(effects
				(font
					(size 1.27 1.27)
					(thickness 0.15)
				)
				(justify left bottom)
				(hide yes)
			)
		)
		(property "License" "Apache-2.0"
			(at 340.36 92.71 0)
			(effects
				(font
					(size 1.27 1.27)
					(thickness 0.15)
				)
				(justify left bottom)
				(hide yes)
			)
		)
		(property "Author" "Antmicro"
			(at 342.9 92.71 0)
			(effects
				(font
					(size 1.27 1.27)
					(thickness 0.15)
				)
				(justify left bottom)
				(hide yes)
			)
		)
		(property "Val" "1u"
			(at 319.532 111.76 90)
			(effects
				(font
					(size 1.27 1.27)
					(thickness 0.15)
				)
				(justify right)
			)
		)
		(property "Voltage" "25V"
			(at 345.44 92.71 0)
			(effects
				(font
					(size 1.27 1.27)
				)
				(justify left bottom)
				(hide yes)
			)
		)
		(property "Dielectric" "X5R"
			(at 347.98 92.71 0)
			(effects
				(font
					(size 1.27 1.27)
				)
				(justify left bottom)
				(hide yes)
			)
		)
		(pin "2"
		)
		(pin "1"
		)
		(instances
			(project "OCuLink to 10GbE adapter"
				(path ""
					(reference "C131")
					(unit 1)
				)
			)
			(project "thunderbolt-to-10gbe-adapter"
				(path ""
					(reference "C225")
					(unit 1)
				)
			)
		)
	)
	(symbol
		(lib_id "antmicroCapacitors0603:C_10u_10V_X7R_0603")
		(at 309.88 149.86 270)
		(mirror x)
		(unit 1)
		(exclude_from_sim no)
		(in_bom yes)
		(on_board yes)
		(dnp no)
		(property "Reference" "C221"
			(at 307.848 146.05 90)
			(effects
				(font
					(size 1.27 1.27)
					(thickness 0.15)
				)
				(justify right)
			)
		)
		(property "Value" "C_10u_10V_X7R_0603"
			(at 299.72 134.62 0)
			(effects
				(font
					(size 1.27 1.27)
					(thickness 0.15)
				)
				(justify left bottom)
				(hide yes)
			)
		)
		(property "Footprint" "antmicro-footprints:C_0603_1608Metric"
			(at 297.18 134.62 0)
			(effects
				(font
					(size 1.27 1.27)
					(thickness 0.15)
				)
				(justify left bottom)
				(hide yes)
			)
		)
		(property "Datasheet" "https://www.murata.com/products/productdetail?partno=GRM188Z71A106KA73%23"
			(at 294.64 134.62 0)
			(effects
				(font
					(size 1.27 1.27)
					(thickness 0.15)
				)
				(justify left bottom)
				(hide yes)
			)
		)
		(property "Description" "SMD Multilayer Ceramic Capacitor,  10µF, 10V, 0603, ±10%, X7R"
			(at 309.88 149.86 0)
			(effects
				(font
					(size 1.27 1.27)
				)
				(hide yes)
			)
		)
		(property "MPN" "GRM188Z71A106KA73D"
			(at 292.1 134.62 0)
			(effects
				(font
					(size 1.27 1.27)
					(thickness 0.15)
				)
				(justify left bottom)
				(hide yes)
			)
		)
		(property "Val" "10u"
			(at 307.848 148.59 90)
			(effects
				(font
					(size 1.27 1.27)
					(thickness 0.15)
				)
				(justify right)
			)
		)
		(property "Voltage" "10V"
			(at 289.56 134.62 0)
			(effects
				(font
					(size 1.27 1.27)
					(thickness 0.15)
				)
				(justify left bottom)
				(hide yes)
			)
		)
		(property "Dielectric" "X7R"
			(at 287.02 134.62 0)
			(effects
				(font
					(size 1.27 1.27)
					(thickness 0.15)
				)
				(justify left bottom)
				(hide yes)
			)
		)
		(property "Manufacturer" "Murata"
			(at 284.48 134.62 0)
			(effects
				(font
					(size 1.27 1.27)
					(thickness 0.15)
				)
				(justify left bottom)
				(hide yes)
			)
		)
		(property "License" "Apache-2.0"
			(at 281.94 134.62 0)
			(effects
				(font
					(size 1.27 1.27)
					(thickness 0.15)
				)
				(justify left bottom)
				(hide yes)
			)
		)
		(property "Author" "Antmicro"
			(at 279.4 134.62 0)
			(effects
				(font
					(size 1.27 1.27)
					(thickness 0.15)
				)
				(justify left bottom)
				(hide yes)
			)
		)
		(pin "1"
		)
		(pin "2"
		)
		(instances
			(project "OCuLink to 10GbE adapter"
				(path ""
					(reference "C160")
					(unit 1)
				)
			)
			(project "thunderbolt-to-10gbe-adapter"
				(path ""
					(reference "C221")
					(unit 1)
				)
			)
		)
	)
	(symbol
		(lib_id "antmicropower:GND")
		(at 151.13 236.22 0)
		(unit 1)
		(exclude_from_sim no)
		(in_bom yes)
		(on_board yes)
		(dnp no)
		(property "Reference" "#PWR0279"
			(at 160.02 238.76 0)
			(effects
				(font
					(size 1.27 1.27)
					(thickness 0.15)
				)
				(justify left bottom)
				(hide yes)
			)
		)
		(property "Value" "GND"
			(at 151.13 240.03 0)
			(effects
				(font
					(size 1.27 1.27)
					(thickness 0.15)
				)
			)
		)
		(property "Footprint" ""
			(at 160.02 243.84 0)
			(effects
				(font
					(size 1.27 1.27)
					(thickness 0.15)
				)
				(justify left bottom)
				(hide yes)
			)
		)
		(property "Datasheet" ""
			(at 160.02 248.92 0)
			(effects
				(font
					(size 1.27 1.27)
					(thickness 0.15)
				)
				(justify left bottom)
				(hide yes)
			)
		)
		(property "Description" ""
			(at 151.13 236.22 0)
			(effects
				(font
					(size 1.27 1.27)
				)
				(hide yes)
			)
		)
		(property "Author" "Antmicro"
			(at 160.02 243.84 0)
			(effects
				(font
					(size 1.27 1.27)
					(thickness 0.15)
				)
				(justify left bottom)
				(hide yes)
			)
		)
		(property "License" "Apache-2.0"
			(at 160.02 246.38 0)
			(effects
				(font
					(size 1.27 1.27)
					(thickness 0.15)
				)
				(justify left bottom)
				(hide yes)
			)
		)
		(pin "1"
		)
		(instances
			(project "OCuLink to 10GbE adapter"
				(path ""
					(reference "#PWR0241")
					(unit 1)
				)
			)
			(project "thunderbolt-to-10gbe-adapter"
				(path ""
					(reference "#PWR0279")
					(unit 1)
				)
			)
		)
	)
	(symbol
		(lib_id "antmicroCapacitors0603:C_10u_10V_X7R_0603")
		(at 283.21 149.86 270)
		(mirror x)
		(unit 1)
		(exclude_from_sim no)
		(in_bom yes)
		(on_board yes)
		(dnp no)
		(property "Reference" "C209"
			(at 281.178 146.05 90)
			(effects
				(font
					(size 1.27 1.27)
					(thickness 0.15)
				)
				(justify right)
			)
		)
		(property "Value" "C_10u_10V_X7R_0603"
			(at 273.05 134.62 0)
			(effects
				(font
					(size 1.27 1.27)
					(thickness 0.15)
				)
				(justify left bottom)
				(hide yes)
			)
		)
		(property "Footprint" "antmicro-footprints:C_0603_1608Metric"
			(at 270.51 134.62 0)
			(effects
				(font
					(size 1.27 1.27)
					(thickness 0.15)
				)
				(justify left bottom)
				(hide yes)
			)
		)
		(property "Datasheet" "https://www.murata.com/products/productdetail?partno=GRM188Z71A106KA73%23"
			(at 267.97 134.62 0)
			(effects
				(font
					(size 1.27 1.27)
					(thickness 0.15)
				)
				(justify left bottom)
				(hide yes)
			)
		)
		(property "Description" "SMD Multilayer Ceramic Capacitor,  10µF, 10V, 0603, ±10%, X7R"
			(at 283.21 149.86 0)
			(effects
				(font
					(size 1.27 1.27)
				)
				(hide yes)
			)
		)
		(property "MPN" "GRM188Z71A106KA73D"
			(at 265.43 134.62 0)
			(effects
				(font
					(size 1.27 1.27)
					(thickness 0.15)
				)
				(justify left bottom)
				(hide yes)
			)
		)
		(property "Val" "10u"
			(at 281.178 148.59 90)
			(effects
				(font
					(size 1.27 1.27)
					(thickness 0.15)
				)
				(justify right)
			)
		)
		(property "Voltage" "10V"
			(at 262.89 134.62 0)
			(effects
				(font
					(size 1.27 1.27)
					(thickness 0.15)
				)
				(justify left bottom)
				(hide yes)
			)
		)
		(property "Dielectric" "X7R"
			(at 260.35 134.62 0)
			(effects
				(font
					(size 1.27 1.27)
					(thickness 0.15)
				)
				(justify left bottom)
				(hide yes)
			)
		)
		(property "Manufacturer" "Murata"
			(at 257.81 134.62 0)
			(effects
				(font
					(size 1.27 1.27)
					(thickness 0.15)
				)
				(justify left bottom)
				(hide yes)
			)
		)
		(property "License" "Apache-2.0"
			(at 255.27 134.62 0)
			(effects
				(font
					(size 1.27 1.27)
					(thickness 0.15)
				)
				(justify left bottom)
				(hide yes)
			)
		)
		(property "Author" "Antmicro"
			(at 252.73 134.62 0)
			(effects
				(font
					(size 1.27 1.27)
					(thickness 0.15)
				)
				(justify left bottom)
				(hide yes)
			)
		)
		(pin "1"
		)
		(pin "2"
		)
		(instances
			(project "OCuLink to 10GbE adapter"
				(path ""
					(reference "C157")
					(unit 1)
				)
			)
			(project "thunderbolt-to-10gbe-adapter"
				(path ""
					(reference "C209")
					(unit 1)
				)
			)
		)
	)
	(symbol
		(lib_id "antmicropower:GND")
		(at 77.47 102.87 0)
		(unit 1)
		(exclude_from_sim no)
		(in_bom yes)
		(on_board yes)
		(dnp no)
		(property "Reference" "#PWR0232"
			(at 86.36 105.41 0)
			(effects
				(font
					(size 1.27 1.27)
					(thickness 0.15)
				)
				(justify left bottom)
				(hide yes)
			)
		)
		(property "Value" "GND"
			(at 77.47 106.68 0)
			(effects
				(font
					(size 1.27 1.27)
					(thickness 0.15)
				)
			)
		)
		(property "Footprint" ""
			(at 86.36 110.49 0)
			(effects
				(font
					(size 1.27 1.27)
					(thickness 0.15)
				)
				(justify left bottom)
				(hide yes)
			)
		)
		(property "Datasheet" ""
			(at 86.36 115.57 0)
			(effects
				(font
					(size 1.27 1.27)
					(thickness 0.15)
				)
				(justify left bottom)
				(hide yes)
			)
		)
		(property "Description" ""
			(at 77.47 102.87 0)
			(effects
				(font
					(size 1.27 1.27)
				)
				(hide yes)
			)
		)
		(property "Author" "Antmicro"
			(at 86.36 110.49 0)
			(effects
				(font
					(size 1.27 1.27)
					(thickness 0.15)
				)
				(justify left bottom)
				(hide yes)
			)
		)
		(property "License" "Apache-2.0"
			(at 86.36 113.03 0)
			(effects
				(font
					(size 1.27 1.27)
					(thickness 0.15)
				)
				(justify left bottom)
				(hide yes)
			)
		)
		(pin "1"
		)
		(instances
			(project "OCuLink to 10GbE adapter"
				(path ""
					(reference "#PWR0175")
					(unit 1)
				)
			)
			(project "thunderbolt-to-10gbe-adapter"
				(path ""
					(reference "#PWR0232")
					(unit 1)
				)
			)
		)
	)
	(symbol
		(lib_id "antmicropower:GND")
		(at 99.06 54.61 0)
		(unit 1)
		(exclude_from_sim no)
		(in_bom yes)
		(on_board yes)
		(dnp no)
		(property "Reference" "#PWR0246"
			(at 107.95 57.15 0)
			(effects
				(font
					(size 1.27 1.27)
					(thickness 0.15)
				)
				(justify left bottom)
				(hide yes)
			)
		)
		(property "Value" "GND"
			(at 99.06 58.42 0)
			(effects
				(font
					(size 1.27 1.27)
					(thickness 0.15)
				)
			)
		)
		(property "Footprint" ""
			(at 107.95 62.23 0)
			(effects
				(font
					(size 1.27 1.27)
					(thickness 0.15)
				)
				(justify left bottom)
				(hide yes)
			)
		)
		(property "Datasheet" ""
			(at 107.95 67.31 0)
			(effects
				(font
					(size 1.27 1.27)
					(thickness 0.15)
				)
				(justify left bottom)
				(hide yes)
			)
		)
		(property "Description" ""
			(at 99.06 54.61 0)
			(effects
				(font
					(size 1.27 1.27)
				)
				(hide yes)
			)
		)
		(property "Author" "Antmicro"
			(at 107.95 62.23 0)
			(effects
				(font
					(size 1.27 1.27)
					(thickness 0.15)
				)
				(justify left bottom)
				(hide yes)
			)
		)
		(property "License" "Apache-2.0"
			(at 107.95 64.77 0)
			(effects
				(font
					(size 1.27 1.27)
					(thickness 0.15)
				)
				(justify left bottom)
				(hide yes)
			)
		)
		(pin "1"
		)
		(instances
			(project "OCuLink to 10GbE adapter"
				(path ""
					(reference "#PWR0115")
					(unit 1)
				)
			)
			(project "thunderbolt-to-10gbe-adapter"
				(path ""
					(reference "#PWR0246")
					(unit 1)
				)
			)
		)
	)
	(symbol
		(lib_id "antmicroFerriteBeadsandChips:FB_470Z_1A_Murata-BLM18PG_0603")
		(at 80.01 252.73 0)
		(unit 1)
		(exclude_from_sim no)
		(in_bom yes)
		(on_board yes)
		(dnp no)
		(fields_autoplaced yes)
		(property "Reference" "FB3"
			(at 82.5119 246.38 0)
			(effects
				(font
					(size 1.27 1.27)
					(thickness 0.15)
				)
			)
		)
		(property "Value" "FB_470Z_1A_Murata-BLM18PG_0603"
			(at 93.98 255.27 0)
			(effects
				(font
					(size 1.27 1.27)
					(thickness 0.15)
				)
				(justify left bottom)
				(hide yes)
			)
		)
		(property "Footprint" "antmicro-footprints:FB_0603_1608Metric"
			(at 93.98 260.35 0)
			(effects
				(font
					(size 1.27 1.27)
					(thickness 0.15)
				)
				(justify left bottom)
				(hide yes)
			)
		)
		(property "Datasheet" "https://www.murata.com/en-us/products/productdata/8796738650142/ENFA0003.pdf"
			(at 93.98 262.89 0)
			(effects
				(font
					(size 1.27 1.27)
					(thickness 0.15)
				)
				(justify left bottom)
				(hide yes)
			)
		)
		(property "Description" "Ferrite Bead, 0603 [1608 Metric], 470 ohm, 1 A, BLM18P, 0.2 ohm, ± 25%, DC power line"
			(at 80.01 252.73 0)
			(effects
				(font
					(size 1.27 1.27)
				)
				(hide yes)
			)
		)
		(property "Val" "470Z/1A"
			(at 82.5119 248.92 0)
			(effects
				(font
					(size 1.27 1.27)
				)
			)
		)
		(property "MPN" "BLM18PG471SN1D"
			(at 93.98 265.43 0)
			(effects
				(font
					(size 1.27 1.27)
					(thickness 0.15)
				)
				(justify left bottom)
				(hide yes)
			)
		)
		(property "Manufacturer" "Murata"
			(at 93.98 267.97 0)
			(effects
				(font
					(size 1.27 1.27)
					(thickness 0.15)
				)
				(justify left bottom)
				(hide yes)
			)
		)
		(property "Current" ""
			(at 100.33 275.59 0)
			(effects
				(font
					(size 1.27 1.27)
					(thickness 0.15)
				)
				(justify left bottom)
				(hide yes)
			)
		)
		(property "Author" "Antmicro"
			(at 93.98 270.51 0)
			(effects
				(font
					(size 1.27 1.27)
					(thickness 0.15)
				)
				(justify left bottom)
				(hide yes)
			)
		)
		(property "License" "Apache-2.0"
			(at 93.98 273.05 0)
			(effects
				(font
					(size 1.27 1.27)
					(thickness 0.15)
				)
				(justify left bottom)
				(hide yes)
			)
		)
		(pin "2"
		)
		(pin "1"
		)
		(instances
			(project ""
				(path ""
					(reference "FB7")
					(unit 1)
				)
			)
			(project "thunderbolt-to-10gbe-adapter"
				(path ""
					(reference "FB3")
					(unit 1)
				)
			)
		)
	)
	(symbol
		(lib_id "antmicropower:GND")
		(at 397.51 93.98 0)
		(unit 1)
		(exclude_from_sim no)
		(in_bom yes)
		(on_board yes)
		(dnp no)
		(property "Reference" "#PWR0351"
			(at 406.4 96.52 0)
			(effects
				(font
					(size 1.27 1.27)
					(thickness 0.15)
				)
				(justify left bottom)
				(hide yes)
			)
		)
		(property "Value" "GND"
			(at 397.51 97.79 0)
			(effects
				(font
					(size 1.27 1.27)
					(thickness 0.15)
				)
			)
		)
		(property "Footprint" ""
			(at 406.4 101.6 0)
			(effects
				(font
					(size 1.27 1.27)
					(thickness 0.15)
				)
				(justify left bottom)
				(hide yes)
			)
		)
		(property "Datasheet" ""
			(at 406.4 106.68 0)
			(effects
				(font
					(size 1.27 1.27)
					(thickness 0.15)
				)
				(justify left bottom)
				(hide yes)
			)
		)
		(property "Description" ""
			(at 397.51 93.98 0)
			(effects
				(font
					(size 1.27 1.27)
				)
				(hide yes)
			)
		)
		(property "Author" "Antmicro"
			(at 406.4 101.6 0)
			(effects
				(font
					(size 1.27 1.27)
					(thickness 0.15)
				)
				(justify left bottom)
				(hide yes)
			)
		)
		(property "License" "Apache-2.0"
			(at 406.4 104.14 0)
			(effects
				(font
					(size 1.27 1.27)
					(thickness 0.15)
				)
				(justify left bottom)
				(hide yes)
			)
		)
		(pin "1"
		)
		(instances
			(project "OCuLink to 10GbE adapter"
				(path ""
					(reference "#PWR0174")
					(unit 1)
				)
			)
			(project "thunderbolt-to-10gbe-adapter"
				(path ""
					(reference "#PWR0351")
					(unit 1)
				)
			)
		)
	)
	(symbol
		(lib_id "antmicroCapacitorspol:C_Pol_100u_6V_KEMET-T490-A")
		(at 57.15 148.59 270)
		(unit 1)
		(exclude_from_sim no)
		(in_bom yes)
		(on_board yes)
		(dnp no)
		(fields_autoplaced yes)
		(property "Reference" "C326"
			(at 59.69 149.3266 90)
			(effects
				(font
					(size 1.27 1.27)
					(thickness 0.15)
				)
				(justify left)
			)
		)
		(property "Value" "C_Pol_100u_6V_KEMET-T490-A"
			(at 54.61 162.56 0)
			(effects
				(font
					(size 1.27 1.27)
					(thickness 0.15)
				)
				(justify left bottom)
				(hide yes)
			)
		)
		(property "Footprint" "antmicro-footprints:C_Pol_EIA-A"
			(at 49.53 162.56 0)
			(effects
				(font
					(size 1.27 1.27)
					(thickness 0.15)
				)
				(justify left bottom)
				(hide yes)
			)
		)
		(property "Datasheet" "https://www.kemet.com/en/us/capacitors/product/T490A107M006ATE800.html"
			(at 46.99 162.56 0)
			(effects
				(font
					(size 1.27 1.27)
					(thickness 0.15)
				)
				(justify left bottom)
				(hide yes)
			)
		)
		(property "Description" "Surface Mount Tantalum Capacitor,  Solid SMD 6V 100uF 1206 20% ESR=800mOhms"
			(at 31.75 162.56 0)
			(effects
				(font
					(size 1.27 1.27)
				)
				(justify left bottom)
				(hide yes)
			)
		)
		(property "Val" "100u"
			(at 59.69 151.8666 90)
			(effects
				(font
					(size 1.27 1.27)
					(thickness 0.15)
				)
				(justify left)
			)
		)
		(property "MPN" "T490A107M006ATE800"
			(at 44.45 162.56 0)
			(effects
				(font
					(size 1.27 1.27)
					(thickness 0.15)
				)
				(justify left bottom)
				(hide yes)
			)
		)
		(property "Manufacturer" "KEMET"
			(at 41.91 162.56 0)
			(effects
				(font
					(size 1.27 1.27)
					(thickness 0.15)
				)
				(justify left bottom)
				(hide yes)
			)
		)
		(property "License" "Apache-2.0"
			(at 39.37 162.56 0)
			(effects
				(font
					(size 1.27 1.27)
					(thickness 0.15)
				)
				(justify left bottom)
				(hide yes)
			)
		)
		(property "Author" "Antmicro"
			(at 36.83 162.56 0)
			(effects
				(font
					(size 1.27 1.27)
					(thickness 0.15)
				)
				(justify left bottom)
				(hide yes)
			)
		)
		(property "Voltage" "6V"
			(at 34.29 162.56 0)
			(effects
				(font
					(size 1.27 1.27)
				)
				(justify left bottom)
				(hide yes)
			)
		)
		(property "Dielectric" "template_dielectric"
			(at 31.75 162.56 0)
			(effects
				(font
					(size 1.27 1.27)
				)
				(justify left bottom)
				(hide yes)
			)
		)
		(pin "2"
		)
		(pin "1"
		)
		(instances
			(project "thunderbolt-to-10gbe-adapter"
				(path ""
					(reference "C326")
					(unit 1)
				)
			)
		)
	)
	(symbol
		(lib_id "antmicroCapacitors0603:C_10u_10V_X7R_0603")
		(at 97.79 127 90)
		(unit 1)
		(exclude_from_sim no)
		(in_bom yes)
		(on_board yes)
		(dnp no)
		(property "Reference" "C177"
			(at 99.568 123.19 90)
			(effects
				(font
					(size 1.27 1.27)
					(thickness 0.15)
				)
				(justify right)
			)
		)
		(property "Value" "C_10u_10V_X7R_0603"
			(at 107.95 111.76 0)
			(effects
				(font
					(size 1.27 1.27)
					(thickness 0.15)
				)
				(justify left bottom)
				(hide yes)
			)
		)
		(property "Footprint" "antmicro-footprints:C_0603_1608Metric"
			(at 110.49 111.76 0)
			(effects
				(font
					(size 1.27 1.27)
					(thickness 0.15)
				)
				(justify left bottom)
				(hide yes)
			)
		)
		(property "Datasheet" "https://www.murata.com/products/productdetail?partno=GRM188Z71A106KA73%23"
			(at 113.03 111.76 0)
			(effects
				(font
					(size 1.27 1.27)
					(thickness 0.15)
				)
				(justify left bottom)
				(hide yes)
			)
		)
		(property "Description" "SMD Multilayer Ceramic Capacitor,  10µF, 10V, 0603, ±10%, X7R"
			(at 97.79 127 0)
			(effects
				(font
					(size 1.27 1.27)
				)
				(hide yes)
			)
		)
		(property "MPN" "GRM188Z71A106KA73D"
			(at 115.57 111.76 0)
			(effects
				(font
					(size 1.27 1.27)
					(thickness 0.15)
				)
				(justify left bottom)
				(hide yes)
			)
		)
		(property "Val" "10u"
			(at 99.568 125.73 90)
			(effects
				(font
					(size 1.27 1.27)
					(thickness 0.15)
				)
				(justify right)
			)
		)
		(property "Voltage" "10V"
			(at 118.11 111.76 0)
			(effects
				(font
					(size 1.27 1.27)
					(thickness 0.15)
				)
				(justify left bottom)
				(hide yes)
			)
		)
		(property "Dielectric" "X7R"
			(at 120.65 111.76 0)
			(effects
				(font
					(size 1.27 1.27)
					(thickness 0.15)
				)
				(justify left bottom)
				(hide yes)
			)
		)
		(property "Manufacturer" "Murata"
			(at 123.19 111.76 0)
			(effects
				(font
					(size 1.27 1.27)
					(thickness 0.15)
				)
				(justify left bottom)
				(hide yes)
			)
		)
		(property "License" "Apache-2.0"
			(at 125.73 111.76 0)
			(effects
				(font
					(size 1.27 1.27)
					(thickness 0.15)
				)
				(justify left bottom)
				(hide yes)
			)
		)
		(property "Author" "Antmicro"
			(at 128.27 111.76 0)
			(effects
				(font
					(size 1.27 1.27)
					(thickness 0.15)
				)
				(justify left bottom)
				(hide yes)
			)
		)
		(pin "1"
		)
		(pin "2"
		)
		(instances
			(project "OCuLink to 10GbE adapter"
				(path ""
					(reference "C140")
					(unit 1)
				)
			)
			(project "thunderbolt-to-10gbe-adapter"
				(path ""
					(reference "C177")
					(unit 1)
				)
			)
		)
	)
	(symbol
		(lib_id "antmicroCapacitors0603:C_22u_16V_0603")
		(at 344.17 130.81 90)
		(unit 1)
		(exclude_from_sim no)
		(in_bom yes)
		(on_board yes)
		(dnp no)
		(fields_autoplaced yes)
		(property "Reference" "C239"
			(at 346.71 126.9936 90)
			(effects
				(font
					(size 1.27 1.27)
					(thickness 0.15)
				)
				(justify right)
			)
		)
		(property "Value" "C_22u_16V_0603"
			(at 354.33 110.49 0)
			(effects
				(font
					(size 1.27 1.27)
					(thickness 0.15)
				)
				(justify left bottom)
				(hide yes)
			)
		)
		(property "Footprint" "antmicro-footprints:C_0603_1608Metric_EIA"
			(at 356.87 110.49 0)
			(effects
				(font
					(size 1.27 1.27)
					(thickness 0.15)
				)
				(justify left bottom)
				(hide yes)
			)
		)
		(property "Datasheet" "https://product.samsungsem.com/mlcc/CL10A226MO7JZN.do"
			(at 359.41 110.49 0)
			(effects
				(font
					(size 1.27 1.27)
					(thickness 0.15)
				)
				(justify left bottom)
				(hide yes)
			)
		)
		(property "Description" "SMD Multilayer Ceramic Capacitor"
			(at 344.17 130.81 0)
			(effects
				(font
					(size 1.27 1.27)
				)
				(hide yes)
			)
		)
		(property "MPN" "CL10A226MO7JZNC"
			(at 361.95 110.49 0)
			(effects
				(font
					(size 1.27 1.27)
					(thickness 0.15)
				)
				(justify left bottom)
				(hide yes)
			)
		)
		(property "Manufacturer" "Samsung Electro-Mechanics"
			(at 364.49 110.49 0)
			(effects
				(font
					(size 1.27 1.27)
					(thickness 0.15)
				)
				(justify left bottom)
				(hide yes)
			)
		)
		(property "License" "Apache-2.0"
			(at 367.03 110.49 0)
			(effects
				(font
					(size 1.27 1.27)
					(thickness 0.15)
				)
				(justify left bottom)
				(hide yes)
			)
		)
		(property "Author" "Antmicro"
			(at 369.57 110.49 0)
			(effects
				(font
					(size 1.27 1.27)
					(thickness 0.15)
				)
				(justify left bottom)
				(hide yes)
			)
		)
		(property "Val" "22u"
			(at 346.71 129.5336 90)
			(effects
				(font
					(size 1.27 1.27)
					(thickness 0.15)
				)
				(justify right)
			)
		)
		(property "Voltage" "16V"
			(at 372.11 110.49 0)
			(effects
				(font
					(size 1.27 1.27)
				)
				(justify left bottom)
				(hide yes)
			)
		)
		(property "Dielectric" ""
			(at 374.65 110.49 0)
			(effects
				(font
					(size 1.27 1.27)
				)
				(justify left bottom)
				(hide yes)
			)
		)
		(pin "1"
		)
		(pin "2"
		)
		(instances
			(project "OCuLink to 10GbE adapter"
				(path ""
					(reference "C150")
					(unit 1)
				)
			)
			(project "thunderbolt-to-10gbe-adapter"
				(path ""
					(reference "C239")
					(unit 1)
				)
			)
		)
	)
	(symbol
		(lib_id "antmicropower:GND")
		(at 308.61 93.98 0)
		(unit 1)
		(exclude_from_sim no)
		(in_bom yes)
		(on_board yes)
		(dnp no)
		(property "Reference" "#PWR0305"
			(at 317.5 96.52 0)
			(effects
				(font
					(size 1.27 1.27)
					(thickness 0.15)
				)
				(justify left bottom)
				(hide yes)
			)
		)
		(property "Value" "GND"
			(at 308.61 97.79 0)
			(effects
				(font
					(size 1.27 1.27)
					(thickness 0.15)
				)
			)
		)
		(property "Footprint" ""
			(at 317.5 101.6 0)
			(effects
				(font
					(size 1.27 1.27)
					(thickness 0.15)
				)
				(justify left bottom)
				(hide yes)
			)
		)
		(property "Datasheet" ""
			(at 317.5 106.68 0)
			(effects
				(font
					(size 1.27 1.27)
					(thickness 0.15)
				)
				(justify left bottom)
				(hide yes)
			)
		)
		(property "Description" ""
			(at 308.61 93.98 0)
			(effects
				(font
					(size 1.27 1.27)
				)
				(hide yes)
			)
		)
		(property "Author" "Antmicro"
			(at 317.5 101.6 0)
			(effects
				(font
					(size 1.27 1.27)
					(thickness 0.15)
				)
				(justify left bottom)
				(hide yes)
			)
		)
		(property "License" "Apache-2.0"
			(at 317.5 104.14 0)
			(effects
				(font
					(size 1.27 1.27)
					(thickness 0.15)
				)
				(justify left bottom)
				(hide yes)
			)
		)
		(pin "1"
		)
		(instances
			(project "OCuLink to 10GbE adapter"
				(path ""
					(reference "#PWR0165")
					(unit 1)
				)
			)
			(project "thunderbolt-to-10gbe-adapter"
				(path ""
					(reference "#PWR0305")
					(unit 1)
				)
			)
		)
	)
	(symbol
		(lib_id "antmicropower:GND")
		(at 370.84 115.57 0)
		(unit 1)
		(exclude_from_sim no)
		(in_bom yes)
		(on_board yes)
		(dnp no)
		(property "Reference" "#PWR0339"
			(at 379.73 118.11 0)
			(effects
				(font
					(size 1.27 1.27)
					(thickness 0.15)
				)
				(justify left bottom)
				(hide yes)
			)
		)
		(property "Value" "GND"
			(at 370.84 119.38 0)
			(effects
				(font
					(size 1.27 1.27)
					(thickness 0.15)
				)
			)
		)
		(property "Footprint" ""
			(at 379.73 123.19 0)
			(effects
				(font
					(size 1.27 1.27)
					(thickness 0.15)
				)
				(justify left bottom)
				(hide yes)
			)
		)
		(property "Datasheet" ""
			(at 379.73 128.27 0)
			(effects
				(font
					(size 1.27 1.27)
					(thickness 0.15)
				)
				(justify left bottom)
				(hide yes)
			)
		)
		(property "Description" ""
			(at 370.84 115.57 0)
			(effects
				(font
					(size 1.27 1.27)
				)
				(hide yes)
			)
		)
		(property "Author" "Antmicro"
			(at 379.73 123.19 0)
			(effects
				(font
					(size 1.27 1.27)
					(thickness 0.15)
				)
				(justify left bottom)
				(hide yes)
			)
		)
		(property "License" "Apache-2.0"
			(at 379.73 125.73 0)
			(effects
				(font
					(size 1.27 1.27)
					(thickness 0.15)
				)
				(justify left bottom)
				(hide yes)
			)
		)
		(pin "1"
		)
		(instances
			(project "OCuLink to 10GbE adapter"
				(path ""
					(reference "#PWR0185")
					(unit 1)
				)
			)
			(project "thunderbolt-to-10gbe-adapter"
				(path ""
					(reference "#PWR0339")
					(unit 1)
				)
			)
		)
	)
	(symbol
		(lib_id "antmicropower:+1V8")
		(at 26.67 116.84 0)
		(unit 1)
		(exclude_from_sim no)
		(in_bom yes)
		(on_board yes)
		(dnp no)
		(property "Reference" "#PWR0219"
			(at 41.91 119.38 0)
			(effects
				(font
					(size 1.27 1.27)
					(thickness 0.15)
				)
				(justify left bottom)
				(hide yes)
			)
		)
		(property "Value" "+1V88"
			(at 26.67 113.03 0)
			(effects
				(font
					(size 1.27 1.27)
					(thickness 0.15)
				)
			)
		)
		(property "Footprint" ""
			(at 41.91 124.46 0)
			(effects
				(font
					(size 1.27 1.27)
					(thickness 0.15)
				)
				(justify left bottom)
				(hide yes)
			)
		)
		(property "Datasheet" ""
			(at 41.91 127 0)
			(effects
				(font
					(size 1.27 1.27)
					(thickness 0.15)
				)
				(justify left bottom)
				(hide yes)
			)
		)
		(property "Description" ""
			(at 26.67 116.84 0)
			(effects
				(font
					(size 1.27 1.27)
				)
				(hide yes)
			)
		)
		(property "Author" "Antmicro"
			(at 41.91 121.92 0)
			(effects
				(font
					(size 1.27 1.27)
					(thickness 0.15)
				)
				(justify left bottom)
				(hide yes)
			)
		)
		(property "License" "Apache-2.0"
			(at 41.91 124.46 0)
			(effects
				(font
					(size 1.27 1.27)
					(thickness 0.15)
				)
				(justify left bottom)
				(hide yes)
			)
		)
		(pin "1"
		)
		(instances
			(project "OCuLink to 10GbE adapter"
				(path ""
					(reference "#PWR0186")
					(unit 1)
				)
			)
			(project "thunderbolt-to-10gbe-adapter"
				(path ""
					(reference "#PWR0219")
					(unit 1)
				)
			)
		)
	)
	(symbol
		(lib_id "antmicropower:GND")
		(at 308.61 54.61 0)
		(unit 1)
		(exclude_from_sim no)
		(in_bom yes)
		(on_board yes)
		(dnp no)
		(property "Reference" "#PWR0303"
			(at 317.5 57.15 0)
			(effects
				(font
					(size 1.27 1.27)
					(thickness 0.15)
				)
				(justify left bottom)
				(hide yes)
			)
		)
		(property "Value" "GND"
			(at 308.61 58.42 0)
			(effects
				(font
					(size 1.27 1.27)
					(thickness 0.15)
				)
			)
		)
		(property "Footprint" ""
			(at 317.5 62.23 0)
			(effects
				(font
					(size 1.27 1.27)
					(thickness 0.15)
				)
				(justify left bottom)
				(hide yes)
			)
		)
		(property "Datasheet" ""
			(at 317.5 67.31 0)
			(effects
				(font
					(size 1.27 1.27)
					(thickness 0.15)
				)
				(justify left bottom)
				(hide yes)
			)
		)
		(property "Description" ""
			(at 308.61 54.61 0)
			(effects
				(font
					(size 1.27 1.27)
				)
				(hide yes)
			)
		)
		(property "Author" "Antmicro"
			(at 317.5 62.23 0)
			(effects
				(font
					(size 1.27 1.27)
					(thickness 0.15)
				)
				(justify left bottom)
				(hide yes)
			)
		)
		(property "License" "Apache-2.0"
			(at 317.5 64.77 0)
			(effects
				(font
					(size 1.27 1.27)
					(thickness 0.15)
				)
				(justify left bottom)
				(hide yes)
			)
		)
		(pin "1"
		)
		(instances
			(project "OCuLink to 10GbE adapter"
				(path ""
					(reference "#PWR0122")
					(unit 1)
				)
			)
			(project "thunderbolt-to-10gbe-adapter"
				(path ""
					(reference "#PWR0303")
					(unit 1)
				)
			)
		)
	)
	(symbol
		(lib_id "antmicropower:GND")
		(at 283.21 152.4 0)
		(unit 1)
		(exclude_from_sim no)
		(in_bom yes)
		(on_board yes)
		(dnp no)
		(property "Reference" "#PWR0295"
			(at 292.1 154.94 0)
			(effects
				(font
					(size 1.27 1.27)
					(thickness 0.15)
				)
				(justify left bottom)
				(hide yes)
			)
		)
		(property "Value" "GND"
			(at 283.21 156.21 0)
			(effects
				(font
					(size 1.27 1.27)
					(thickness 0.15)
				)
			)
		)
		(property "Footprint" ""
			(at 292.1 160.02 0)
			(effects
				(font
					(size 1.27 1.27)
					(thickness 0.15)
				)
				(justify left bottom)
				(hide yes)
			)
		)
		(property "Datasheet" ""
			(at 292.1 165.1 0)
			(effects
				(font
					(size 1.27 1.27)
					(thickness 0.15)
				)
				(justify left bottom)
				(hide yes)
			)
		)
		(property "Description" ""
			(at 283.21 152.4 0)
			(effects
				(font
					(size 1.27 1.27)
				)
				(hide yes)
			)
		)
		(property "Author" "Antmicro"
			(at 292.1 160.02 0)
			(effects
				(font
					(size 1.27 1.27)
					(thickness 0.15)
				)
				(justify left bottom)
				(hide yes)
			)
		)
		(property "License" "Apache-2.0"
			(at 292.1 162.56 0)
			(effects
				(font
					(size 1.27 1.27)
					(thickness 0.15)
				)
				(justify left bottom)
				(hide yes)
			)
		)
		(pin "1"
		)
		(instances
			(project "OCuLink to 10GbE adapter"
				(path ""
					(reference "#PWR0207")
					(unit 1)
				)
			)
			(project "thunderbolt-to-10gbe-adapter"
				(path ""
					(reference "#PWR0295")
					(unit 1)
				)
			)
		)
	)
	(symbol
		(lib_id "antmicropower:GND")
		(at 292.1 152.4 0)
		(unit 1)
		(exclude_from_sim no)
		(in_bom yes)
		(on_board yes)
		(dnp no)
		(property "Reference" "#PWR0296"
			(at 300.99 154.94 0)
			(effects
				(font
					(size 1.27 1.27)
					(thickness 0.15)
				)
				(justify left bottom)
				(hide yes)
			)
		)
		(property "Value" "GND"
			(at 292.1 156.21 0)
			(effects
				(font
					(size 1.27 1.27)
					(thickness 0.15)
				)
			)
		)
		(property "Footprint" ""
			(at 300.99 160.02 0)
			(effects
				(font
					(size 1.27 1.27)
					(thickness 0.15)
				)
				(justify left bottom)
				(hide yes)
			)
		)
		(property "Datasheet" ""
			(at 300.99 165.1 0)
			(effects
				(font
					(size 1.27 1.27)
					(thickness 0.15)
				)
				(justify left bottom)
				(hide yes)
			)
		)
		(property "Description" ""
			(at 292.1 152.4 0)
			(effects
				(font
					(size 1.27 1.27)
				)
				(hide yes)
			)
		)
		(property "Author" "Antmicro"
			(at 300.99 160.02 0)
			(effects
				(font
					(size 1.27 1.27)
					(thickness 0.15)
				)
				(justify left bottom)
				(hide yes)
			)
		)
		(property "License" "Apache-2.0"
			(at 300.99 162.56 0)
			(effects
				(font
					(size 1.27 1.27)
					(thickness 0.15)
				)
				(justify left bottom)
				(hide yes)
			)
		)
		(pin "1"
		)
		(instances
			(project "OCuLink to 10GbE adapter"
				(path ""
					(reference "#PWR0208")
					(unit 1)
				)
			)
			(project "thunderbolt-to-10gbe-adapter"
				(path ""
					(reference "#PWR0296")
					(unit 1)
				)
			)
		)
	)
	(symbol
		(lib_id "antmicropower:+1V0")
		(at 26.67 196.85 0)
		(unit 1)
		(exclude_from_sim no)
		(in_bom yes)
		(on_board yes)
		(dnp no)
		(property "Reference" "#PWR0223"
			(at 26.67 200.66 0)
			(effects
				(font
					(size 1.27 1.27)
				)
				(hide yes)
			)
		)
		(property "Value" "+1V0"
			(at 26.67 192.786 0)
			(effects
				(font
					(size 1.27 1.27)
				)
			)
		)
		(property "Footprint" ""
			(at 26.67 196.85 0)
			(effects
				(font
					(size 1.27 1.27)
				)
				(hide yes)
			)
		)
		(property "Datasheet" ""
			(at 26.67 196.85 0)
			(effects
				(font
					(size 1.27 1.27)
				)
				(hide yes)
			)
		)
		(property "Description" ""
			(at 26.67 196.85 0)
			(effects
				(font
					(size 1.27 1.27)
				)
				(hide yes)
			)
		)
		(pin "1"
		)
		(instances
			(project "OCuLink to 10GbE adapter"
				(path ""
					(reference "#PWR0231")
					(unit 1)
				)
			)
			(project "thunderbolt-to-10gbe-adapter"
				(path ""
					(reference "#PWR0223")
					(unit 1)
				)
			)
		)
	)
	(symbol
		(lib_id "antmicroCapacitors0402:C_1u_25V_0402")
		(at 326.39 91.44 90)
		(unit 1)
		(exclude_from_sim no)
		(in_bom yes)
		(on_board yes)
		(dnp no)
		(property "Reference" "C229"
			(at 328.422 87.63 90)
			(effects
				(font
					(size 1.27 1.27)
					(thickness 0.15)
				)
				(justify right)
			)
		)
		(property "Value" "C_1u_25V_0402"
			(at 336.55 71.12 0)
			(effects
				(font
					(size 1.27 1.27)
					(thickness 0.15)
				)
				(justify left bottom)
				(hide yes)
			)
		)
		(property "Footprint" "antmicro-footprints:C_0402_1005Metric"
			(at 339.09 71.12 0)
			(effects
				(font
					(size 1.27 1.27)
					(thickness 0.15)
				)
				(justify left bottom)
				(hide yes)
			)
		)
		(property "Datasheet" "https://www.murata.com/products/productdetail?partno=GRM155R61E105KE11%23"
			(at 341.63 71.12 0)
			(effects
				(font
					(size 1.27 1.27)
					(thickness 0.15)
				)
				(justify left bottom)
				(hide yes)
			)
		)
		(property "Description" "SMD Multilayer Ceramic Capacitor, 1 µF, 25 V, 0402 [1005 Metric], ± 10%, X5R, GRM Series"
			(at 326.39 91.44 0)
			(effects
				(font
					(size 1.27 1.27)
				)
				(hide yes)
			)
		)
		(property "MPN" "GRM155R61E105KE11J"
			(at 344.17 71.12 0)
			(effects
				(font
					(size 1.27 1.27)
					(thickness 0.15)
				)
				(justify left bottom)
				(hide yes)
			)
		)
		(property "Manufacturer" "Murata"
			(at 346.71 71.12 0)
			(effects
				(font
					(size 1.27 1.27)
					(thickness 0.15)
				)
				(justify left bottom)
				(hide yes)
			)
		)
		(property "License" "Apache-2.0"
			(at 349.25 71.12 0)
			(effects
				(font
					(size 1.27 1.27)
					(thickness 0.15)
				)
				(justify left bottom)
				(hide yes)
			)
		)
		(property "Author" "Antmicro"
			(at 351.79 71.12 0)
			(effects
				(font
					(size 1.27 1.27)
					(thickness 0.15)
				)
				(justify left bottom)
				(hide yes)
			)
		)
		(property "Val" "1u"
			(at 328.422 90.17 90)
			(effects
				(font
					(size 1.27 1.27)
					(thickness 0.15)
				)
				(justify right)
			)
		)
		(property "Voltage" "25V"
			(at 354.33 71.12 0)
			(effects
				(font
					(size 1.27 1.27)
				)
				(justify left bottom)
				(hide yes)
			)
		)
		(property "Dielectric" "X5R"
			(at 356.87 71.12 0)
			(effects
				(font
					(size 1.27 1.27)
				)
				(justify left bottom)
				(hide yes)
			)
		)
		(pin "2"
		)
		(pin "1"
		)
		(instances
			(project "OCuLink to 10GbE adapter"
				(path ""
					(reference "C120")
					(unit 1)
				)
			)
			(project "thunderbolt-to-10gbe-adapter"
				(path ""
					(reference "C229")
					(unit 1)
				)
			)
		)
	)
	(symbol
		(lib_id "antmicroCapacitors0402:C_100n_0402")
		(at 74.93 260.35 90)
		(unit 1)
		(exclude_from_sim no)
		(in_bom yes)
		(on_board yes)
		(dnp no)
		(property "Reference" "C160"
			(at 76.962 256.54 90)
			(effects
				(font
					(size 1.27 1.27)
					(thickness 0.15)
				)
				(justify right)
			)
		)
		(property "Value" "C_100n_0402"
			(at 97.79 245.11 0)
			(effects
				(font
					(size 1.27 1.27)
					(thickness 0.15)
				)
				(justify left bottom)
				(hide yes)
			)
		)
		(property "Footprint" "antmicro-footprints:C_0402_1005Metric"
			(at 100.33 245.11 0)
			(effects
				(font
					(size 1.27 1.27)
					(thickness 0.15)
				)
				(justify left bottom)
				(hide yes)
			)
		)
		(property "Datasheet" "https://www.murata.com/products/productdetail?partno=GRM155R61H104KE14%23"
			(at 102.87 245.11 0)
			(effects
				(font
					(size 1.27 1.27)
					(thickness 0.15)
				)
				(justify left bottom)
				(hide yes)
			)
		)
		(property "Description" "SMD Multilayer Ceramic Capacitor, 0.1 µF, 50 V, 0402 [1005 Metric], ± 10%, X5R, GRM Series"
			(at 74.93 260.35 0)
			(effects
				(font
					(size 1.27 1.27)
				)
				(hide yes)
			)
		)
		(property "MPN" "GRM155R61H104KE14D"
			(at 105.41 245.11 0)
			(effects
				(font
					(size 1.27 1.27)
					(thickness 0.15)
				)
				(justify left bottom)
				(hide yes)
			)
		)
		(property "Val" "100n"
			(at 76.962 259.08 90)
			(effects
				(font
					(size 1.27 1.27)
					(thickness 0.15)
				)
				(justify right)
			)
		)
		(property "Voltage" "50V"
			(at 85.09 245.11 0)
			(effects
				(font
					(size 1.27 1.27)
					(thickness 0.15)
				)
				(justify left bottom)
				(hide yes)
			)
		)
		(property "Dielectric" "X5R"
			(at 87.63 245.11 0)
			(effects
				(font
					(size 1.27 1.27)
					(thickness 0.15)
				)
				(justify left bottom)
				(hide yes)
			)
		)
		(property "Manufacturer" "Murata"
			(at 90.17 245.11 0)
			(effects
				(font
					(size 1.27 1.27)
					(thickness 0.15)
				)
				(justify left bottom)
				(hide yes)
			)
		)
		(property "License" "Apache-2.0"
			(at 92.71 245.11 0)
			(effects
				(font
					(size 1.27 1.27)
					(thickness 0.15)
				)
				(justify left bottom)
				(hide yes)
			)
		)
		(property "Author" "Antmicro"
			(at 95.25 245.11 0)
			(effects
				(font
					(size 1.27 1.27)
					(thickness 0.15)
				)
				(justify left bottom)
				(hide yes)
			)
		)
		(pin "2"
		)
		(pin "1"
		)
		(instances
			(project "OCuLink to 10GbE adapter"
				(path ""
					(reference "C188")
					(unit 1)
				)
			)
			(project "thunderbolt-to-10gbe-adapter"
				(path ""
					(reference "C160")
					(unit 1)
				)
			)
		)
	)
	(symbol
		(lib_id "antmicroCapacitors0402:C_1u_25V_0402")
		(at 317.5 91.44 90)
		(unit 1)
		(exclude_from_sim no)
		(in_bom yes)
		(on_board yes)
		(dnp no)
		(property "Reference" "C224"
			(at 319.532 87.63 90)
			(effects
				(font
					(size 1.27 1.27)
					(thickness 0.15)
				)
				(justify right)
			)
		)
		(property "Value" "C_1u_25V_0402"
			(at 327.66 71.12 0)
			(effects
				(font
					(size 1.27 1.27)
					(thickness 0.15)
				)
				(justify left bottom)
				(hide yes)
			)
		)
		(property "Footprint" "antmicro-footprints:C_0402_1005Metric"
			(at 330.2 71.12 0)
			(effects
				(font
					(size 1.27 1.27)
					(thickness 0.15)
				)
				(justify left bottom)
				(hide yes)
			)
		)
		(property "Datasheet" "https://www.murata.com/products/productdetail?partno=GRM155R61E105KE11%23"
			(at 332.74 71.12 0)
			(effects
				(font
					(size 1.27 1.27)
					(thickness 0.15)
				)
				(justify left bottom)
				(hide yes)
			)
		)
		(property "Description" "SMD Multilayer Ceramic Capacitor, 1 µF, 25 V, 0402 [1005 Metric], ± 10%, X5R, GRM Series"
			(at 317.5 91.44 0)
			(effects
				(font
					(size 1.27 1.27)
				)
				(hide yes)
			)
		)
		(property "MPN" "GRM155R61E105KE11J"
			(at 335.28 71.12 0)
			(effects
				(font
					(size 1.27 1.27)
					(thickness 0.15)
				)
				(justify left bottom)
				(hide yes)
			)
		)
		(property "Manufacturer" "Murata"
			(at 337.82 71.12 0)
			(effects
				(font
					(size 1.27 1.27)
					(thickness 0.15)
				)
				(justify left bottom)
				(hide yes)
			)
		)
		(property "License" "Apache-2.0"
			(at 340.36 71.12 0)
			(effects
				(font
					(size 1.27 1.27)
					(thickness 0.15)
				)
				(justify left bottom)
				(hide yes)
			)
		)
		(property "Author" "Antmicro"
			(at 342.9 71.12 0)
			(effects
				(font
					(size 1.27 1.27)
					(thickness 0.15)
				)
				(justify left bottom)
				(hide yes)
			)
		)
		(property "Val" "1u"
			(at 319.532 90.17 90)
			(effects
				(font
					(size 1.27 1.27)
					(thickness 0.15)
				)
				(justify right)
			)
		)
		(property "Voltage" "25V"
			(at 345.44 71.12 0)
			(effects
				(font
					(size 1.27 1.27)
				)
				(justify left bottom)
				(hide yes)
			)
		)
		(property "Dielectric" "X5R"
			(at 347.98 71.12 0)
			(effects
				(font
					(size 1.27 1.27)
				)
				(justify left bottom)
				(hide yes)
			)
		)
		(pin "2"
		)
		(pin "1"
		)
		(instances
			(project "OCuLink to 10GbE adapter"
				(path ""
					(reference "C119")
					(unit 1)
				)
			)
			(project "thunderbolt-to-10gbe-adapter"
				(path ""
					(reference "C224")
					(unit 1)
				)
			)
		)
	)
	(symbol
		(lib_id "antmicropower:GND")
		(at 308.61 76.2 0)
		(unit 1)
		(exclude_from_sim no)
		(in_bom yes)
		(on_board yes)
		(dnp no)
		(property "Reference" "#PWR0304"
			(at 317.5 78.74 0)
			(effects
				(font
					(size 1.27 1.27)
					(thickness 0.15)
				)
				(justify left bottom)
				(hide yes)
			)
		)
		(property "Value" "GND"
			(at 308.61 80.01 0)
			(effects
				(font
					(size 1.27 1.27)
					(thickness 0.15)
				)
			)
		)
		(property "Footprint" ""
			(at 317.5 83.82 0)
			(effects
				(font
					(size 1.27 1.27)
					(thickness 0.15)
				)
				(justify left bottom)
				(hide yes)
			)
		)
		(property "Datasheet" ""
			(at 317.5 88.9 0)
			(effects
				(font
					(size 1.27 1.27)
					(thickness 0.15)
				)
				(justify left bottom)
				(hide yes)
			)
		)
		(property "Description" ""
			(at 308.61 76.2 0)
			(effects
				(font
					(size 1.27 1.27)
				)
				(hide yes)
			)
		)
		(property "Author" "Antmicro"
			(at 317.5 83.82 0)
			(effects
				(font
					(size 1.27 1.27)
					(thickness 0.15)
				)
				(justify left bottom)
				(hide yes)
			)
		)
		(property "License" "Apache-2.0"
			(at 317.5 86.36 0)
			(effects
				(font
					(size 1.27 1.27)
					(thickness 0.15)
				)
				(justify left bottom)
				(hide yes)
			)
		)
		(pin "1"
		)
		(instances
			(project "OCuLink to 10GbE adapter"
				(path ""
					(reference "#PWR0140")
					(unit 1)
				)
			)
			(project "thunderbolt-to-10gbe-adapter"
				(path ""
					(reference "#PWR0304")
					(unit 1)
				)
			)
		)
	)
	(symbol
		(lib_id "antmicroFerriteBeadsandChips:FB_33Z_3A_Murata-BLM18PG_0603")
		(at 81.28 119.38 0)
		(unit 1)
		(exclude_from_sim no)
		(in_bom yes)
		(on_board yes)
		(dnp no)
		(fields_autoplaced yes)
		(property "Reference" "FB5"
			(at 83.7819 113.03 0)
			(effects
				(font
					(size 1.27 1.27)
					(thickness 0.15)
				)
			)
		)
		(property "Value" "FB_33Z_3A_Murata-BLM18PG_0603"
			(at 95.25 121.92 0)
			(effects
				(font
					(size 1.27 1.27)
					(thickness 0.15)
				)
				(justify left bottom)
				(hide yes)
			)
		)
		(property "Footprint" "antmicro-footprints:FB_0603_1608Metric"
			(at 95.25 127 0)
			(effects
				(font
					(size 1.27 1.27)
					(thickness 0.15)
				)
				(justify left bottom)
				(hide yes)
			)
		)
		(property "Datasheet" "https://www.murata.com/products/productdata/8796737273886/QNFA9101.pdf?1649080818000"
			(at 95.25 129.54 0)
			(effects
				(font
					(size 1.27 1.27)
					(thickness 0.15)
				)
				(justify left bottom)
				(hide yes)
			)
		)
		(property "Description" "Ferrite Bead, 0603 [1608 Metric], 33 ohm, 3 A, BLM18PG, 0.025 ohm, ± 25%, DC power line"
			(at 81.28 119.38 0)
			(effects
				(font
					(size 1.27 1.27)
				)
				(hide yes)
			)
		)
		(property "Val" "33Z/3A"
			(at 83.7819 115.57 0)
			(effects
				(font
					(size 1.27 1.27)
				)
			)
		)
		(property "MPN" "BLM18PG330SH1D"
			(at 95.25 132.08 0)
			(effects
				(font
					(size 1.27 1.27)
					(thickness 0.15)
				)
				(justify left bottom)
				(hide yes)
			)
		)
		(property "Manufacturer" "Murata"
			(at 95.25 134.62 0)
			(effects
				(font
					(size 1.27 1.27)
					(thickness 0.15)
				)
				(justify left bottom)
				(hide yes)
			)
		)
		(property "Current" ""
			(at 101.6 142.24 0)
			(effects
				(font
					(size 1.27 1.27)
					(thickness 0.15)
				)
				(justify left bottom)
				(hide yes)
			)
		)
		(property "Author" "Antmicro"
			(at 95.25 137.16 0)
			(effects
				(font
					(size 1.27 1.27)
					(thickness 0.15)
				)
				(justify left bottom)
				(hide yes)
			)
		)
		(property "License" "Apache-2.0"
			(at 95.25 139.7 0)
			(effects
				(font
					(size 1.27 1.27)
					(thickness 0.15)
				)
				(justify left bottom)
				(hide yes)
			)
		)
		(pin "2"
		)
		(pin "1"
		)
		(instances
			(project "OCuLink to 10GbE adapter"
				(path ""
					(reference "FB4")
					(unit 1)
				)
			)
			(project "thunderbolt-to-10gbe-adapter"
				(path ""
					(reference "FB5")
					(unit 1)
				)
			)
		)
	)
	(symbol
		(lib_id "antmicroCapacitors0402:C_1u_25V_0402")
		(at 361.95 52.07 90)
		(unit 1)
		(exclude_from_sim no)
		(in_bom yes)
		(on_board yes)
		(dnp no)
		(property "Reference" "C245"
			(at 363.982 48.26 90)
			(effects
				(font
					(size 1.27 1.27)
					(thickness 0.15)
				)
				(justify right)
			)
		)
		(property "Value" "C_1u_25V_0402"
			(at 372.11 31.75 0)
			(effects
				(font
					(size 1.27 1.27)
					(thickness 0.15)
				)
				(justify left bottom)
				(hide yes)
			)
		)
		(property "Footprint" "antmicro-footprints:C_0402_1005Metric"
			(at 374.65 31.75 0)
			(effects
				(font
					(size 1.27 1.27)
					(thickness 0.15)
				)
				(justify left bottom)
				(hide yes)
			)
		)
		(property "Datasheet" "https://www.murata.com/products/productdetail?partno=GRM155R61E105KE11%23"
			(at 377.19 31.75 0)
			(effects
				(font
					(size 1.27 1.27)
					(thickness 0.15)
				)
				(justify left bottom)
				(hide yes)
			)
		)
		(property "Description" "SMD Multilayer Ceramic Capacitor, 1 µF, 25 V, 0402 [1005 Metric], ± 10%, X5R, GRM Series"
			(at 361.95 52.07 0)
			(effects
				(font
					(size 1.27 1.27)
				)
				(hide yes)
			)
		)
		(property "MPN" "GRM155R61E105KE11J"
			(at 379.73 31.75 0)
			(effects
				(font
					(size 1.27 1.27)
					(thickness 0.15)
				)
				(justify left bottom)
				(hide yes)
			)
		)
		(property "Manufacturer" "Murata"
			(at 382.27 31.75 0)
			(effects
				(font
					(size 1.27 1.27)
					(thickness 0.15)
				)
				(justify left bottom)
				(hide yes)
			)
		)
		(property "License" "Apache-2.0"
			(at 384.81 31.75 0)
			(effects
				(font
					(size 1.27 1.27)
					(thickness 0.15)
				)
				(justify left bottom)
				(hide yes)
			)
		)
		(property "Author" "Antmicro"
			(at 387.35 31.75 0)
			(effects
				(font
					(size 1.27 1.27)
					(thickness 0.15)
				)
				(justify left bottom)
				(hide yes)
			)
		)
		(property "Val" "1u"
			(at 363.982 50.8 90)
			(effects
				(font
					(size 1.27 1.27)
					(thickness 0.15)
				)
				(justify right)
			)
		)
		(property "Voltage" "25V"
			(at 389.89 31.75 0)
			(effects
				(font
					(size 1.27 1.27)
				)
				(justify left bottom)
				(hide yes)
			)
		)
		(property "Dielectric" "X5R"
			(at 392.43 31.75 0)
			(effects
				(font
					(size 1.27 1.27)
				)
				(justify left bottom)
				(hide yes)
			)
		)
		(pin "2"
		)
		(pin "1"
		)
		(instances
			(project "OCuLink to 10GbE adapter"
				(path ""
					(reference "C94")
					(unit 1)
				)
			)
			(project "thunderbolt-to-10gbe-adapter"
				(path ""
					(reference "C245")
					(unit 1)
				)
			)
		)
	)
	(symbol
		(lib_id "antmicropower:GND")
		(at 317.5 93.98 0)
		(unit 1)
		(exclude_from_sim no)
		(in_bom yes)
		(on_board yes)
		(dnp no)
		(property "Reference" "#PWR0310"
			(at 326.39 96.52 0)
			(effects
				(font
					(size 1.27 1.27)
					(thickness 0.15)
				)
				(justify left bottom)
				(hide yes)
			)
		)
		(property "Value" "GND"
			(at 317.5 97.79 0)
			(effects
				(font
					(size 1.27 1.27)
					(thickness 0.15)
				)
			)
		)
		(property "Footprint" ""
			(at 326.39 101.6 0)
			(effects
				(font
					(size 1.27 1.27)
					(thickness 0.15)
				)
				(justify left bottom)
				(hide yes)
			)
		)
		(property "Datasheet" ""
			(at 326.39 106.68 0)
			(effects
				(font
					(size 1.27 1.27)
					(thickness 0.15)
				)
				(justify left bottom)
				(hide yes)
			)
		)
		(property "Description" ""
			(at 317.5 93.98 0)
			(effects
				(font
					(size 1.27 1.27)
				)
				(hide yes)
			)
		)
		(property "Author" "Antmicro"
			(at 326.39 101.6 0)
			(effects
				(font
					(size 1.27 1.27)
					(thickness 0.15)
				)
				(justify left bottom)
				(hide yes)
			)
		)
		(property "License" "Apache-2.0"
			(at 326.39 104.14 0)
			(effects
				(font
					(size 1.27 1.27)
					(thickness 0.15)
				)
				(justify left bottom)
				(hide yes)
			)
		)
		(pin "1"
		)
		(instances
			(project "OCuLink to 10GbE adapter"
				(path ""
					(reference "#PWR0166")
					(unit 1)
				)
			)
			(project "thunderbolt-to-10gbe-adapter"
				(path ""
					(reference "#PWR0310")
					(unit 1)
				)
			)
		)
	)
	(symbol
		(lib_id "antmicroCapacitors0402:C_1u_25V_0402")
		(at 308.61 91.44 90)
		(unit 1)
		(exclude_from_sim no)
		(in_bom yes)
		(on_board yes)
		(dnp no)
		(property "Reference" "C219"
			(at 310.642 87.63 90)
			(effects
				(font
					(size 1.27 1.27)
					(thickness 0.15)
				)
				(justify right)
			)
		)
		(property "Value" "C_1u_25V_0402"
			(at 318.77 71.12 0)
			(effects
				(font
					(size 1.27 1.27)
					(thickness 0.15)
				)
				(justify left bottom)
				(hide yes)
			)
		)
		(property "Footprint" "antmicro-footprints:C_0402_1005Metric"
			(at 321.31 71.12 0)
			(effects
				(font
					(size 1.27 1.27)
					(thickness 0.15)
				)
				(justify left bottom)
				(hide yes)
			)
		)
		(property "Datasheet" "https://www.murata.com/products/productdetail?partno=GRM155R61E105KE11%23"
			(at 323.85 71.12 0)
			(effects
				(font
					(size 1.27 1.27)
					(thickness 0.15)
				)
				(justify left bottom)
				(hide yes)
			)
		)
		(property "Description" "SMD Multilayer Ceramic Capacitor, 1 µF, 25 V, 0402 [1005 Metric], ± 10%, X5R, GRM Series"
			(at 308.61 91.44 0)
			(effects
				(font
					(size 1.27 1.27)
				)
				(hide yes)
			)
		)
		(property "MPN" "GRM155R61E105KE11J"
			(at 326.39 71.12 0)
			(effects
				(font
					(size 1.27 1.27)
					(thickness 0.15)
				)
				(justify left bottom)
				(hide yes)
			)
		)
		(property "Manufacturer" "Murata"
			(at 328.93 71.12 0)
			(effects
				(font
					(size 1.27 1.27)
					(thickness 0.15)
				)
				(justify left bottom)
				(hide yes)
			)
		)
		(property "License" "Apache-2.0"
			(at 331.47 71.12 0)
			(effects
				(font
					(size 1.27 1.27)
					(thickness 0.15)
				)
				(justify left bottom)
				(hide yes)
			)
		)
		(property "Author" "Antmicro"
			(at 334.01 71.12 0)
			(effects
				(font
					(size 1.27 1.27)
					(thickness 0.15)
				)
				(justify left bottom)
				(hide yes)
			)
		)
		(property "Val" "1u"
			(at 310.642 90.17 90)
			(effects
				(font
					(size 1.27 1.27)
					(thickness 0.15)
				)
				(justify right)
			)
		)
		(property "Voltage" "25V"
			(at 336.55 71.12 0)
			(effects
				(font
					(size 1.27 1.27)
				)
				(justify left bottom)
				(hide yes)
			)
		)
		(property "Dielectric" "X5R"
			(at 339.09 71.12 0)
			(effects
				(font
					(size 1.27 1.27)
				)
				(justify left bottom)
				(hide yes)
			)
		)
		(pin "2"
		)
		(pin "1"
		)
		(instances
			(project "OCuLink to 10GbE adapter"
				(path ""
					(reference "C118")
					(unit 1)
				)
			)
			(project "thunderbolt-to-10gbe-adapter"
				(path ""
					(reference "C219")
					(unit 1)
				)
			)
		)
	)
	(symbol
		(lib_id "antmicropower:GND")
		(at 124.46 182.88 0)
		(unit 1)
		(exclude_from_sim no)
		(in_bom yes)
		(on_board yes)
		(dnp no)
		(property "Reference" "#PWR0259"
			(at 133.35 185.42 0)
			(effects
				(font
					(size 1.27 1.27)
					(thickness 0.15)
				)
				(justify left bottom)
				(hide yes)
			)
		)
		(property "Value" "GND"
			(at 124.46 186.69 0)
			(effects
				(font
					(size 1.27 1.27)
					(thickness 0.15)
				)
			)
		)
		(property "Footprint" ""
			(at 133.35 190.5 0)
			(effects
				(font
					(size 1.27 1.27)
					(thickness 0.15)
				)
				(justify left bottom)
				(hide yes)
			)
		)
		(property "Datasheet" ""
			(at 133.35 195.58 0)
			(effects
				(font
					(size 1.27 1.27)
					(thickness 0.15)
				)
				(justify left bottom)
				(hide yes)
			)
		)
		(property "Description" ""
			(at 124.46 182.88 0)
			(effects
				(font
					(size 1.27 1.27)
				)
				(hide yes)
			)
		)
		(property "Author" "Antmicro"
			(at 133.35 190.5 0)
			(effects
				(font
					(size 1.27 1.27)
					(thickness 0.15)
				)
				(justify left bottom)
				(hide yes)
			)
		)
		(property "License" "Apache-2.0"
			(at 133.35 193.04 0)
			(effects
				(font
					(size 1.27 1.27)
					(thickness 0.15)
				)
				(justify left bottom)
				(hide yes)
			)
		)
		(pin "1"
		)
		(instances
			(project "OCuLink to 10GbE adapter"
				(path ""
					(reference "#PWR0227")
					(unit 1)
				)
			)
			(project "thunderbolt-to-10gbe-adapter"
				(path ""
					(reference "#PWR0259")
					(unit 1)
				)
			)
		)
	)
	(symbol
		(lib_id "antmicroCapacitors0402:C_1u_25V_0402")
		(at 370.84 52.07 90)
		(unit 1)
		(exclude_from_sim no)
		(in_bom yes)
		(on_board yes)
		(dnp no)
		(property "Reference" "C250"
			(at 372.872 48.26 90)
			(effects
				(font
					(size 1.27 1.27)
					(thickness 0.15)
				)
				(justify right)
			)
		)
		(property "Value" "C_1u_25V_0402"
			(at 381 31.75 0)
			(effects
				(font
					(size 1.27 1.27)
					(thickness 0.15)
				)
				(justify left bottom)
				(hide yes)
			)
		)
		(property "Footprint" "antmicro-footprints:C_0402_1005Metric"
			(at 383.54 31.75 0)
			(effects
				(font
					(size 1.27 1.27)
					(thickness 0.15)
				)
				(justify left bottom)
				(hide yes)
			)
		)
		(property "Datasheet" "https://www.murata.com/products/productdetail?partno=GRM155R61E105KE11%23"
			(at 386.08 31.75 0)
			(effects
				(font
					(size 1.27 1.27)
					(thickness 0.15)
				)
				(justify left bottom)
				(hide yes)
			)
		)
		(property "Description" "SMD Multilayer Ceramic Capacitor, 1 µF, 25 V, 0402 [1005 Metric], ± 10%, X5R, GRM Series"
			(at 370.84 52.07 0)
			(effects
				(font
					(size 1.27 1.27)
				)
				(hide yes)
			)
		)
		(property "MPN" "GRM155R61E105KE11J"
			(at 388.62 31.75 0)
			(effects
				(font
					(size 1.27 1.27)
					(thickness 0.15)
				)
				(justify left bottom)
				(hide yes)
			)
		)
		(property "Manufacturer" "Murata"
			(at 391.16 31.75 0)
			(effects
				(font
					(size 1.27 1.27)
					(thickness 0.15)
				)
				(justify left bottom)
				(hide yes)
			)
		)
		(property "License" "Apache-2.0"
			(at 393.7 31.75 0)
			(effects
				(font
					(size 1.27 1.27)
					(thickness 0.15)
				)
				(justify left bottom)
				(hide yes)
			)
		)
		(property "Author" "Antmicro"
			(at 396.24 31.75 0)
			(effects
				(font
					(size 1.27 1.27)
					(thickness 0.15)
				)
				(justify left bottom)
				(hide yes)
			)
		)
		(property "Val" "1u"
			(at 372.872 50.8 90)
			(effects
				(font
					(size 1.27 1.27)
					(thickness 0.15)
				)
				(justify right)
			)
		)
		(property "Voltage" "25V"
			(at 398.78 31.75 0)
			(effects
				(font
					(size 1.27 1.27)
				)
				(justify left bottom)
				(hide yes)
			)
		)
		(property "Dielectric" "X5R"
			(at 401.32 31.75 0)
			(effects
				(font
					(size 1.27 1.27)
				)
				(justify left bottom)
				(hide yes)
			)
		)
		(pin "2"
		)
		(pin "1"
		)
		(instances
			(project "OCuLink to 10GbE adapter"
				(path ""
					(reference "C95")
					(unit 1)
				)
			)
			(project "thunderbolt-to-10gbe-adapter"
				(path ""
					(reference "C250")
					(unit 1)
				)
			)
		)
	)
	(symbol
		(lib_id "antmicropower:GND")
		(at 142.24 156.21 0)
		(unit 1)
		(exclude_from_sim no)
		(in_bom yes)
		(on_board yes)
		(dnp no)
		(property "Reference" "#PWR0270"
			(at 151.13 158.75 0)
			(effects
				(font
					(size 1.27 1.27)
					(thickness 0.15)
				)
				(justify left bottom)
				(hide yes)
			)
		)
		(property "Value" "GND"
			(at 142.24 160.02 0)
			(effects
				(font
					(size 1.27 1.27)
					(thickness 0.15)
				)
			)
		)
		(property "Footprint" ""
			(at 151.13 163.83 0)
			(effects
				(font
					(size 1.27 1.27)
					(thickness 0.15)
				)
				(justify left bottom)
				(hide yes)
			)
		)
		(property "Datasheet" ""
			(at 151.13 168.91 0)
			(effects
				(font
					(size 1.27 1.27)
					(thickness 0.15)
				)
				(justify left bottom)
				(hide yes)
			)
		)
		(property "Description" ""
			(at 142.24 156.21 0)
			(effects
				(font
					(size 1.27 1.27)
				)
				(hide yes)
			)
		)
		(property "Author" "Antmicro"
			(at 151.13 163.83 0)
			(effects
				(font
					(size 1.27 1.27)
					(thickness 0.15)
				)
				(justify left bottom)
				(hide yes)
			)
		)
		(property "License" "Apache-2.0"
			(at 151.13 166.37 0)
			(effects
				(font
					(size 1.27 1.27)
					(thickness 0.15)
				)
				(justify left bottom)
				(hide yes)
			)
		)
		(pin "1"
		)
		(instances
			(project "OCuLink to 10GbE adapter"
				(path ""
					(reference "#PWR0219")
					(unit 1)
				)
			)
			(project "thunderbolt-to-10gbe-adapter"
				(path ""
					(reference "#PWR0270")
					(unit 1)
				)
			)
		)
	)
	(symbol
		(lib_id "antmicropower:+1V0")
		(at 26.67 170.18 0)
		(unit 1)
		(exclude_from_sim no)
		(in_bom yes)
		(on_board yes)
		(dnp no)
		(property "Reference" "#PWR0222"
			(at 26.67 173.99 0)
			(effects
				(font
					(size 1.27 1.27)
				)
				(hide yes)
			)
		)
		(property "Value" "+1V0"
			(at 26.67 166.116 0)
			(effects
				(font
					(size 1.27 1.27)
				)
			)
		)
		(property "Footprint" ""
			(at 26.67 170.18 0)
			(effects
				(font
					(size 1.27 1.27)
				)
				(hide yes)
			)
		)
		(property "Datasheet" ""
			(at 26.67 170.18 0)
			(effects
				(font
					(size 1.27 1.27)
				)
				(hide yes)
			)
		)
		(property "Description" ""
			(at 26.67 170.18 0)
			(effects
				(font
					(size 1.27 1.27)
				)
				(hide yes)
			)
		)
		(pin "1"
		)
		(instances
			(project "OCuLink to 10GbE adapter"
				(path ""
					(reference "#PWR0221")
					(unit 1)
				)
			)
			(project "thunderbolt-to-10gbe-adapter"
				(path ""
					(reference "#PWR0222")
					(unit 1)
				)
			)
		)
	)
	(symbol
		(lib_id "antmicropower:GND")
		(at 317.5 133.35 0)
		(unit 1)
		(exclude_from_sim no)
		(in_bom yes)
		(on_board yes)
		(dnp no)
		(property "Reference" "#PWR0312"
			(at 326.39 135.89 0)
			(effects
				(font
					(size 1.27 1.27)
					(thickness 0.15)
				)
				(justify left bottom)
				(hide yes)
			)
		)
		(property "Value" "GND"
			(at 317.5 137.16 0)
			(effects
				(font
					(size 1.27 1.27)
					(thickness 0.15)
				)
			)
		)
		(property "Footprint" ""
			(at 326.39 140.97 0)
			(effects
				(font
					(size 1.27 1.27)
					(thickness 0.15)
				)
				(justify left bottom)
				(hide yes)
			)
		)
		(property "Datasheet" ""
			(at 326.39 146.05 0)
			(effects
				(font
					(size 1.27 1.27)
					(thickness 0.15)
				)
				(justify left bottom)
				(hide yes)
			)
		)
		(property "Description" ""
			(at 317.5 133.35 0)
			(effects
				(font
					(size 1.27 1.27)
				)
				(hide yes)
			)
		)
		(property "Author" "Antmicro"
			(at 326.39 140.97 0)
			(effects
				(font
					(size 1.27 1.27)
					(thickness 0.15)
				)
				(justify left bottom)
				(hide yes)
			)
		)
		(property "License" "Apache-2.0"
			(at 326.39 143.51 0)
			(effects
				(font
					(size 1.27 1.27)
					(thickness 0.15)
				)
				(justify left bottom)
				(hide yes)
			)
		)
		(pin "1"
		)
		(instances
			(project "OCuLink to 10GbE adapter"
				(path ""
					(reference "#PWR0197")
					(unit 1)
				)
			)
			(project "thunderbolt-to-10gbe-adapter"
				(path ""
					(reference "#PWR0312")
					(unit 1)
				)
			)
		)
	)
	(symbol
		(lib_id "antmicroCapacitors0402:C_1u_25V_0402")
		(at 133.35 73.66 90)
		(unit 1)
		(exclude_from_sim no)
		(in_bom yes)
		(on_board yes)
		(dnp no)
		(property "Reference" "C191"
			(at 135.382 69.85 90)
			(effects
				(font
					(size 1.27 1.27)
					(thickness 0.15)
				)
				(justify right)
			)
		)
		(property "Value" "C_1u_25V_0402"
			(at 143.51 53.34 0)
			(effects
				(font
					(size 1.27 1.27)
					(thickness 0.15)
				)
				(justify left bottom)
				(hide yes)
			)
		)
		(property "Footprint" "antmicro-footprints:C_0402_1005Metric"
			(at 146.05 53.34 0)
			(effects
				(font
					(size 1.27 1.27)
					(thickness 0.15)
				)
				(justify left bottom)
				(hide yes)
			)
		)
		(property "Datasheet" "https://www.murata.com/products/productdetail?partno=GRM155R61E105KE11%23"
			(at 148.59 53.34 0)
			(effects
				(font
					(size 1.27 1.27)
					(thickness 0.15)
				)
				(justify left bottom)
				(hide yes)
			)
		)
		(property "Description" "SMD Multilayer Ceramic Capacitor, 1 µF, 25 V, 0402 [1005 Metric], ± 10%, X5R, GRM Series"
			(at 133.35 73.66 0)
			(effects
				(font
					(size 1.27 1.27)
				)
				(hide yes)
			)
		)
		(property "MPN" "GRM155R61E105KE11J"
			(at 151.13 53.34 0)
			(effects
				(font
					(size 1.27 1.27)
					(thickness 0.15)
				)
				(justify left bottom)
				(hide yes)
			)
		)
		(property "Manufacturer" "Murata"
			(at 153.67 53.34 0)
			(effects
				(font
					(size 1.27 1.27)
					(thickness 0.15)
				)
				(justify left bottom)
				(hide yes)
			)
		)
		(property "License" "Apache-2.0"
			(at 156.21 53.34 0)
			(effects
				(font
					(size 1.27 1.27)
					(thickness 0.15)
				)
				(justify left bottom)
				(hide yes)
			)
		)
		(property "Author" "Antmicro"
			(at 158.75 53.34 0)
			(effects
				(font
					(size 1.27 1.27)
					(thickness 0.15)
				)
				(justify left bottom)
				(hide yes)
			)
		)
		(property "Val" "1u"
			(at 135.382 72.39 90)
			(effects
				(font
					(size 1.27 1.27)
					(thickness 0.15)
				)
				(justify right)
			)
		)
		(property "Voltage" "25V"
			(at 161.29 53.34 0)
			(effects
				(font
					(size 1.27 1.27)
				)
				(justify left bottom)
				(hide yes)
			)
		)
		(property "Dielectric" "X5R"
			(at 163.83 53.34 0)
			(effects
				(font
					(size 1.27 1.27)
				)
				(justify left bottom)
				(hide yes)
			)
		)
		(pin "2"
		)
		(pin "1"
		)
		(instances
			(project "OCuLink to 10GbE adapter"
				(path ""
					(reference "C102")
					(unit 1)
				)
			)
			(project "thunderbolt-to-10gbe-adapter"
				(path ""
					(reference "C191")
					(unit 1)
				)
			)
		)
	)
	(symbol
		(lib_id "antmicropower:GND")
		(at 74.93 262.89 0)
		(unit 1)
		(exclude_from_sim no)
		(in_bom yes)
		(on_board yes)
		(dnp no)
		(property "Reference" "#PWR0231"
			(at 83.82 265.43 0)
			(effects
				(font
					(size 1.27 1.27)
					(thickness 0.15)
				)
				(justify left bottom)
				(hide yes)
			)
		)
		(property "Value" "GND"
			(at 74.93 266.7 0)
			(effects
				(font
					(size 1.27 1.27)
					(thickness 0.15)
				)
			)
		)
		(property "Footprint" ""
			(at 83.82 270.51 0)
			(effects
				(font
					(size 1.27 1.27)
					(thickness 0.15)
				)
				(justify left bottom)
				(hide yes)
			)
		)
		(property "Datasheet" ""
			(at 83.82 275.59 0)
			(effects
				(font
					(size 1.27 1.27)
					(thickness 0.15)
				)
				(justify left bottom)
				(hide yes)
			)
		)
		(property "Description" ""
			(at 74.93 262.89 0)
			(effects
				(font
					(size 1.27 1.27)
				)
				(hide yes)
			)
		)
		(property "Author" "Antmicro"
			(at 83.82 270.51 0)
			(effects
				(font
					(size 1.27 1.27)
					(thickness 0.15)
				)
				(justify left bottom)
				(hide yes)
			)
		)
		(property "License" "Apache-2.0"
			(at 83.82 273.05 0)
			(effects
				(font
					(size 1.27 1.27)
					(thickness 0.15)
				)
				(justify left bottom)
				(hide yes)
			)
		)
		(pin "1"
		)
		(instances
			(project "OCuLink to 10GbE adapter"
				(path ""
					(reference "#PWR0243")
					(unit 1)
				)
			)
			(project "thunderbolt-to-10gbe-adapter"
				(path ""
					(reference "#PWR0231")
					(unit 1)
				)
			)
		)
	)
	(symbol
		(lib_id "antmicropower:+1V0")
		(at 26.67 223.52 0)
		(unit 1)
		(exclude_from_sim no)
		(in_bom yes)
		(on_board yes)
		(dnp no)
		(property "Reference" "#PWR0224"
			(at 26.67 227.33 0)
			(effects
				(font
					(size 1.27 1.27)
				)
				(hide yes)
			)
		)
		(property "Value" "+1V0"
			(at 26.67 219.456 0)
			(effects
				(font
					(size 1.27 1.27)
				)
			)
		)
		(property "Footprint" ""
			(at 26.67 223.52 0)
			(effects
				(font
					(size 1.27 1.27)
				)
				(hide yes)
			)
		)
		(property "Datasheet" ""
			(at 26.67 223.52 0)
			(effects
				(font
					(size 1.27 1.27)
				)
				(hide yes)
			)
		)
		(property "Description" ""
			(at 26.67 223.52 0)
			(effects
				(font
					(size 1.27 1.27)
				)
				(hide yes)
			)
		)
		(pin "1"
		)
		(instances
			(project "OCuLink to 10GbE adapter"
				(path ""
					(reference "#PWR0238")
					(unit 1)
				)
			)
			(project "thunderbolt-to-10gbe-adapter"
				(path ""
					(reference "#PWR0224")
					(unit 1)
				)
			)
		)
	)
	(symbol
		(lib_id "antmicropower:GND")
		(at 67.31 182.88 0)
		(unit 1)
		(exclude_from_sim no)
		(in_bom yes)
		(on_board yes)
		(dnp no)
		(property "Reference" "#PWR0227"
			(at 76.2 185.42 0)
			(effects
				(font
					(size 1.27 1.27)
					(thickness 0.15)
				)
				(justify left bottom)
				(hide yes)
			)
		)
		(property "Value" "GND"
			(at 67.31 186.69 0)
			(effects
				(font
					(size 1.27 1.27)
					(thickness 0.15)
				)
			)
		)
		(property "Footprint" ""
			(at 76.2 190.5 0)
			(effects
				(font
					(size 1.27 1.27)
					(thickness 0.15)
				)
				(justify left bottom)
				(hide yes)
			)
		)
		(property "Datasheet" ""
			(at 76.2 195.58 0)
			(effects
				(font
					(size 1.27 1.27)
					(thickness 0.15)
				)
				(justify left bottom)
				(hide yes)
			)
		)
		(property "Description" ""
			(at 67.31 182.88 0)
			(effects
				(font
					(size 1.27 1.27)
				)
				(hide yes)
			)
		)
		(property "Author" "Antmicro"
			(at 76.2 190.5 0)
			(effects
				(font
					(size 1.27 1.27)
					(thickness 0.15)
				)
				(justify left bottom)
				(hide yes)
			)
		)
		(property "License" "Apache-2.0"
			(at 76.2 193.04 0)
			(effects
				(font
					(size 1.27 1.27)
					(thickness 0.15)
				)
				(justify left bottom)
				(hide yes)
			)
		)
		(pin "1"
		)
		(instances
			(project "OCuLink to 10GbE adapter"
				(path ""
					(reference "#PWR0222")
					(unit 1)
				)
			)
			(project "thunderbolt-to-10gbe-adapter"
				(path ""
					(reference "#PWR0227")
					(unit 1)
				)
			)
		)
	)
	(symbol
		(lib_id "antmicroCapacitors0603:C_22u_16V_0603")
		(at 379.73 91.44 90)
		(unit 1)
		(exclude_from_sim no)
		(in_bom yes)
		(on_board yes)
		(dnp no)
		(fields_autoplaced yes)
		(property "Reference" "C257"
			(at 382.27 87.6236 90)
			(effects
				(font
					(size 1.27 1.27)
					(thickness 0.15)
				)
				(justify right)
			)
		)
		(property "Value" "C_22u_16V_0603"
			(at 389.89 71.12 0)
			(effects
				(font
					(size 1.27 1.27)
					(thickness 0.15)
				)
				(justify left bottom)
				(hide yes)
			)
		)
		(property "Footprint" "antmicro-footprints:C_0603_1608Metric_EIA"
			(at 392.43 71.12 0)
			(effects
				(font
					(size 1.27 1.27)
					(thickness 0.15)
				)
				(justify left bottom)
				(hide yes)
			)
		)
		(property "Datasheet" "https://product.samsungsem.com/mlcc/CL10A226MO7JZN.do"
			(at 394.97 71.12 0)
			(effects
				(font
					(size 1.27 1.27)
					(thickness 0.15)
				)
				(justify left bottom)
				(hide yes)
			)
		)
		(property "Description" "SMD Multilayer Ceramic Capacitor"
			(at 379.73 91.44 0)
			(effects
				(font
					(size 1.27 1.27)
				)
				(hide yes)
			)
		)
		(property "MPN" "CL10A226MO7JZNC"
			(at 397.51 71.12 0)
			(effects
				(font
					(size 1.27 1.27)
					(thickness 0.15)
				)
				(justify left bottom)
				(hide yes)
			)
		)
		(property "Manufacturer" "Samsung Electro-Mechanics"
			(at 400.05 71.12 0)
			(effects
				(font
					(size 1.27 1.27)
					(thickness 0.15)
				)
				(justify left bottom)
				(hide yes)
			)
		)
		(property "License" "Apache-2.0"
			(at 402.59 71.12 0)
			(effects
				(font
					(size 1.27 1.27)
					(thickness 0.15)
				)
				(justify left bottom)
				(hide yes)
			)
		)
		(property "Author" "Antmicro"
			(at 405.13 71.12 0)
			(effects
				(font
					(size 1.27 1.27)
					(thickness 0.15)
				)
				(justify left bottom)
				(hide yes)
			)
		)
		(property "Val" "22u"
			(at 382.27 90.1636 90)
			(effects
				(font
					(size 1.27 1.27)
					(thickness 0.15)
				)
				(justify right)
			)
		)
		(property "Voltage" "16V"
			(at 407.67 71.12 0)
			(effects
				(font
					(size 1.27 1.27)
				)
				(justify left bottom)
				(hide yes)
			)
		)
		(property "Dielectric" ""
			(at 410.21 71.12 0)
			(effects
				(font
					(size 1.27 1.27)
				)
				(justify left bottom)
				(hide yes)
			)
		)
		(pin "1"
		)
		(pin "2"
		)
		(instances
			(project "OCuLink to 10GbE adapter"
				(path ""
					(reference "C125")
					(unit 1)
				)
			)
			(project "thunderbolt-to-10gbe-adapter"
				(path ""
					(reference "C257")
					(unit 1)
				)
			)
		)
	)
	(symbol
		(lib_id "antmicroCapacitors0603:C_10u_10V_X7R_0603")
		(at 292.1 149.86 270)
		(mirror x)
		(unit 1)
		(exclude_from_sim no)
		(in_bom yes)
		(on_board yes)
		(dnp no)
		(property "Reference" "C210"
			(at 290.068 146.05 90)
			(effects
				(font
					(size 1.27 1.27)
					(thickness 0.15)
				)
				(justify right)
			)
		)
		(property "Value" "C_10u_10V_X7R_0603"
			(at 281.94 134.62 0)
			(effects
				(font
					(size 1.27 1.27)
					(thickness 0.15)
				)
				(justify left bottom)
				(hide yes)
			)
		)
		(property "Footprint" "antmicro-footprints:C_0603_1608Metric"
			(at 279.4 134.62 0)
			(effects
				(font
					(size 1.27 1.27)
					(thickness 0.15)
				)
				(justify left bottom)
				(hide yes)
			)
		)
		(property "Datasheet" "https://www.murata.com/products/productdetail?partno=GRM188Z71A106KA73%23"
			(at 276.86 134.62 0)
			(effects
				(font
					(size 1.27 1.27)
					(thickness 0.15)
				)
				(justify left bottom)
				(hide yes)
			)
		)
		(property "Description" "SMD Multilayer Ceramic Capacitor,  10µF, 10V, 0603, ±10%, X7R"
			(at 292.1 149.86 0)
			(effects
				(font
					(size 1.27 1.27)
				)
				(hide yes)
			)
		)
		(property "MPN" "GRM188Z71A106KA73D"
			(at 274.32 134.62 0)
			(effects
				(font
					(size 1.27 1.27)
					(thickness 0.15)
				)
				(justify left bottom)
				(hide yes)
			)
		)
		(property "Val" "10u"
			(at 290.068 148.59 90)
			(effects
				(font
					(size 1.27 1.27)
					(thickness 0.15)
				)
				(justify right)
			)
		)
		(property "Voltage" "10V"
			(at 271.78 134.62 0)
			(effects
				(font
					(size 1.27 1.27)
					(thickness 0.15)
				)
				(justify left bottom)
				(hide yes)
			)
		)
		(property "Dielectric" "X7R"
			(at 269.24 134.62 0)
			(effects
				(font
					(size 1.27 1.27)
					(thickness 0.15)
				)
				(justify left bottom)
				(hide yes)
			)
		)
		(property "Manufacturer" "Murata"
			(at 266.7 134.62 0)
			(effects
				(font
					(size 1.27 1.27)
					(thickness 0.15)
				)
				(justify left bottom)
				(hide yes)
			)
		)
		(property "License" "Apache-2.0"
			(at 264.16 134.62 0)
			(effects
				(font
					(size 1.27 1.27)
					(thickness 0.15)
				)
				(justify left bottom)
				(hide yes)
			)
		)
		(property "Author" "Antmicro"
			(at 261.62 134.62 0)
			(effects
				(font
					(size 1.27 1.27)
					(thickness 0.15)
				)
				(justify left bottom)
				(hide yes)
			)
		)
		(pin "1"
		)
		(pin "2"
		)
		(instances
			(project "OCuLink to 10GbE adapter"
				(path ""
					(reference "C158")
					(unit 1)
				)
			)
			(project "thunderbolt-to-10gbe-adapter"
				(path ""
					(reference "C210")
					(unit 1)
				)
			)
		)
	)
	(symbol
		(lib_id "antmicropower:GND")
		(at 88.9 129.54 0)
		(unit 1)
		(exclude_from_sim no)
		(in_bom yes)
		(on_board yes)
		(dnp no)
		(property "Reference" "#PWR0240"
			(at 97.79 132.08 0)
			(effects
				(font
					(size 1.27 1.27)
					(thickness 0.15)
				)
				(justify left bottom)
				(hide yes)
			)
		)
		(property "Value" "GND"
			(at 88.9 133.35 0)
			(effects
				(font
					(size 1.27 1.27)
					(thickness 0.15)
				)
			)
		)
		(property "Footprint" ""
			(at 97.79 137.16 0)
			(effects
				(font
					(size 1.27 1.27)
					(thickness 0.15)
				)
				(justify left bottom)
				(hide yes)
			)
		)
		(property "Datasheet" ""
			(at 97.79 142.24 0)
			(effects
				(font
					(size 1.27 1.27)
					(thickness 0.15)
				)
				(justify left bottom)
				(hide yes)
			)
		)
		(property "Description" ""
			(at 88.9 129.54 0)
			(effects
				(font
					(size 1.27 1.27)
				)
				(hide yes)
			)
		)
		(property "Author" "Antmicro"
			(at 97.79 137.16 0)
			(effects
				(font
					(size 1.27 1.27)
					(thickness 0.15)
				)
				(justify left bottom)
				(hide yes)
			)
		)
		(property "License" "Apache-2.0"
			(at 97.79 139.7 0)
			(effects
				(font
					(size 1.27 1.27)
					(thickness 0.15)
				)
				(justify left bottom)
				(hide yes)
			)
		)
		(pin "1"
		)
		(instances
			(project "OCuLink to 10GbE adapter"
				(path ""
					(reference "#PWR0188")
					(unit 1)
				)
			)
			(project "thunderbolt-to-10gbe-adapter"
				(path ""
					(reference "#PWR0240")
					(unit 1)
				)
			)
		)
	)
	(symbol
		(lib_id "antmicropower:VDD")
		(at 208.28 104.14 0)
		(unit 1)
		(exclude_from_sim no)
		(in_bom yes)
		(on_board yes)
		(dnp no)
		(property "Reference" "#PWR0286"
			(at 208.28 107.95 0)
			(effects
				(font
					(size 1.27 1.27)
				)
				(hide yes)
			)
		)
		(property "Value" "XGB_AVDDH"
			(at 208.28 100.33 0)
			(effects
				(font
					(size 1.27 1.27)
				)
			)
		)
		(property "Footprint" ""
			(at 208.28 104.14 0)
			(effects
				(font
					(size 1.27 1.27)
				)
				(hide yes)
			)
		)
		(property "Datasheet" ""
			(at 208.28 104.14 0)
			(effects
				(font
					(size 1.27 1.27)
				)
				(hide yes)
			)
		)
		(property "Description" ""
			(at 208.28 104.14 0)
			(effects
				(font
					(size 1.27 1.27)
				)
				(hide yes)
			)
		)
		(pin "1"
		)
		(instances
			(project "OCuLink to 10GbE adapter"
				(path ""
					(reference "#PWR0157")
					(unit 1)
				)
			)
			(project "thunderbolt-to-10gbe-adapter"
				(path ""
					(reference "#PWR0286")
					(unit 1)
				)
			)
		)
	)
	(symbol
		(lib_id "antmicropower:VDD")
		(at 214.63 87.63 0)
		(unit 1)
		(exclude_from_sim no)
		(in_bom yes)
		(on_board yes)
		(dnp no)
		(property "Reference" "#PWR0288"
			(at 214.63 91.44 0)
			(effects
				(font
					(size 1.27 1.27)
				)
				(hide yes)
			)
		)
		(property "Value" "DVDD"
			(at 214.63 83.82 0)
			(effects
				(font
					(size 1.27 1.27)
				)
			)
		)
		(property "Footprint" ""
			(at 214.63 87.63 0)
			(effects
				(font
					(size 1.27 1.27)
				)
				(hide yes)
			)
		)
		(property "Datasheet" ""
			(at 214.63 87.63 0)
			(effects
				(font
					(size 1.27 1.27)
				)
				(hide yes)
			)
		)
		(property "Description" ""
			(at 214.63 87.63 0)
			(effects
				(font
					(size 1.27 1.27)
				)
				(hide yes)
			)
		)
		(pin "1"
		)
		(instances
			(project "OCuLink to 10GbE adapter"
				(path ""
					(reference "#PWR0159")
					(unit 1)
				)
			)
			(project "thunderbolt-to-10gbe-adapter"
				(path ""
					(reference "#PWR0288")
					(unit 1)
				)
			)
		)
	)
	(symbol
		(lib_id "antmicropower:GND")
		(at 344.17 54.61 0)
		(unit 1)
		(exclude_from_sim no)
		(in_bom yes)
		(on_board yes)
		(dnp no)
		(property "Reference" "#PWR0322"
			(at 353.06 57.15 0)
			(effects
				(font
					(size 1.27 1.27)
					(thickness 0.15)
				)
				(justify left bottom)
				(hide yes)
			)
		)
		(property "Value" "GND"
			(at 344.17 58.42 0)
			(effects
				(font
					(size 1.27 1.27)
					(thickness 0.15)
				)
			)
		)
		(property "Footprint" ""
			(at 353.06 62.23 0)
			(effects
				(font
					(size 1.27 1.27)
					(thickness 0.15)
				)
				(justify left bottom)
				(hide yes)
			)
		)
		(property "Datasheet" ""
			(at 353.06 67.31 0)
			(effects
				(font
					(size 1.27 1.27)
					(thickness 0.15)
				)
				(justify left bottom)
				(hide yes)
			)
		)
		(property "Description" ""
			(at 344.17 54.61 0)
			(effects
				(font
					(size 1.27 1.27)
				)
				(hide yes)
			)
		)
		(property "Author" "Antmicro"
			(at 353.06 62.23 0)
			(effects
				(font
					(size 1.27 1.27)
					(thickness 0.15)
				)
				(justify left bottom)
				(hide yes)
			)
		)
		(property "License" "Apache-2.0"
			(at 353.06 64.77 0)
			(effects
				(font
					(size 1.27 1.27)
					(thickness 0.15)
				)
				(justify left bottom)
				(hide yes)
			)
		)
		(pin "1"
		)
		(instances
			(project "OCuLink to 10GbE adapter"
				(path ""
					(reference "#PWR0126")
					(unit 1)
				)
			)
			(project "thunderbolt-to-10gbe-adapter"
				(path ""
					(reference "#PWR0322")
					(unit 1)
				)
			)
		)
	)
	(symbol
		(lib_id "antmicropower:GND")
		(at 151.13 76.2 0)
		(unit 1)
		(exclude_from_sim no)
		(in_bom yes)
		(on_board yes)
		(dnp no)
		(property "Reference" "#PWR0274"
			(at 160.02 78.74 0)
			(effects
				(font
					(size 1.27 1.27)
					(thickness 0.15)
				)
				(justify left bottom)
				(hide yes)
			)
		)
		(property "Value" "GND"
			(at 151.13 80.01 0)
			(effects
				(font
					(size 1.27 1.27)
					(thickness 0.15)
				)
			)
		)
		(property "Footprint" ""
			(at 160.02 83.82 0)
			(effects
				(font
					(size 1.27 1.27)
					(thickness 0.15)
				)
				(justify left bottom)
				(hide yes)
			)
		)
		(property "Datasheet" ""
			(at 160.02 88.9 0)
			(effects
				(font
					(size 1.27 1.27)
					(thickness 0.15)
				)
				(justify left bottom)
				(hide yes)
			)
		)
		(property "Description" ""
			(at 151.13 76.2 0)
			(effects
				(font
					(size 1.27 1.27)
				)
				(hide yes)
			)
		)
		(property "Author" "Antmicro"
			(at 160.02 83.82 0)
			(effects
				(font
					(size 1.27 1.27)
					(thickness 0.15)
				)
				(justify left bottom)
				(hide yes)
			)
		)
		(property "License" "Apache-2.0"
			(at 160.02 86.36 0)
			(effects
				(font
					(size 1.27 1.27)
					(thickness 0.15)
				)
				(justify left bottom)
				(hide yes)
			)
		)
		(pin "1"
		)
		(instances
			(project "OCuLink to 10GbE adapter"
				(path ""
					(reference "#PWR0138")
					(unit 1)
				)
			)
			(project "thunderbolt-to-10gbe-adapter"
				(path ""
					(reference "#PWR0274")
					(unit 1)
				)
			)
		)
	)
	(symbol
		(lib_id "antmicroCapacitors0402:C_100n_0402")
		(at 86.36 153.67 90)
		(unit 1)
		(exclude_from_sim no)
		(in_bom yes)
		(on_board yes)
		(dnp no)
		(property "Reference" "C163"
			(at 88.392 149.86 90)
			(effects
				(font
					(size 1.27 1.27)
					(thickness 0.15)
				)
				(justify right)
			)
		)
		(property "Value" "C_100n_0402"
			(at 109.22 138.43 0)
			(effects
				(font
					(size 1.27 1.27)
					(thickness 0.15)
				)
				(justify left bottom)
				(hide yes)
			)
		)
		(property "Footprint" "antmicro-footprints:C_0402_1005Metric"
			(at 111.76 138.43 0)
			(effects
				(font
					(size 1.27 1.27)
					(thickness 0.15)
				)
				(justify left bottom)
				(hide yes)
			)
		)
		(property "Datasheet" "https://www.murata.com/products/productdetail?partno=GRM155R61H104KE14%23"
			(at 114.3 138.43 0)
			(effects
				(font
					(size 1.27 1.27)
					(thickness 0.15)
				)
				(justify left bottom)
				(hide yes)
			)
		)
		(property "Description" "SMD Multilayer Ceramic Capacitor, 0.1 µF, 50 V, 0402 [1005 Metric], ± 10%, X5R, GRM Series"
			(at 86.36 153.67 0)
			(effects
				(font
					(size 1.27 1.27)
				)
				(hide yes)
			)
		)
		(property "MPN" "GRM155R61H104KE14D"
			(at 116.84 138.43 0)
			(effects
				(font
					(size 1.27 1.27)
					(thickness 0.15)
				)
				(justify left bottom)
				(hide yes)
			)
		)
		(property "Val" "100n"
			(at 88.392 152.4 90)
			(effects
				(font
					(size 1.27 1.27)
					(thickness 0.15)
				)
				(justify right)
			)
		)
		(property "Voltage" "50V"
			(at 96.52 138.43 0)
			(effects
				(font
					(size 1.27 1.27)
					(thickness 0.15)
				)
				(justify left bottom)
				(hide yes)
			)
		)
		(property "Dielectric" "X5R"
			(at 99.06 138.43 0)
			(effects
				(font
					(size 1.27 1.27)
					(thickness 0.15)
				)
				(justify left bottom)
				(hide yes)
			)
		)
		(property "Manufacturer" "Murata"
			(at 101.6 138.43 0)
			(effects
				(font
					(size 1.27 1.27)
					(thickness 0.15)
				)
				(justify left bottom)
				(hide yes)
			)
		)
		(property "License" "Apache-2.0"
			(at 104.14 138.43 0)
			(effects
				(font
					(size 1.27 1.27)
					(thickness 0.15)
				)
				(justify left bottom)
				(hide yes)
			)
		)
		(property "Author" "Antmicro"
			(at 106.68 138.43 0)
			(effects
				(font
					(size 1.27 1.27)
					(thickness 0.15)
				)
				(justify left bottom)
				(hide yes)
			)
		)
		(pin "2"
		)
		(pin "1"
		)
		(instances
			(project ""
				(path ""
					(reference "C162")
					(unit 1)
				)
			)
			(project "thunderbolt-to-10gbe-adapter"
				(path ""
					(reference "C163")
					(unit 1)
				)
			)
		)
	)
	(symbol
		(lib_id "antmicroCapacitors0603:C_10u_10V_X7R_0603")
		(at 90.17 233.68 90)
		(unit 1)
		(exclude_from_sim no)
		(in_bom yes)
		(on_board yes)
		(dnp no)
		(property "Reference" "C173"
			(at 92.456 229.87 90)
			(effects
				(font
					(size 1.27 1.27)
					(thickness 0.15)
				)
				(justify right)
			)
		)
		(property "Value" "C_10u_10V_X7R_0603"
			(at 100.33 218.44 0)
			(effects
				(font
					(size 1.27 1.27)
					(thickness 0.15)
				)
				(justify left bottom)
				(hide yes)
			)
		)
		(property "Footprint" "antmicro-footprints:C_0603_1608Metric"
			(at 102.87 218.44 0)
			(effects
				(font
					(size 1.27 1.27)
					(thickness 0.15)
				)
				(justify left bottom)
				(hide yes)
			)
		)
		(property "Datasheet" "https://www.murata.com/products/productdetail?partno=GRM188Z71A106KA73%23"
			(at 105.41 218.44 0)
			(effects
				(font
					(size 1.27 1.27)
					(thickness 0.15)
				)
				(justify left bottom)
				(hide yes)
			)
		)
		(property "Description" "SMD Multilayer Ceramic Capacitor,  10µF, 10V, 0603, ±10%, X7R"
			(at 90.17 233.68 0)
			(effects
				(font
					(size 1.27 1.27)
				)
				(hide yes)
			)
		)
		(property "MPN" "GRM188Z71A106KA73D"
			(at 107.95 218.44 0)
			(effects
				(font
					(size 1.27 1.27)
					(thickness 0.15)
				)
				(justify left bottom)
				(hide yes)
			)
		)
		(property "Val" "10u"
			(at 92.456 232.41 90)
			(effects
				(font
					(size 1.27 1.27)
					(thickness 0.15)
				)
				(justify right)
			)
		)
		(property "Voltage" "10V"
			(at 110.49 218.44 0)
			(effects
				(font
					(size 1.27 1.27)
					(thickness 0.15)
				)
				(justify left bottom)
				(hide yes)
			)
		)
		(property "Dielectric" "X7R"
			(at 113.03 218.44 0)
			(effects
				(font
					(size 1.27 1.27)
					(thickness 0.15)
				)
				(justify left bottom)
				(hide yes)
			)
		)
		(property "Manufacturer" "Murata"
			(at 115.57 218.44 0)
			(effects
				(font
					(size 1.27 1.27)
					(thickness 0.15)
				)
				(justify left bottom)
				(hide yes)
			)
		)
		(property "License" "Apache-2.0"
			(at 118.11 218.44 0)
			(effects
				(font
					(size 1.27 1.27)
					(thickness 0.15)
				)
				(justify left bottom)
				(hide yes)
			)
		)
		(property "Author" "Antmicro"
			(at 120.65 218.44 0)
			(effects
				(font
					(size 1.27 1.27)
					(thickness 0.15)
				)
				(justify left bottom)
				(hide yes)
			)
		)
		(pin "1"
		)
		(pin "2"
		)
		(instances
			(project "OCuLink to 10GbE adapter"
				(path ""
					(reference "C186")
					(unit 1)
				)
			)
			(project "thunderbolt-to-10gbe-adapter"
				(path ""
					(reference "C173")
					(unit 1)
				)
			)
		)
	)
	(symbol
		(lib_id "antmicropower:GND")
		(at 388.62 76.2 0)
		(unit 1)
		(exclude_from_sim no)
		(in_bom yes)
		(on_board yes)
		(dnp no)
		(property "Reference" "#PWR0346"
			(at 397.51 78.74 0)
			(effects
				(font
					(size 1.27 1.27)
					(thickness 0.15)
				)
				(justify left bottom)
				(hide yes)
			)
		)
		(property "Value" "GND"
			(at 388.62 80.01 0)
			(effects
				(font
					(size 1.27 1.27)
					(thickness 0.15)
				)
			)
		)
		(property "Footprint" ""
			(at 397.51 83.82 0)
			(effects
				(font
					(size 1.27 1.27)
					(thickness 0.15)
				)
				(justify left bottom)
				(hide yes)
			)
		)
		(property "Datasheet" ""
			(at 397.51 88.9 0)
			(effects
				(font
					(size 1.27 1.27)
					(thickness 0.15)
				)
				(justify left bottom)
				(hide yes)
			)
		)
		(property "Description" ""
			(at 388.62 76.2 0)
			(effects
				(font
					(size 1.27 1.27)
				)
				(hide yes)
			)
		)
		(property "Author" "Antmicro"
			(at 397.51 83.82 0)
			(effects
				(font
					(size 1.27 1.27)
					(thickness 0.15)
				)
				(justify left bottom)
				(hide yes)
			)
		)
		(property "License" "Apache-2.0"
			(at 397.51 86.36 0)
			(effects
				(font
					(size 1.27 1.27)
					(thickness 0.15)
				)
				(justify left bottom)
				(hide yes)
			)
		)
		(pin "1"
		)
		(instances
			(project "OCuLink to 10GbE adapter"
				(path ""
					(reference "#PWR0149")
					(unit 1)
				)
			)
			(project "thunderbolt-to-10gbe-adapter"
				(path ""
					(reference "#PWR0346")
					(unit 1)
				)
			)
		)
	)
	(symbol
		(lib_id "antmicropower:GND")
		(at 151.13 182.88 0)
		(unit 1)
		(exclude_from_sim no)
		(in_bom yes)
		(on_board yes)
		(dnp no)
		(property "Reference" "#PWR0277"
			(at 160.02 185.42 0)
			(effects
				(font
					(size 1.27 1.27)
					(thickness 0.15)
				)
				(justify left bottom)
				(hide yes)
			)
		)
		(property "Value" "GND"
			(at 151.13 186.69 0)
			(effects
				(font
					(size 1.27 1.27)
					(thickness 0.15)
				)
			)
		)
		(property "Footprint" ""
			(at 160.02 190.5 0)
			(effects
				(font
					(size 1.27 1.27)
					(thickness 0.15)
				)
				(justify left bottom)
				(hide yes)
			)
		)
		(property "Datasheet" ""
			(at 160.02 195.58 0)
			(effects
				(font
					(size 1.27 1.27)
					(thickness 0.15)
				)
				(justify left bottom)
				(hide yes)
			)
		)
		(property "Description" ""
			(at 151.13 182.88 0)
			(effects
				(font
					(size 1.27 1.27)
				)
				(hide yes)
			)
		)
		(property "Author" "Antmicro"
			(at 160.02 190.5 0)
			(effects
				(font
					(size 1.27 1.27)
					(thickness 0.15)
				)
				(justify left bottom)
				(hide yes)
			)
		)
		(property "License" "Apache-2.0"
			(at 160.02 193.04 0)
			(effects
				(font
					(size 1.27 1.27)
					(thickness 0.15)
				)
				(justify left bottom)
				(hide yes)
			)
		)
		(pin "1"
		)
		(instances
			(project "OCuLink to 10GbE adapter"
				(path ""
					(reference "#PWR0230")
					(unit 1)
				)
			)
			(project "thunderbolt-to-10gbe-adapter"
				(path ""
					(reference "#PWR0277")
					(unit 1)
				)
			)
		)
	)
	(symbol
		(lib_id "antmicroCapacitors0603:C_22u_16V_0603")
		(at 99.06 52.07 90)
		(unit 1)
		(exclude_from_sim no)
		(in_bom yes)
		(on_board yes)
		(dnp no)
		(property "Reference" "C175"
			(at 101.092 48.26 90)
			(effects
				(font
					(size 1.27 1.27)
					(thickness 0.15)
				)
				(justify right)
			)
		)
		(property "Value" "C_22u_16V_0603"
			(at 109.22 31.75 0)
			(effects
				(font
					(size 1.27 1.27)
					(thickness 0.15)
				)
				(justify left bottom)
				(hide yes)
			)
		)
		(property "Footprint" "antmicro-footprints:C_0603_1608Metric_EIA"
			(at 111.76 31.75 0)
			(effects
				(font
					(size 1.27 1.27)
					(thickness 0.15)
				)
				(justify left bottom)
				(hide yes)
			)
		)
		(property "Datasheet" "https://product.samsungsem.com/mlcc/CL10A226MO7JZN.do"
			(at 114.3 31.75 0)
			(effects
				(font
					(size 1.27 1.27)
					(thickness 0.15)
				)
				(justify left bottom)
				(hide yes)
			)
		)
		(property "Description" "SMD Multilayer Ceramic Capacitor"
			(at 99.06 52.07 0)
			(effects
				(font
					(size 1.27 1.27)
				)
				(hide yes)
			)
		)
		(property "MPN" "CL10A226MO7JZNC"
			(at 116.84 31.75 0)
			(effects
				(font
					(size 1.27 1.27)
					(thickness 0.15)
				)
				(justify left bottom)
				(hide yes)
			)
		)
		(property "Manufacturer" "Samsung Electro-Mechanics"
			(at 119.38 31.75 0)
			(effects
				(font
					(size 1.27 1.27)
					(thickness 0.15)
				)
				(justify left bottom)
				(hide yes)
			)
		)
		(property "License" "Apache-2.0"
			(at 121.92 31.75 0)
			(effects
				(font
					(size 1.27 1.27)
					(thickness 0.15)
				)
				(justify left bottom)
				(hide yes)
			)
		)
		(property "Author" "Antmicro"
			(at 124.46 31.75 0)
			(effects
				(font
					(size 1.27 1.27)
					(thickness 0.15)
				)
				(justify left bottom)
				(hide yes)
			)
		)
		(property "Val" "22u"
			(at 101.092 50.8 90)
			(effects
				(font
					(size 1.27 1.27)
					(thickness 0.15)
				)
				(justify right)
			)
		)
		(property "Voltage" "16V"
			(at 127 31.75 0)
			(effects
				(font
					(size 1.27 1.27)
				)
				(justify left bottom)
				(hide yes)
			)
		)
		(property "Dielectric" ""
			(at 129.54 31.75 0)
			(effects
				(font
					(size 1.27 1.27)
				)
				(justify left bottom)
				(hide yes)
			)
		)
		(pin "1"
		)
		(pin "2"
		)
		(instances
			(project "OCuLink to 10GbE adapter"
				(path ""
					(reference "C81")
					(unit 1)
				)
			)
			(project "thunderbolt-to-10gbe-adapter"
				(path ""
					(reference "C175")
					(unit 1)
				)
			)
		)
	)
	(symbol
		(lib_id "antmicropower:GND")
		(at 370.84 54.61 0)
		(unit 1)
		(exclude_from_sim no)
		(in_bom yes)
		(on_board yes)
		(dnp no)
		(property "Reference" "#PWR0336"
			(at 379.73 57.15 0)
			(effects
				(font
					(size 1.27 1.27)
					(thickness 0.15)
				)
				(justify left bottom)
				(hide yes)
			)
		)
		(property "Value" "GND"
			(at 370.84 58.42 0)
			(effects
				(font
					(size 1.27 1.27)
					(thickness 0.15)
				)
			)
		)
		(property "Footprint" ""
			(at 379.73 62.23 0)
			(effects
				(font
					(size 1.27 1.27)
					(thickness 0.15)
				)
				(justify left bottom)
				(hide yes)
			)
		)
		(property "Datasheet" ""
			(at 379.73 67.31 0)
			(effects
				(font
					(size 1.27 1.27)
					(thickness 0.15)
				)
				(justify left bottom)
				(hide yes)
			)
		)
		(property "Description" ""
			(at 370.84 54.61 0)
			(effects
				(font
					(size 1.27 1.27)
				)
				(hide yes)
			)
		)
		(property "Author" "Antmicro"
			(at 379.73 62.23 0)
			(effects
				(font
					(size 1.27 1.27)
					(thickness 0.15)
				)
				(justify left bottom)
				(hide yes)
			)
		)
		(property "License" "Apache-2.0"
			(at 379.73 64.77 0)
			(effects
				(font
					(size 1.27 1.27)
					(thickness 0.15)
				)
				(justify left bottom)
				(hide yes)
			)
		)
		(pin "1"
		)
		(instances
			(project "OCuLink to 10GbE adapter"
				(path ""
					(reference "#PWR0129")
					(unit 1)
				)
			)
			(project "thunderbolt-to-10gbe-adapter"
				(path ""
					(reference "#PWR0336")
					(unit 1)
				)
			)
		)
	)
	(symbol
		(lib_id "antmicropower:GND")
		(at 326.39 93.98 0)
		(unit 1)
		(exclude_from_sim no)
		(in_bom yes)
		(on_board yes)
		(dnp no)
		(property "Reference" "#PWR0315"
			(at 335.28 96.52 0)
			(effects
				(font
					(size 1.27 1.27)
					(thickness 0.15)
				)
				(justify left bottom)
				(hide yes)
			)
		)
		(property "Value" "GND"
			(at 326.39 97.79 0)
			(effects
				(font
					(size 1.27 1.27)
					(thickness 0.15)
				)
			)
		)
		(property "Footprint" ""
			(at 335.28 101.6 0)
			(effects
				(font
					(size 1.27 1.27)
					(thickness 0.15)
				)
				(justify left bottom)
				(hide yes)
			)
		)
		(property "Datasheet" ""
			(at 335.28 106.68 0)
			(effects
				(font
					(size 1.27 1.27)
					(thickness 0.15)
				)
				(justify left bottom)
				(hide yes)
			)
		)
		(property "Description" ""
			(at 326.39 93.98 0)
			(effects
				(font
					(size 1.27 1.27)
				)
				(hide yes)
			)
		)
		(property "Author" "Antmicro"
			(at 335.28 101.6 0)
			(effects
				(font
					(size 1.27 1.27)
					(thickness 0.15)
				)
				(justify left bottom)
				(hide yes)
			)
		)
		(property "License" "Apache-2.0"
			(at 335.28 104.14 0)
			(effects
				(font
					(size 1.27 1.27)
					(thickness 0.15)
				)
				(justify left bottom)
				(hide yes)
			)
		)
		(pin "1"
		)
		(instances
			(project "OCuLink to 10GbE adapter"
				(path ""
					(reference "#PWR0167")
					(unit 1)
				)
			)
			(project "thunderbolt-to-10gbe-adapter"
				(path ""
					(reference "#PWR0315")
					(unit 1)
				)
			)
		)
	)
	(symbol
		(lib_id "antmicropower:GND")
		(at 317.5 54.61 0)
		(unit 1)
		(exclude_from_sim no)
		(in_bom yes)
		(on_board yes)
		(dnp no)
		(property "Reference" "#PWR0308"
			(at 326.39 57.15 0)
			(effects
				(font
					(size 1.27 1.27)
					(thickness 0.15)
				)
				(justify left bottom)
				(hide yes)
			)
		)
		(property "Value" "GND"
			(at 317.5 58.42 0)
			(effects
				(font
					(size 1.27 1.27)
					(thickness 0.15)
				)
			)
		)
		(property "Footprint" ""
			(at 326.39 62.23 0)
			(effects
				(font
					(size 1.27 1.27)
					(thickness 0.15)
				)
				(justify left bottom)
				(hide yes)
			)
		)
		(property "Datasheet" ""
			(at 326.39 67.31 0)
			(effects
				(font
					(size 1.27 1.27)
					(thickness 0.15)
				)
				(justify left bottom)
				(hide yes)
			)
		)
		(property "Description" ""
			(at 317.5 54.61 0)
			(effects
				(font
					(size 1.27 1.27)
				)
				(hide yes)
			)
		)
		(property "Author" "Antmicro"
			(at 326.39 62.23 0)
			(effects
				(font
					(size 1.27 1.27)
					(thickness 0.15)
				)
				(justify left bottom)
				(hide yes)
			)
		)
		(property "License" "Apache-2.0"
			(at 326.39 64.77 0)
			(effects
				(font
					(size 1.27 1.27)
					(thickness 0.15)
				)
				(justify left bottom)
				(hide yes)
			)
		)
		(pin "1"
		)
		(instances
			(project "OCuLink to 10GbE adapter"
				(path ""
					(reference "#PWR0123")
					(unit 1)
				)
			)
			(project "thunderbolt-to-10gbe-adapter"
				(path ""
					(reference "#PWR0308")
					(unit 1)
				)
			)
		)
	)
	(symbol
		(lib_id "antmicropower:GND")
		(at 361.95 54.61 0)
		(unit 1)
		(exclude_from_sim no)
		(in_bom yes)
		(on_board yes)
		(dnp no)
		(property "Reference" "#PWR0331"
			(at 370.84 57.15 0)
			(effects
				(font
					(size 1.27 1.27)
					(thickness 0.15)
				)
				(justify left bottom)
				(hide yes)
			)
		)
		(property "Value" "GND"
			(at 361.95 58.42 0)
			(effects
				(font
					(size 1.27 1.27)
					(thickness 0.15)
				)
			)
		)
		(property "Footprint" ""
			(at 370.84 62.23 0)
			(effects
				(font
					(size 1.27 1.27)
					(thickness 0.15)
				)
				(justify left bottom)
				(hide yes)
			)
		)
		(property "Datasheet" ""
			(at 370.84 67.31 0)
			(effects
				(font
					(size 1.27 1.27)
					(thickness 0.15)
				)
				(justify left bottom)
				(hide yes)
			)
		)
		(property "Description" ""
			(at 361.95 54.61 0)
			(effects
				(font
					(size 1.27 1.27)
				)
				(hide yes)
			)
		)
		(property "Author" "Antmicro"
			(at 370.84 62.23 0)
			(effects
				(font
					(size 1.27 1.27)
					(thickness 0.15)
				)
				(justify left bottom)
				(hide yes)
			)
		)
		(property "License" "Apache-2.0"
			(at 370.84 64.77 0)
			(effects
				(font
					(size 1.27 1.27)
					(thickness 0.15)
				)
				(justify left bottom)
				(hide yes)
			)
		)
		(pin "1"
		)
		(instances
			(project "OCuLink to 10GbE adapter"
				(path ""
					(reference "#PWR0128")
					(unit 1)
				)
			)
			(project "thunderbolt-to-10gbe-adapter"
				(path ""
					(reference "#PWR0331")
					(unit 1)
				)
			)
		)
	)
	(symbol
		(lib_id "antmicroCapacitors0603:C_10u_10V_X7R_0603")
		(at 115.57 153.67 90)
		(unit 1)
		(exclude_from_sim no)
		(in_bom yes)
		(on_board yes)
		(dnp no)
		(property "Reference" "C180"
			(at 117.856 149.86 90)
			(effects
				(font
					(size 1.27 1.27)
					(thickness 0.15)
				)
				(justify right)
			)
		)
		(property "Value" "C_10u_10V_X7R_0603"
			(at 125.73 138.43 0)
			(effects
				(font
					(size 1.27 1.27)
					(thickness 0.15)
				)
				(justify left bottom)
				(hide yes)
			)
		)
		(property "Footprint" "antmicro-footprints:C_0603_1608Metric"
			(at 128.27 138.43 0)
			(effects
				(font
					(size 1.27 1.27)
					(thickness 0.15)
				)
				(justify left bottom)
				(hide yes)
			)
		)
		(property "Datasheet" "https://www.murata.com/products/productdetail?partno=GRM188Z71A106KA73%23"
			(at 130.81 138.43 0)
			(effects
				(font
					(size 1.27 1.27)
					(thickness 0.15)
				)
				(justify left bottom)
				(hide yes)
			)
		)
		(property "Description" "SMD Multilayer Ceramic Capacitor,  10µF, 10V, 0603, ±10%, X7R"
			(at 115.57 153.67 0)
			(effects
				(font
					(size 1.27 1.27)
				)
				(hide yes)
			)
		)
		(property "MPN" "GRM188Z71A106KA73D"
			(at 133.35 138.43 0)
			(effects
				(font
					(size 1.27 1.27)
					(thickness 0.15)
				)
				(justify left bottom)
				(hide yes)
			)
		)
		(property "Val" "10u"
			(at 117.856 152.4 90)
			(effects
				(font
					(size 1.27 1.27)
					(thickness 0.15)
				)
				(justify right)
			)
		)
		(property "Voltage" "10V"
			(at 135.89 138.43 0)
			(effects
				(font
					(size 1.27 1.27)
					(thickness 0.15)
				)
				(justify left bottom)
				(hide yes)
			)
		)
		(property "Dielectric" "X7R"
			(at 138.43 138.43 0)
			(effects
				(font
					(size 1.27 1.27)
					(thickness 0.15)
				)
				(justify left bottom)
				(hide yes)
			)
		)
		(property "Manufacturer" "Murata"
			(at 140.97 138.43 0)
			(effects
				(font
					(size 1.27 1.27)
					(thickness 0.15)
				)
				(justify left bottom)
				(hide yes)
			)
		)
		(property "License" "Apache-2.0"
			(at 143.51 138.43 0)
			(effects
				(font
					(size 1.27 1.27)
					(thickness 0.15)
				)
				(justify left bottom)
				(hide yes)
			)
		)
		(property "Author" "Antmicro"
			(at 146.05 138.43 0)
			(effects
				(font
					(size 1.27 1.27)
					(thickness 0.15)
				)
				(justify left bottom)
				(hide yes)
			)
		)
		(pin "1"
		)
		(pin "2"
		)
		(instances
			(project "OCuLink to 10GbE adapter"
				(path ""
					(reference "C165")
					(unit 1)
				)
			)
			(project "thunderbolt-to-10gbe-adapter"
				(path ""
					(reference "C180")
					(unit 1)
				)
			)
		)
	)
	(symbol
		(lib_id "antmicropower:GND")
		(at 344.17 115.57 0)
		(unit 1)
		(exclude_from_sim no)
		(in_bom yes)
		(on_board yes)
		(dnp no)
		(property "Reference" "#PWR0324"
			(at 353.06 118.11 0)
			(effects
				(font
					(size 1.27 1.27)
					(thickness 0.15)
				)
				(justify left bottom)
				(hide yes)
			)
		)
		(property "Value" "GND"
			(at 344.17 119.38 0)
			(effects
				(font
					(size 1.27 1.27)
					(thickness 0.15)
				)
			)
		)
		(property "Footprint" ""
			(at 353.06 123.19 0)
			(effects
				(font
					(size 1.27 1.27)
					(thickness 0.15)
				)
				(justify left bottom)
				(hide yes)
			)
		)
		(property "Datasheet" ""
			(at 353.06 128.27 0)
			(effects
				(font
					(size 1.27 1.27)
					(thickness 0.15)
				)
				(justify left bottom)
				(hide yes)
			)
		)
		(property "Description" ""
			(at 344.17 115.57 0)
			(effects
				(font
					(size 1.27 1.27)
				)
				(hide yes)
			)
		)
		(property "Author" "Antmicro"
			(at 353.06 123.19 0)
			(effects
				(font
					(size 1.27 1.27)
					(thickness 0.15)
				)
				(justify left bottom)
				(hide yes)
			)
		)
		(property "License" "Apache-2.0"
			(at 353.06 125.73 0)
			(effects
				(font
					(size 1.27 1.27)
					(thickness 0.15)
				)
				(justify left bottom)
				(hide yes)
			)
		)
		(pin "1"
		)
		(instances
			(project "OCuLink to 10GbE adapter"
				(path ""
					(reference "#PWR0182")
					(unit 1)
				)
			)
			(project "thunderbolt-to-10gbe-adapter"
				(path ""
					(reference "#PWR0324")
					(unit 1)
				)
			)
		)
	)
	(symbol
		(lib_id "antmicroCapacitors0603:C_10u_10V_X7R_0603")
		(at 326.39 130.81 90)
		(unit 1)
		(exclude_from_sim no)
		(in_bom yes)
		(on_board yes)
		(dnp no)
		(property "Reference" "C231"
			(at 328.422 127 90)
			(effects
				(font
					(size 1.27 1.27)
					(thickness 0.15)
				)
				(justify right)
			)
		)
		(property "Value" "C_10u_10V_X7R_0603"
			(at 336.55 115.57 0)
			(effects
				(font
					(size 1.27 1.27)
					(thickness 0.15)
				)
				(justify left bottom)
				(hide yes)
			)
		)
		(property "Footprint" "antmicro-footprints:C_0603_1608Metric"
			(at 339.09 115.57 0)
			(effects
				(font
					(size 1.27 1.27)
					(thickness 0.15)
				)
				(justify left bottom)
				(hide yes)
			)
		)
		(property "Datasheet" "https://www.murata.com/products/productdetail?partno=GRM188Z71A106KA73%23"
			(at 341.63 115.57 0)
			(effects
				(font
					(size 1.27 1.27)
					(thickness 0.15)
				)
				(justify left bottom)
				(hide yes)
			)
		)
		(property "Description" "SMD Multilayer Ceramic Capacitor,  10µF, 10V, 0603, ±10%, X7R"
			(at 326.39 130.81 0)
			(effects
				(font
					(size 1.27 1.27)
				)
				(hide yes)
			)
		)
		(property "MPN" "GRM188Z71A106KA73D"
			(at 344.17 115.57 0)
			(effects
				(font
					(size 1.27 1.27)
					(thickness 0.15)
				)
				(justify left bottom)
				(hide yes)
			)
		)
		(property "Val" "10u"
			(at 328.422 129.54 90)
			(effects
				(font
					(size 1.27 1.27)
					(thickness 0.15)
				)
				(justify right)
			)
		)
		(property "Voltage" "10V"
			(at 346.71 115.57 0)
			(effects
				(font
					(size 1.27 1.27)
					(thickness 0.15)
				)
				(justify left bottom)
				(hide yes)
			)
		)
		(property "Dielectric" "X7R"
			(at 349.25 115.57 0)
			(effects
				(font
					(size 1.27 1.27)
					(thickness 0.15)
				)
				(justify left bottom)
				(hide yes)
			)
		)
		(property "Manufacturer" "Murata"
			(at 351.79 115.57 0)
			(effects
				(font
					(size 1.27 1.27)
					(thickness 0.15)
				)
				(justify left bottom)
				(hide yes)
			)
		)
		(property "License" "Apache-2.0"
			(at 354.33 115.57 0)
			(effects
				(font
					(size 1.27 1.27)
					(thickness 0.15)
				)
				(justify left bottom)
				(hide yes)
			)
		)
		(property "Author" "Antmicro"
			(at 356.87 115.57 0)
			(effects
				(font
					(size 1.27 1.27)
					(thickness 0.15)
				)
				(justify left bottom)
				(hide yes)
			)
		)
		(pin "1"
		)
		(pin "2"
		)
		(instances
			(project "OCuLink to 10GbE adapter"
				(path ""
					(reference "C149")
					(unit 1)
				)
			)
			(project "thunderbolt-to-10gbe-adapter"
				(path ""
					(reference "C231")
					(unit 1)
				)
			)
		)
	)
	(symbol
		(lib_id "antmicroCapacitors0402:C_1u_25V_0402")
		(at 124.46 52.07 90)
		(unit 1)
		(exclude_from_sim no)
		(in_bom yes)
		(on_board yes)
		(dnp no)
		(property "Reference" "C184"
			(at 126.492 48.26 90)
			(effects
				(font
					(size 1.27 1.27)
					(thickness 0.15)
				)
				(justify right)
			)
		)
		(property "Value" "C_1u_25V_0402"
			(at 134.62 31.75 0)
			(effects
				(font
					(size 1.27 1.27)
					(thickness 0.15)
				)
				(justify left bottom)
				(hide yes)
			)
		)
		(property "Footprint" "antmicro-footprints:C_0402_1005Metric"
			(at 137.16 31.75 0)
			(effects
				(font
					(size 1.27 1.27)
					(thickness 0.15)
				)
				(justify left bottom)
				(hide yes)
			)
		)
		(property "Datasheet" "https://www.murata.com/products/productdetail?partno=GRM155R61E105KE11%23"
			(at 139.7 31.75 0)
			(effects
				(font
					(size 1.27 1.27)
					(thickness 0.15)
				)
				(justify left bottom)
				(hide yes)
			)
		)
		(property "Description" "SMD Multilayer Ceramic Capacitor, 1 µF, 25 V, 0402 [1005 Metric], ± 10%, X5R, GRM Series"
			(at 124.46 52.07 0)
			(effects
				(font
					(size 1.27 1.27)
				)
				(hide yes)
			)
		)
		(property "MPN" "GRM155R61E105KE11J"
			(at 142.24 31.75 0)
			(effects
				(font
					(size 1.27 1.27)
					(thickness 0.15)
				)
				(justify left bottom)
				(hide yes)
			)
		)
		(property "Manufacturer" "Murata"
			(at 144.78 31.75 0)
			(effects
				(font
					(size 1.27 1.27)
					(thickness 0.15)
				)
				(justify left bottom)
				(hide yes)
			)
		)
		(property "License" "Apache-2.0"
			(at 147.32 31.75 0)
			(effects
				(font
					(size 1.27 1.27)
					(thickness 0.15)
				)
				(justify left bottom)
				(hide yes)
			)
		)
		(property "Author" "Antmicro"
			(at 149.86 31.75 0)
			(effects
				(font
					(size 1.27 1.27)
					(thickness 0.15)
				)
				(justify left bottom)
				(hide yes)
			)
		)
		(property "Val" "1u"
			(at 126.492 50.8 90)
			(effects
				(font
					(size 1.27 1.27)
					(thickness 0.15)
				)
				(justify right)
			)
		)
		(property "Voltage" "25V"
			(at 152.4 31.75 0)
			(effects
				(font
					(size 1.27 1.27)
				)
				(justify left bottom)
				(hide yes)
			)
		)
		(property "Dielectric" "X5R"
			(at 154.94 31.75 0)
			(effects
				(font
					(size 1.27 1.27)
				)
				(justify left bottom)
				(hide yes)
			)
		)
		(pin "2"
		)
		(pin "1"
		)
		(instances
			(project "OCuLink to 10GbE adapter"
				(path ""
					(reference "C83")
					(unit 1)
				)
			)
			(project "thunderbolt-to-10gbe-adapter"
				(path ""
					(reference "C184")
					(unit 1)
				)
			)
		)
	)
	(symbol
		(lib_id "antmicroCapacitors0603:C_22u_16V_0603")
		(at 76.2 153.67 90)
		(unit 1)
		(exclude_from_sim no)
		(in_bom yes)
		(on_board yes)
		(dnp no)
		(property "Reference" "C155"
			(at 78.232 149.86 90)
			(effects
				(font
					(size 1.27 1.27)
					(thickness 0.15)
				)
				(justify right)
			)
		)
		(property "Value" "C_22u_16V_0603"
			(at 86.36 133.35 0)
			(effects
				(font
					(size 1.27 1.27)
					(thickness 0.15)
				)
				(justify left bottom)
				(hide yes)
			)
		)
		(property "Footprint" "antmicro-footprints:C_0603_1608Metric_EIA"
			(at 88.9 133.35 0)
			(effects
				(font
					(size 1.27 1.27)
					(thickness 0.15)
				)
				(justify left bottom)
				(hide yes)
			)
		)
		(property "Datasheet" "https://product.samsungsem.com/mlcc/CL10A226MO7JZN.do"
			(at 91.44 133.35 0)
			(effects
				(font
					(size 1.27 1.27)
					(thickness 0.15)
				)
				(justify left bottom)
				(hide yes)
			)
		)
		(property "Description" "SMD Multilayer Ceramic Capacitor"
			(at 76.2 153.67 0)
			(effects
				(font
					(size 1.27 1.27)
				)
				(hide yes)
			)
		)
		(property "MPN" "CL10A226MO7JZNC"
			(at 93.98 133.35 0)
			(effects
				(font
					(size 1.27 1.27)
					(thickness 0.15)
				)
				(justify left bottom)
				(hide yes)
			)
		)
		(property "Manufacturer" "Samsung Electro-Mechanics"
			(at 96.52 133.35 0)
			(effects
				(font
					(size 1.27 1.27)
					(thickness 0.15)
				)
				(justify left bottom)
				(hide yes)
			)
		)
		(property "License" "Apache-2.0"
			(at 99.06 133.35 0)
			(effects
				(font
					(size 1.27 1.27)
					(thickness 0.15)
				)
				(justify left bottom)
				(hide yes)
			)
		)
		(property "Author" "Antmicro"
			(at 101.6 133.35 0)
			(effects
				(font
					(size 1.27 1.27)
					(thickness 0.15)
				)
				(justify left bottom)
				(hide yes)
			)
		)
		(property "Val" "22u"
			(at 78.232 152.4 90)
			(effects
				(font
					(size 1.27 1.27)
					(thickness 0.15)
				)
				(justify right)
			)
		)
		(property "Voltage" "16V"
			(at 104.14 133.35 0)
			(effects
				(font
					(size 1.27 1.27)
				)
				(justify left bottom)
				(hide yes)
			)
		)
		(property "Dielectric" ""
			(at 106.68 133.35 0)
			(effects
				(font
					(size 1.27 1.27)
				)
				(justify left bottom)
				(hide yes)
			)
		)
		(pin "1"
		)
		(pin "2"
		)
		(instances
			(project "OCuLink to 10GbE adapter"
				(path ""
					(reference "C161")
					(unit 1)
				)
			)
			(project "thunderbolt-to-10gbe-adapter"
				(path ""
					(reference "C155")
					(unit 1)
				)
			)
		)
	)
	(symbol
		(lib_id "antmicroTestPoints:TP_0.75mm_SMD")
		(at 238.76 179.07 0)
		(unit 1)
		(exclude_from_sim no)
		(in_bom no)
		(on_board yes)
		(dnp no)
		(fields_autoplaced yes)
		(property "Reference" "TP20"
			(at 243.84 179.07 0)
			(effects
				(font
					(size 1.27 1.27)
					(thickness 0.15)
				)
				(justify left)
			)
		)
		(property "Value" "TP_0.75mm_SMD"
			(at 248.92 182.88 0)
			(effects
				(font
					(size 1.27 1.27)
					(thickness 0.15)
				)
				(justify left bottom)
				(hide yes)
			)
		)
		(property "Footprint" "antmicro-footprints:TP_SMD_0.75mm"
			(at 248.92 185.42 0)
			(effects
				(font
					(size 1.27 1.27)
					(thickness 0.15)
				)
				(justify left bottom)
				(hide yes)
			)
		)
		(property "Datasheet" ""
			(at 256.54 191.77 0)
			(effects
				(font
					(size 1.27 1.27)
					(thickness 0.15)
				)
				(justify left bottom)
				(hide yes)
			)
		)
		(property "Description" "SMT test point"
			(at 249.555 193.04 0)
			(effects
				(font
					(size 1.27 1.27)
				)
				(justify left bottom)
				(hide yes)
			)
		)
		(property "MPN" ""
			(at 249.555 190.5 0)
			(effects
				(font
					(size 1.27 1.27)
					(thickness 0.15)
				)
				(justify left bottom)
				(hide yes)
			)
		)
		(property "Manufacturer" ""
			(at 249.555 185.42 0)
			(effects
				(font
					(size 1.27 1.27)
					(thickness 0.15)
				)
				(justify left bottom)
				(hide yes)
			)
		)
		(property "Author" "Antmicro"
			(at 248.92 187.96 0)
			(effects
				(font
					(size 1.27 1.27)
					(thickness 0.15)
				)
				(justify left bottom)
				(hide yes)
			)
		)
		(property "License" "Apache-2.0"
			(at 248.92 190.5 0)
			(effects
				(font
					(size 1.27 1.27)
					(thickness 0.15)
				)
				(justify left bottom)
				(hide yes)
			)
		)
		(pin "1"
		)
		(instances
			(project "oculink-to-10gbe-adapter"
				(path ""
					(reference "TP35")
					(unit 1)
				)
			)
			(project "thunderbolt-to-10gbe-adapter"
				(path ""
					(reference "TP20")
					(unit 1)
				)
			)
		)
	)
	(symbol
		(lib_id "antmicroCapacitorspol:C_Pol_100u_6V_KEMET-T490-A")
		(at 64.77 46.99 90)
		(mirror x)
		(unit 1)
		(exclude_from_sim no)
		(in_bom yes)
		(on_board yes)
		(dnp no)
		(fields_autoplaced yes)
		(property "Reference" "C154"
			(at 62.23 47.7266 90)
			(effects
				(font
					(size 1.27 1.27)
					(thickness 0.15)
				)
				(justify left)
			)
		)
		(property "Value" "C_Pol_100u_6V_KEMET-T490-A"
			(at 67.31 60.96 0)
			(effects
				(font
					(size 1.27 1.27)
					(thickness 0.15)
				)
				(justify left bottom)
				(hide yes)
			)
		)
		(property "Footprint" "antmicro-footprints:C_Pol_EIA-A"
			(at 72.39 60.96 0)
			(effects
				(font
					(size 1.27 1.27)
					(thickness 0.15)
				)
				(justify left bottom)
				(hide yes)
			)
		)
		(property "Datasheet" "https://www.kemet.com/en/us/capacitors/product/T490A107M006ATE800.html"
			(at 74.93 60.96 0)
			(effects
				(font
					(size 1.27 1.27)
					(thickness 0.15)
				)
				(justify left bottom)
				(hide yes)
			)
		)
		(property "Description" "Surface Mount Tantalum Capacitor,  Solid SMD 6V 100uF 1206 20% ESR=800mOhms"
			(at 90.17 60.96 0)
			(effects
				(font
					(size 1.27 1.27)
				)
				(justify left bottom)
				(hide yes)
			)
		)
		(property "Val" "100u"
			(at 62.23 50.2666 90)
			(effects
				(font
					(size 1.27 1.27)
					(thickness 0.15)
				)
				(justify left)
			)
		)
		(property "MPN" "T490A107M006ATE800"
			(at 77.47 60.96 0)
			(effects
				(font
					(size 1.27 1.27)
					(thickness 0.15)
				)
				(justify left bottom)
				(hide yes)
			)
		)
		(property "Manufacturer" "KEMET"
			(at 80.01 60.96 0)
			(effects
				(font
					(size 1.27 1.27)
					(thickness 0.15)
				)
				(justify left bottom)
				(hide yes)
			)
		)
		(property "License" "Apache-2.0"
			(at 82.55 60.96 0)
			(effects
				(font
					(size 1.27 1.27)
					(thickness 0.15)
				)
				(justify left bottom)
				(hide yes)
			)
		)
		(property "Author" "Antmicro"
			(at 85.09 60.96 0)
			(effects
				(font
					(size 1.27 1.27)
					(thickness 0.15)
				)
				(justify left bottom)
				(hide yes)
			)
		)
		(property "Voltage" "6V"
			(at 87.63 60.96 0)
			(effects
				(font
					(size 1.27 1.27)
				)
				(justify left bottom)
				(hide yes)
			)
		)
		(property "Dielectric" "template_dielectric"
			(at 90.17 60.96 0)
			(effects
				(font
					(size 1.27 1.27)
				)
				(justify left bottom)
				(hide yes)
			)
		)
		(pin "2"
		)
		(pin "1"
		)
		(instances
			(project "thunderbolt-to-10gbe-adapter"
				(path ""
					(reference "C154")
					(unit 1)
				)
			)
		)
	)
	(symbol
		(lib_id "antmicroCapacitors0603:C_22u_16V_0603")
		(at 81.28 52.07 90)
		(unit 1)
		(exclude_from_sim no)
		(in_bom yes)
		(on_board yes)
		(dnp no)
		(property "Reference" "C165"
			(at 83.312 48.26 90)
			(effects
				(font
					(size 1.27 1.27)
					(thickness 0.15)
				)
				(justify right)
			)
		)
		(property "Value" "C_22u_16V_0603"
			(at 91.44 31.75 0)
			(effects
				(font
					(size 1.27 1.27)
					(thickness 0.15)
				)
				(justify left bottom)
				(hide yes)
			)
		)
		(property "Footprint" "antmicro-footprints:C_0603_1608Metric_EIA"
			(at 93.98 31.75 0)
			(effects
				(font
					(size 1.27 1.27)
					(thickness 0.15)
				)
				(justify left bottom)
				(hide yes)
			)
		)
		(property "Datasheet" "https://product.samsungsem.com/mlcc/CL10A226MO7JZN.do"
			(at 96.52 31.75 0)
			(effects
				(font
					(size 1.27 1.27)
					(thickness 0.15)
				)
				(justify left bottom)
				(hide yes)
			)
		)
		(property "Description" "SMD Multilayer Ceramic Capacitor"
			(at 81.28 52.07 0)
			(effects
				(font
					(size 1.27 1.27)
				)
				(hide yes)
			)
		)
		(property "MPN" "CL10A226MO7JZNC"
			(at 99.06 31.75 0)
			(effects
				(font
					(size 1.27 1.27)
					(thickness 0.15)
				)
				(justify left bottom)
				(hide yes)
			)
		)
		(property "Manufacturer" "Samsung Electro-Mechanics"
			(at 101.6 31.75 0)
			(effects
				(font
					(size 1.27 1.27)
					(thickness 0.15)
				)
				(justify left bottom)
				(hide yes)
			)
		)
		(property "License" "Apache-2.0"
			(at 104.14 31.75 0)
			(effects
				(font
					(size 1.27 1.27)
					(thickness 0.15)
				)
				(justify left bottom)
				(hide yes)
			)
		)
		(property "Author" "Antmicro"
			(at 106.68 31.75 0)
			(effects
				(font
					(size 1.27 1.27)
					(thickness 0.15)
				)
				(justify left bottom)
				(hide yes)
			)
		)
		(property "Val" "22u"
			(at 83.312 50.8 90)
			(effects
				(font
					(size 1.27 1.27)
					(thickness 0.15)
				)
				(justify right)
			)
		)
		(property "Voltage" "16V"
			(at 109.22 31.75 0)
			(effects
				(font
					(size 1.27 1.27)
				)
				(justify left bottom)
				(hide yes)
			)
		)
		(property "Dielectric" ""
			(at 111.76 31.75 0)
			(effects
				(font
					(size 1.27 1.27)
				)
				(justify left bottom)
				(hide yes)
			)
		)
		(pin "1"
		)
		(pin "2"
		)
		(instances
			(project "OCuLink to 10GbE adapter"
				(path ""
					(reference "C79")
					(unit 1)
				)
			)
			(project "thunderbolt-to-10gbe-adapter"
				(path ""
					(reference "C165")
					(unit 1)
				)
			)
		)
	)
	(symbol
		(lib_id "antmicropower:GND")
		(at 66.04 156.21 0)
		(unit 1)
		(exclude_from_sim no)
		(in_bom yes)
		(on_board yes)
		(dnp no)
		(property "Reference" "#PWR0506"
			(at 74.93 158.75 0)
			(effects
				(font
					(size 1.27 1.27)
					(thickness 0.15)
				)
				(justify left bottom)
				(hide yes)
			)
		)
		(property "Value" "GND"
			(at 66.04 160.02 0)
			(effects
				(font
					(size 1.27 1.27)
					(thickness 0.15)
				)
			)
		)
		(property "Footprint" ""
			(at 74.93 163.83 0)
			(effects
				(font
					(size 1.27 1.27)
					(thickness 0.15)
				)
				(justify left bottom)
				(hide yes)
			)
		)
		(property "Datasheet" ""
			(at 74.93 168.91 0)
			(effects
				(font
					(size 1.27 1.27)
					(thickness 0.15)
				)
				(justify left bottom)
				(hide yes)
			)
		)
		(property "Description" ""
			(at 66.04 156.21 0)
			(effects
				(font
					(size 1.27 1.27)
				)
				(hide yes)
			)
		)
		(property "Author" "Antmicro"
			(at 74.93 163.83 0)
			(effects
				(font
					(size 1.27 1.27)
					(thickness 0.15)
				)
				(justify left bottom)
				(hide yes)
			)
		)
		(property "License" "Apache-2.0"
			(at 74.93 166.37 0)
			(effects
				(font
					(size 1.27 1.27)
					(thickness 0.15)
				)
				(justify left bottom)
				(hide yes)
			)
		)
		(pin "1"
		)
		(instances
			(project "thunderbolt-to-10gbe-adapter"
				(path ""
					(reference "#PWR0506")
					(unit 1)
				)
			)
		)
	)
	(symbol
		(lib_id "antmicroCapacitors0402:C_1u_25V_0402")
		(at 379.73 73.66 90)
		(unit 1)
		(exclude_from_sim no)
		(in_bom yes)
		(on_board yes)
		(dnp no)
		(property "Reference" "C256"
			(at 381.762 69.85 90)
			(effects
				(font
					(size 1.27 1.27)
					(thickness 0.15)
				)
				(justify right)
			)
		)
		(property "Value" "C_1u_25V_0402"
			(at 389.89 53.34 0)
			(effects
				(font
					(size 1.27 1.27)
					(thickness 0.15)
				)
				(justify left bottom)
				(hide yes)
			)
		)
		(property "Footprint" "antmicro-footprints:C_0402_1005Metric"
			(at 392.43 53.34 0)
			(effects
				(font
					(size 1.27 1.27)
					(thickness 0.15)
				)
				(justify left bottom)
				(hide yes)
			)
		)
		(property "Datasheet" "https://www.murata.com/products/productdetail?partno=GRM155R61E105KE11%23"
			(at 394.97 53.34 0)
			(effects
				(font
					(size 1.27 1.27)
					(thickness 0.15)
				)
				(justify left bottom)
				(hide yes)
			)
		)
		(property "Description" "SMD Multilayer Ceramic Capacitor, 1 µF, 25 V, 0402 [1005 Metric], ± 10%, X5R, GRM Series"
			(at 379.73 73.66 0)
			(effects
				(font
					(size 1.27 1.27)
				)
				(hide yes)
			)
		)
		(property "MPN" "GRM155R61E105KE11J"
			(at 397.51 53.34 0)
			(effects
				(font
					(size 1.27 1.27)
					(thickness 0.15)
				)
				(justify left bottom)
				(hide yes)
			)
		)
		(property "Manufacturer" "Murata"
			(at 400.05 53.34 0)
			(effects
				(font
					(size 1.27 1.27)
					(thickness 0.15)
				)
				(justify left bottom)
				(hide yes)
			)
		)
		(property "License" "Apache-2.0"
			(at 402.59 53.34 0)
			(effects
				(font
					(size 1.27 1.27)
					(thickness 0.15)
				)
				(justify left bottom)
				(hide yes)
			)
		)
		(property "Author" "Antmicro"
			(at 405.13 53.34 0)
			(effects
				(font
					(size 1.27 1.27)
					(thickness 0.15)
				)
				(justify left bottom)
				(hide yes)
			)
		)
		(property "Val" "1u"
			(at 381.762 72.39 90)
			(effects
				(font
					(size 1.27 1.27)
					(thickness 0.15)
				)
				(justify right)
			)
		)
		(property "Voltage" "25V"
			(at 407.67 53.34 0)
			(effects
				(font
					(size 1.27 1.27)
				)
				(justify left bottom)
				(hide yes)
			)
		)
		(property "Dielectric" "X5R"
			(at 410.21 53.34 0)
			(effects
				(font
					(size 1.27 1.27)
				)
				(justify left bottom)
				(hide yes)
			)
		)
		(pin "2"
		)
		(pin "1"
		)
		(instances
			(project "OCuLink to 10GbE adapter"
				(path ""
					(reference "C114")
					(unit 1)
				)
			)
			(project "thunderbolt-to-10gbe-adapter"
				(path ""
					(reference "C256")
					(unit 1)
				)
			)
		)
	)
	(symbol
		(lib_id "antmicroCapacitors0402:C_1u_25V_0402")
		(at 124.46 153.67 90)
		(unit 1)
		(exclude_from_sim no)
		(in_bom yes)
		(on_board yes)
		(dnp no)
		(property "Reference" "C187"
			(at 126.492 149.86 90)
			(effects
				(font
					(size 1.27 1.27)
					(thickness 0.15)
				)
				(justify right)
			)
		)
		(property "Value" "C_1u_25V_0402"
			(at 134.62 133.35 0)
			(effects
				(font
					(size 1.27 1.27)
					(thickness 0.15)
				)
				(justify left bottom)
				(hide yes)
			)
		)
		(property "Footprint" "antmicro-footprints:C_0402_1005Metric"
			(at 137.16 133.35 0)
			(effects
				(font
					(size 1.27 1.27)
					(thickness 0.15)
				)
				(justify left bottom)
				(hide yes)
			)
		)
		(property "Datasheet" "https://www.murata.com/products/productdetail?partno=GRM155R61E105KE11%23"
			(at 139.7 133.35 0)
			(effects
				(font
					(size 1.27 1.27)
					(thickness 0.15)
				)
				(justify left bottom)
				(hide yes)
			)
		)
		(property "Description" "SMD Multilayer Ceramic Capacitor, 1 µF, 25 V, 0402 [1005 Metric], ± 10%, X5R, GRM Series"
			(at 124.46 153.67 0)
			(effects
				(font
					(size 1.27 1.27)
				)
				(hide yes)
			)
		)
		(property "MPN" "GRM155R61E105KE11J"
			(at 142.24 133.35 0)
			(effects
				(font
					(size 1.27 1.27)
					(thickness 0.15)
				)
				(justify left bottom)
				(hide yes)
			)
		)
		(property "Manufacturer" "Murata"
			(at 144.78 133.35 0)
			(effects
				(font
					(size 1.27 1.27)
					(thickness 0.15)
				)
				(justify left bottom)
				(hide yes)
			)
		)
		(property "License" "Apache-2.0"
			(at 147.32 133.35 0)
			(effects
				(font
					(size 1.27 1.27)
					(thickness 0.15)
				)
				(justify left bottom)
				(hide yes)
			)
		)
		(property "Author" "Antmicro"
			(at 149.86 133.35 0)
			(effects
				(font
					(size 1.27 1.27)
					(thickness 0.15)
				)
				(justify left bottom)
				(hide yes)
			)
		)
		(property "Val" "1u"
			(at 126.492 152.4 90)
			(effects
				(font
					(size 1.27 1.27)
					(thickness 0.15)
				)
				(justify right)
			)
		)
		(property "Voltage" "25V"
			(at 152.4 133.35 0)
			(effects
				(font
					(size 1.27 1.27)
				)
				(justify left bottom)
				(hide yes)
			)
		)
		(property "Dielectric" "X5R"
			(at 154.94 133.35 0)
			(effects
				(font
					(size 1.27 1.27)
				)
				(justify left bottom)
				(hide yes)
			)
		)
		(pin "2"
		)
		(pin "1"
		)
		(instances
			(project "OCuLink to 10GbE adapter"
				(path ""
					(reference "C166")
					(unit 1)
				)
			)
			(project "thunderbolt-to-10gbe-adapter"
				(path ""
					(reference "C187")
					(unit 1)
				)
			)
		)
	)
	(symbol
		(lib_id "antmicropower:GND")
		(at 379.73 54.61 0)
		(unit 1)
		(exclude_from_sim no)
		(in_bom yes)
		(on_board yes)
		(dnp no)
		(property "Reference" "#PWR0341"
			(at 388.62 57.15 0)
			(effects
				(font
					(size 1.27 1.27)
					(thickness 0.15)
				)
				(justify left bottom)
				(hide yes)
			)
		)
		(property "Value" "GND"
			(at 379.73 58.42 0)
			(effects
				(font
					(size 1.27 1.27)
					(thickness 0.15)
				)
			)
		)
		(property "Footprint" ""
			(at 388.62 62.23 0)
			(effects
				(font
					(size 1.27 1.27)
					(thickness 0.15)
				)
				(justify left bottom)
				(hide yes)
			)
		)
		(property "Datasheet" ""
			(at 388.62 67.31 0)
			(effects
				(font
					(size 1.27 1.27)
					(thickness 0.15)
				)
				(justify left bottom)
				(hide yes)
			)
		)
		(property "Description" ""
			(at 379.73 54.61 0)
			(effects
				(font
					(size 1.27 1.27)
				)
				(hide yes)
			)
		)
		(property "Author" "Antmicro"
			(at 388.62 62.23 0)
			(effects
				(font
					(size 1.27 1.27)
					(thickness 0.15)
				)
				(justify left bottom)
				(hide yes)
			)
		)
		(property "License" "Apache-2.0"
			(at 388.62 64.77 0)
			(effects
				(font
					(size 1.27 1.27)
					(thickness 0.15)
				)
				(justify left bottom)
				(hide yes)
			)
		)
		(pin "1"
		)
		(instances
			(project "OCuLink to 10GbE adapter"
				(path ""
					(reference "#PWR0130")
					(unit 1)
				)
			)
			(project "thunderbolt-to-10gbe-adapter"
				(path ""
					(reference "#PWR0341")
					(unit 1)
				)
			)
		)
	)
	(symbol
		(lib_id "antmicroCapacitorsmisc:C_100u_0805")
		(at 106.68 153.67 90)
		(unit 1)
		(exclude_from_sim no)
		(in_bom yes)
		(on_board yes)
		(dnp no)
		(property "Reference" "C178"
			(at 108.458 149.86 90)
			(effects
				(font
					(size 1.27 1.27)
					(thickness 0.15)
				)
				(justify right)
			)
		)
		(property "Value" "C_100u_0805"
			(at 116.84 133.35 0)
			(effects
				(font
					(size 1.27 1.27)
					(thickness 0.15)
				)
				(justify left bottom)
				(hide yes)
			)
		)
		(property "Footprint" "antmicro-footprints:C_0805_2012Metric"
			(at 119.38 133.35 0)
			(effects
				(font
					(size 1.27 1.27)
					(thickness 0.15)
				)
				(justify left bottom)
				(hide yes)
			)
		)
		(property "Datasheet" "https://www.murata.com/products/productdetail?partno=GRM21BR60J107ME15%23"
			(at 121.92 133.35 0)
			(effects
				(font
					(size 1.27 1.27)
					(thickness 0.15)
				)
				(justify left bottom)
				(hide yes)
			)
		)
		(property "Description" "SMD Multilayer Ceramic Capacitor, 100 µF, 6.3 V, 0805 [2012 Metric], ± 20%, X5R, GRM Series"
			(at 106.68 153.67 0)
			(effects
				(font
					(size 1.27 1.27)
				)
				(hide yes)
			)
		)
		(property "MPN" "GRM21BR60J107ME15L"
			(at 124.46 133.35 0)
			(effects
				(font
					(size 1.27 1.27)
					(thickness 0.15)
				)
				(justify left bottom)
				(hide yes)
			)
		)
		(property "Manufacturer" "Murata"
			(at 127 133.35 0)
			(effects
				(font
					(size 1.27 1.27)
					(thickness 0.15)
				)
				(justify left bottom)
				(hide yes)
			)
		)
		(property "License" "Apache-2.0"
			(at 129.54 133.35 0)
			(effects
				(font
					(size 1.27 1.27)
					(thickness 0.15)
				)
				(justify left bottom)
				(hide yes)
			)
		)
		(property "Author" "Antmicro"
			(at 132.08 133.35 0)
			(effects
				(font
					(size 1.27 1.27)
					(thickness 0.15)
				)
				(justify left bottom)
				(hide yes)
			)
		)
		(property "Val" "100u"
			(at 108.458 152.4 90)
			(effects
				(font
					(size 1.27 1.27)
					(thickness 0.15)
				)
				(justify right)
			)
		)
		(property "Voltage" ""
			(at 134.62 133.35 0)
			(effects
				(font
					(size 1.27 1.27)
				)
				(justify left bottom)
				(hide yes)
			)
		)
		(property "Dielectric" ""
			(at 137.16 133.35 0)
			(effects
				(font
					(size 1.27 1.27)
				)
				(justify left bottom)
				(hide yes)
			)
		)
		(property "Public" "False"
			(at 139.7 133.35 0)
			(effects
				(font
					(size 1.27 1.27)
				)
				(justify left bottom)
				(hide yes)
			)
		)
		(pin "1"
		)
		(pin "2"
		)
		(instances
			(project "OCuLink to 10GbE adapter"
				(path ""
					(reference "C164")
					(unit 1)
				)
			)
			(project "thunderbolt-to-10gbe-adapter"
				(path ""
					(reference "C178")
					(unit 1)
				)
			)
		)
	)
	(symbol
		(lib_id "antmicropower:GND")
		(at 151.13 209.55 0)
		(unit 1)
		(exclude_from_sim no)
		(in_bom yes)
		(on_board yes)
		(dnp no)
		(property "Reference" "#PWR0278"
			(at 160.02 212.09 0)
			(effects
				(font
					(size 1.27 1.27)
					(thickness 0.15)
				)
				(justify left bottom)
				(hide yes)
			)
		)
		(property "Value" "GND"
			(at 151.13 213.36 0)
			(effects
				(font
					(size 1.27 1.27)
					(thickness 0.15)
				)
			)
		)
		(property "Footprint" ""
			(at 160.02 217.17 0)
			(effects
				(font
					(size 1.27 1.27)
					(thickness 0.15)
				)
				(justify left bottom)
				(hide yes)
			)
		)
		(property "Datasheet" ""
			(at 160.02 222.25 0)
			(effects
				(font
					(size 1.27 1.27)
					(thickness 0.15)
				)
				(justify left bottom)
				(hide yes)
			)
		)
		(property "Description" ""
			(at 151.13 209.55 0)
			(effects
				(font
					(size 1.27 1.27)
				)
				(hide yes)
			)
		)
		(property "Author" "Antmicro"
			(at 160.02 217.17 0)
			(effects
				(font
					(size 1.27 1.27)
					(thickness 0.15)
				)
				(justify left bottom)
				(hide yes)
			)
		)
		(property "License" "Apache-2.0"
			(at 160.02 219.71 0)
			(effects
				(font
					(size 1.27 1.27)
					(thickness 0.15)
				)
				(justify left bottom)
				(hide yes)
			)
		)
		(pin "1"
		)
		(instances
			(project "OCuLink to 10GbE adapter"
				(path ""
					(reference "#PWR0237")
					(unit 1)
				)
			)
			(project "thunderbolt-to-10gbe-adapter"
				(path ""
					(reference "#PWR0278")
					(unit 1)
				)
			)
		)
	)
	(symbol
		(lib_id "antmicroCapacitorspol:C_Pol_100u_6V_KEMET-T490-A")
		(at 55.88 46.99 90)
		(mirror x)
		(unit 1)
		(exclude_from_sim no)
		(in_bom yes)
		(on_board yes)
		(dnp no)
		(fields_autoplaced yes)
		(property "Reference" "C329"
			(at 53.34 47.7266 90)
			(effects
				(font
					(size 1.27 1.27)
					(thickness 0.15)
				)
				(justify left)
			)
		)
		(property "Value" "C_Pol_100u_6V_KEMET-T490-A"
			(at 58.42 60.96 0)
			(effects
				(font
					(size 1.27 1.27)
					(thickness 0.15)
				)
				(justify left bottom)
				(hide yes)
			)
		)
		(property "Footprint" "antmicro-footprints:C_Pol_EIA-A"
			(at 63.5 60.96 0)
			(effects
				(font
					(size 1.27 1.27)
					(thickness 0.15)
				)
				(justify left bottom)
				(hide yes)
			)
		)
		(property "Datasheet" "https://www.kemet.com/en/us/capacitors/product/T490A107M006ATE800.html"
			(at 66.04 60.96 0)
			(effects
				(font
					(size 1.27 1.27)
					(thickness 0.15)
				)
				(justify left bottom)
				(hide yes)
			)
		)
		(property "Description" "Surface Mount Tantalum Capacitor,  Solid SMD 6V 100uF 1206 20% ESR=800mOhms"
			(at 81.28 60.96 0)
			(effects
				(font
					(size 1.27 1.27)
				)
				(justify left bottom)
				(hide yes)
			)
		)
		(property "Val" "100u"
			(at 53.34 50.2666 90)
			(effects
				(font
					(size 1.27 1.27)
					(thickness 0.15)
				)
				(justify left)
			)
		)
		(property "MPN" "T490A107M006ATE800"
			(at 68.58 60.96 0)
			(effects
				(font
					(size 1.27 1.27)
					(thickness 0.15)
				)
				(justify left bottom)
				(hide yes)
			)
		)
		(property "Manufacturer" "KEMET"
			(at 71.12 60.96 0)
			(effects
				(font
					(size 1.27 1.27)
					(thickness 0.15)
				)
				(justify left bottom)
				(hide yes)
			)
		)
		(property "License" "Apache-2.0"
			(at 73.66 60.96 0)
			(effects
				(font
					(size 1.27 1.27)
					(thickness 0.15)
				)
				(justify left bottom)
				(hide yes)
			)
		)
		(property "Author" "Antmicro"
			(at 76.2 60.96 0)
			(effects
				(font
					(size 1.27 1.27)
					(thickness 0.15)
				)
				(justify left bottom)
				(hide yes)
			)
		)
		(property "Voltage" "6V"
			(at 78.74 60.96 0)
			(effects
				(font
					(size 1.27 1.27)
				)
				(justify left bottom)
				(hide yes)
			)
		)
		(property "Dielectric" "template_dielectric"
			(at 81.28 60.96 0)
			(effects
				(font
					(size 1.27 1.27)
				)
				(justify left bottom)
				(hide yes)
			)
		)
		(pin "2"
		)
		(pin "1"
		)
		(instances
			(project "thunderbolt-to-10gbe-adapter"
				(path ""
					(reference "C329")
					(unit 1)
				)
			)
		)
	)
	(symbol
		(lib_id "antmicropower:GND")
		(at 124.46 129.54 0)
		(unit 1)
		(exclude_from_sim no)
		(in_bom yes)
		(on_board yes)
		(dnp no)
		(property "Reference" "#PWR0257"
			(at 133.35 132.08 0)
			(effects
				(font
					(size 1.27 1.27)
					(thickness 0.15)
				)
				(justify left bottom)
				(hide yes)
			)
		)
		(property "Value" "GND"
			(at 124.46 133.35 0)
			(effects
				(font
					(size 1.27 1.27)
					(thickness 0.15)
				)
			)
		)
		(property "Footprint" ""
			(at 133.35 137.16 0)
			(effects
				(font
					(size 1.27 1.27)
					(thickness 0.15)
				)
				(justify left bottom)
				(hide yes)
			)
		)
		(property "Datasheet" ""
			(at 133.35 142.24 0)
			(effects
				(font
					(size 1.27 1.27)
					(thickness 0.15)
				)
				(justify left bottom)
				(hide yes)
			)
		)
		(property "Description" ""
			(at 124.46 129.54 0)
			(effects
				(font
					(size 1.27 1.27)
				)
				(hide yes)
			)
		)
		(property "Author" "Antmicro"
			(at 133.35 137.16 0)
			(effects
				(font
					(size 1.27 1.27)
					(thickness 0.15)
				)
				(justify left bottom)
				(hide yes)
			)
		)
		(property "License" "Apache-2.0"
			(at 133.35 139.7 0)
			(effects
				(font
					(size 1.27 1.27)
					(thickness 0.15)
				)
				(justify left bottom)
				(hide yes)
			)
		)
		(pin "1"
		)
		(instances
			(project "OCuLink to 10GbE adapter"
				(path ""
					(reference "#PWR0191")
					(unit 1)
				)
			)
			(project "thunderbolt-to-10gbe-adapter"
				(path ""
					(reference "#PWR0257")
					(unit 1)
				)
			)
		)
	)
	(symbol
		(lib_id "antmicroCapacitors0603:C_10u_10V_X7R_0603")
		(at 88.9 127 90)
		(unit 1)
		(exclude_from_sim no)
		(in_bom yes)
		(on_board yes)
		(dnp no)
		(property "Reference" "C169"
			(at 90.678 123.19 90)
			(effects
				(font
					(size 1.27 1.27)
					(thickness 0.15)
				)
				(justify right)
			)
		)
		(property "Value" "C_10u_10V_X7R_0603"
			(at 99.06 111.76 0)
			(effects
				(font
					(size 1.27 1.27)
					(thickness 0.15)
				)
				(justify left bottom)
				(hide yes)
			)
		)
		(property "Footprint" "antmicro-footprints:C_0603_1608Metric"
			(at 101.6 111.76 0)
			(effects
				(font
					(size 1.27 1.27)
					(thickness 0.15)
				)
				(justify left bottom)
				(hide yes)
			)
		)
		(property "Datasheet" "https://www.murata.com/products/productdetail?partno=GRM188Z71A106KA73%23"
			(at 104.14 111.76 0)
			(effects
				(font
					(size 1.27 1.27)
					(thickness 0.15)
				)
				(justify left bottom)
				(hide yes)
			)
		)
		(property "Description" "SMD Multilayer Ceramic Capacitor,  10µF, 10V, 0603, ±10%, X7R"
			(at 88.9 127 0)
			(effects
				(font
					(size 1.27 1.27)
				)
				(hide yes)
			)
		)
		(property "MPN" "GRM188Z71A106KA73D"
			(at 106.68 111.76 0)
			(effects
				(font
					(size 1.27 1.27)
					(thickness 0.15)
				)
				(justify left bottom)
				(hide yes)
			)
		)
		(property "Val" "10u"
			(at 90.678 125.73 90)
			(effects
				(font
					(size 1.27 1.27)
					(thickness 0.15)
				)
				(justify right)
			)
		)
		(property "Voltage" "10V"
			(at 109.22 111.76 0)
			(effects
				(font
					(size 1.27 1.27)
					(thickness 0.15)
				)
				(justify left bottom)
				(hide yes)
			)
		)
		(property "Dielectric" "X7R"
			(at 111.76 111.76 0)
			(effects
				(font
					(size 1.27 1.27)
					(thickness 0.15)
				)
				(justify left bottom)
				(hide yes)
			)
		)
		(property "Manufacturer" "Murata"
			(at 114.3 111.76 0)
			(effects
				(font
					(size 1.27 1.27)
					(thickness 0.15)
				)
				(justify left bottom)
				(hide yes)
			)
		)
		(property "License" "Apache-2.0"
			(at 116.84 111.76 0)
			(effects
				(font
					(size 1.27 1.27)
					(thickness 0.15)
				)
				(justify left bottom)
				(hide yes)
			)
		)
		(property "Author" "Antmicro"
			(at 119.38 111.76 0)
			(effects
				(font
					(size 1.27 1.27)
					(thickness 0.15)
				)
				(justify left bottom)
				(hide yes)
			)
		)
		(pin "1"
		)
		(pin "2"
		)
		(instances
			(project "OCuLink to 10GbE adapter"
				(path ""
					(reference "C139")
					(unit 1)
				)
			)
			(project "thunderbolt-to-10gbe-adapter"
				(path ""
					(reference "C169")
					(unit 1)
				)
			)
		)
	)
	(symbol
		(lib_id "antmicropower:GND")
		(at 335.28 115.57 0)
		(unit 1)
		(exclude_from_sim no)
		(in_bom yes)
		(on_board yes)
		(dnp no)
		(property "Reference" "#PWR0321"
			(at 344.17 118.11 0)
			(effects
				(font
					(size 1.27 1.27)
					(thickness 0.15)
				)
				(justify left bottom)
				(hide yes)
			)
		)
		(property "Value" "GND"
			(at 335.28 119.38 0)
			(effects
				(font
					(size 1.27 1.27)
					(thickness 0.15)
				)
			)
		)
		(property "Footprint" ""
			(at 344.17 123.19 0)
			(effects
				(font
					(size 1.27 1.27)
					(thickness 0.15)
				)
				(justify left bottom)
				(hide yes)
			)
		)
		(property "Datasheet" ""
			(at 344.17 128.27 0)
			(effects
				(font
					(size 1.27 1.27)
					(thickness 0.15)
				)
				(justify left bottom)
				(hide yes)
			)
		)
		(property "Description" ""
			(at 335.28 115.57 0)
			(effects
				(font
					(size 1.27 1.27)
				)
				(hide yes)
			)
		)
		(property "Author" "Antmicro"
			(at 344.17 123.19 0)
			(effects
				(font
					(size 1.27 1.27)
					(thickness 0.15)
				)
				(justify left bottom)
				(hide yes)
			)
		)
		(property "License" "Apache-2.0"
			(at 344.17 125.73 0)
			(effects
				(font
					(size 1.27 1.27)
					(thickness 0.15)
				)
				(justify left bottom)
				(hide yes)
			)
		)
		(pin "1"
		)
		(instances
			(project "OCuLink to 10GbE adapter"
				(path ""
					(reference "#PWR0181")
					(unit 1)
				)
			)
			(project "thunderbolt-to-10gbe-adapter"
				(path ""
					(reference "#PWR0321")
					(unit 1)
				)
			)
		)
	)
	(symbol
		(lib_id "antmicropower:GND")
		(at 115.57 54.61 0)
		(unit 1)
		(exclude_from_sim no)
		(in_bom yes)
		(on_board yes)
		(dnp no)
		(property "Reference" "#PWR0253"
			(at 124.46 57.15 0)
			(effects
				(font
					(size 1.27 1.27)
					(thickness 0.15)
				)
				(justify left bottom)
				(hide yes)
			)
		)
		(property "Value" "GND"
			(at 115.57 58.42 0)
			(effects
				(font
					(size 1.27 1.27)
					(thickness 0.15)
				)
			)
		)
		(property "Footprint" ""
			(at 124.46 62.23 0)
			(effects
				(font
					(size 1.27 1.27)
					(thickness 0.15)
				)
				(justify left bottom)
				(hide yes)
			)
		)
		(property "Datasheet" ""
			(at 124.46 67.31 0)
			(effects
				(font
					(size 1.27 1.27)
					(thickness 0.15)
				)
				(justify left bottom)
				(hide yes)
			)
		)
		(property "Description" ""
			(at 115.57 54.61 0)
			(effects
				(font
					(size 1.27 1.27)
				)
				(hide yes)
			)
		)
		(property "Author" "Antmicro"
			(at 124.46 62.23 0)
			(effects
				(font
					(size 1.27 1.27)
					(thickness 0.15)
				)
				(justify left bottom)
				(hide yes)
			)
		)
		(property "License" "Apache-2.0"
			(at 124.46 64.77 0)
			(effects
				(font
					(size 1.27 1.27)
					(thickness 0.15)
				)
				(justify left bottom)
				(hide yes)
			)
		)
		(pin "1"
		)
		(instances
			(project "OCuLink to 10GbE adapter"
				(path ""
					(reference "#PWR0116")
					(unit 1)
				)
			)
			(project "thunderbolt-to-10gbe-adapter"
				(path ""
					(reference "#PWR0253")
					(unit 1)
				)
			)
		)
	)
	(symbol
		(lib_id "antmicropower:+1V0")
		(at 26.67 250.19 0)
		(unit 1)
		(exclude_from_sim no)
		(in_bom yes)
		(on_board yes)
		(dnp no)
		(property "Reference" "#PWR0225"
			(at 26.67 254 0)
			(effects
				(font
					(size 1.27 1.27)
				)
				(hide yes)
			)
		)
		(property "Value" "+1V0"
			(at 26.67 246.126 0)
			(effects
				(font
					(size 1.27 1.27)
				)
			)
		)
		(property "Footprint" ""
			(at 26.67 250.19 0)
			(effects
				(font
					(size 1.27 1.27)
				)
				(hide yes)
			)
		)
		(property "Datasheet" ""
			(at 26.67 250.19 0)
			(effects
				(font
					(size 1.27 1.27)
				)
				(hide yes)
			)
		)
		(property "Description" ""
			(at 26.67 250.19 0)
			(effects
				(font
					(size 1.27 1.27)
				)
				(hide yes)
			)
		)
		(pin "1"
		)
		(instances
			(project "OCuLink to 10GbE adapter"
				(path ""
					(reference "#PWR0242")
					(unit 1)
				)
			)
			(project "thunderbolt-to-10gbe-adapter"
				(path ""
					(reference "#PWR0225")
					(unit 1)
				)
			)
		)
	)
	(symbol
		(lib_id "antmicroCapacitors0402:C_100n_0402")
		(at 77.47 100.33 90)
		(unit 1)
		(exclude_from_sim no)
		(in_bom yes)
		(on_board yes)
		(dnp no)
		(property "Reference" "C161"
			(at 79.502 96.52 90)
			(effects
				(font
					(size 1.27 1.27)
					(thickness 0.15)
				)
				(justify right)
			)
		)
		(property "Value" "C_100n_0402"
			(at 100.33 85.09 0)
			(effects
				(font
					(size 1.27 1.27)
					(thickness 0.15)
				)
				(justify left bottom)
				(hide yes)
			)
		)
		(property "Footprint" "antmicro-footprints:C_0402_1005Metric"
			(at 102.87 85.09 0)
			(effects
				(font
					(size 1.27 1.27)
					(thickness 0.15)
				)
				(justify left bottom)
				(hide yes)
			)
		)
		(property "Datasheet" "https://www.murata.com/products/productdetail?partno=GRM155R61H104KE14%23"
			(at 105.41 85.09 0)
			(effects
				(font
					(size 1.27 1.27)
					(thickness 0.15)
				)
				(justify left bottom)
				(hide yes)
			)
		)
		(property "Description" "SMD Multilayer Ceramic Capacitor, 0.1 µF, 50 V, 0402 [1005 Metric], ± 10%, X5R, GRM Series"
			(at 77.47 100.33 0)
			(effects
				(font
					(size 1.27 1.27)
				)
				(hide yes)
			)
		)
		(property "MPN" "GRM155R61H104KE14D"
			(at 107.95 85.09 0)
			(effects
				(font
					(size 1.27 1.27)
					(thickness 0.15)
				)
				(justify left bottom)
				(hide yes)
			)
		)
		(property "Val" "100n"
			(at 79.502 99.06 90)
			(effects
				(font
					(size 1.27 1.27)
					(thickness 0.15)
				)
				(justify right)
			)
		)
		(property "Voltage" "50V"
			(at 87.63 85.09 0)
			(effects
				(font
					(size 1.27 1.27)
					(thickness 0.15)
				)
				(justify left bottom)
				(hide yes)
			)
		)
		(property "Dielectric" "X5R"
			(at 90.17 85.09 0)
			(effects
				(font
					(size 1.27 1.27)
					(thickness 0.15)
				)
				(justify left bottom)
				(hide yes)
			)
		)
		(property "Manufacturer" "Murata"
			(at 92.71 85.09 0)
			(effects
				(font
					(size 1.27 1.27)
					(thickness 0.15)
				)
				(justify left bottom)
				(hide yes)
			)
		)
		(property "License" "Apache-2.0"
			(at 95.25 85.09 0)
			(effects
				(font
					(size 1.27 1.27)
					(thickness 0.15)
				)
				(justify left bottom)
				(hide yes)
			)
		)
		(property "Author" "Antmicro"
			(at 97.79 85.09 0)
			(effects
				(font
					(size 1.27 1.27)
					(thickness 0.15)
				)
				(justify left bottom)
				(hide yes)
			)
		)
		(pin "2"
		)
		(pin "1"
		)
		(instances
			(project "OCuLink to 10GbE adapter"
				(path ""
					(reference "C128")
					(unit 1)
				)
			)
			(project "thunderbolt-to-10gbe-adapter"
				(path ""
					(reference "C161")
					(unit 1)
				)
			)
		)
	)
	(symbol
		(lib_id "antmicroCapacitors0402:C_1u_25V_0402")
		(at 335.28 52.07 90)
		(unit 1)
		(exclude_from_sim no)
		(in_bom yes)
		(on_board yes)
		(dnp no)
		(property "Reference" "C232"
			(at 337.312 48.26 90)
			(effects
				(font
					(size 1.27 1.27)
					(thickness 0.15)
				)
				(justify right)
			)
		)
		(property "Value" "C_1u_25V_0402"
			(at 345.44 31.75 0)
			(effects
				(font
					(size 1.27 1.27)
					(thickness 0.15)
				)
				(justify left bottom)
				(hide yes)
			)
		)
		(property "Footprint" "antmicro-footprints:C_0402_1005Metric"
			(at 347.98 31.75 0)
			(effects
				(font
					(size 1.27 1.27)
					(thickness 0.15)
				)
				(justify left bottom)
				(hide yes)
			)
		)
		(property "Datasheet" "https://www.murata.com/products/productdetail?partno=GRM155R61E105KE11%23"
			(at 350.52 31.75 0)
			(effects
				(font
					(size 1.27 1.27)
					(thickness 0.15)
				)
				(justify left bottom)
				(hide yes)
			)
		)
		(property "Description" "SMD Multilayer Ceramic Capacitor, 1 µF, 25 V, 0402 [1005 Metric], ± 10%, X5R, GRM Series"
			(at 335.28 52.07 0)
			(effects
				(font
					(size 1.27 1.27)
				)
				(hide yes)
			)
		)
		(property "MPN" "GRM155R61E105KE11J"
			(at 353.06 31.75 0)
			(effects
				(font
					(size 1.27 1.27)
					(thickness 0.15)
				)
				(justify left bottom)
				(hide yes)
			)
		)
		(property "Manufacturer" "Murata"
			(at 355.6 31.75 0)
			(effects
				(font
					(size 1.27 1.27)
					(thickness 0.15)
				)
				(justify left bottom)
				(hide yes)
			)
		)
		(property "License" "Apache-2.0"
			(at 358.14 31.75 0)
			(effects
				(font
					(size 1.27 1.27)
					(thickness 0.15)
				)
				(justify left bottom)
				(hide yes)
			)
		)
		(property "Author" "Antmicro"
			(at 360.68 31.75 0)
			(effects
				(font
					(size 1.27 1.27)
					(thickness 0.15)
				)
				(justify left bottom)
				(hide yes)
			)
		)
		(property "Val" "1u"
			(at 337.312 50.8 90)
			(effects
				(font
					(size 1.27 1.27)
					(thickness 0.15)
				)
				(justify right)
			)
		)
		(property "Voltage" "25V"
			(at 363.22 31.75 0)
			(effects
				(font
					(size 1.27 1.27)
				)
				(justify left bottom)
				(hide yes)
			)
		)
		(property "Dielectric" "X5R"
			(at 365.76 31.75 0)
			(effects
				(font
					(size 1.27 1.27)
				)
				(justify left bottom)
				(hide yes)
			)
		)
		(pin "2"
		)
		(pin "1"
		)
		(instances
			(project "OCuLink to 10GbE adapter"
				(path ""
					(reference "C91")
					(unit 1)
				)
			)
			(project "thunderbolt-to-10gbe-adapter"
				(path ""
					(reference "C232")
					(unit 1)
				)
			)
		)
	)
	(symbol
		(lib_id "antmicroCapacitors0402:C_100n_0402")
		(at 77.47 180.34 90)
		(unit 1)
		(exclude_from_sim no)
		(in_bom yes)
		(on_board yes)
		(dnp no)
		(property "Reference" "C164"
			(at 79.502 176.53 90)
			(effects
				(font
					(size 1.27 1.27)
					(thickness 0.15)
				)
				(justify right)
			)
		)
		(property "Value" "C_100n_0402"
			(at 100.33 165.1 0)
			(effects
				(font
					(size 1.27 1.27)
					(thickness 0.15)
				)
				(justify left bottom)
				(hide yes)
			)
		)
		(property "Footprint" "antmicro-footprints:C_0402_1005Metric"
			(at 102.87 165.1 0)
			(effects
				(font
					(size 1.27 1.27)
					(thickness 0.15)
				)
				(justify left bottom)
				(hide yes)
			)
		)
		(property "Datasheet" "https://www.murata.com/products/productdetail?partno=GRM155R61H104KE14%23"
			(at 105.41 165.1 0)
			(effects
				(font
					(size 1.27 1.27)
					(thickness 0.15)
				)
				(justify left bottom)
				(hide yes)
			)
		)
		(property "Description" "SMD Multilayer Ceramic Capacitor, 0.1 µF, 50 V, 0402 [1005 Metric], ± 10%, X5R, GRM Series"
			(at 77.47 180.34 0)
			(effects
				(font
					(size 1.27 1.27)
				)
				(hide yes)
			)
		)
		(property "MPN" "GRM155R61H104KE14D"
			(at 107.95 165.1 0)
			(effects
				(font
					(size 1.27 1.27)
					(thickness 0.15)
				)
				(justify left bottom)
				(hide yes)
			)
		)
		(property "Val" "100n"
			(at 79.502 179.07 90)
			(effects
				(font
					(size 1.27 1.27)
					(thickness 0.15)
				)
				(justify right)
			)
		)
		(property "Voltage" "50V"
			(at 87.63 165.1 0)
			(effects
				(font
					(size 1.27 1.27)
					(thickness 0.15)
				)
				(justify left bottom)
				(hide yes)
			)
		)
		(property "Dielectric" "X5R"
			(at 90.17 165.1 0)
			(effects
				(font
					(size 1.27 1.27)
					(thickness 0.15)
				)
				(justify left bottom)
				(hide yes)
			)
		)
		(property "Manufacturer" "Murata"
			(at 92.71 165.1 0)
			(effects
				(font
					(size 1.27 1.27)
					(thickness 0.15)
				)
				(justify left bottom)
				(hide yes)
			)
		)
		(property "License" "Apache-2.0"
			(at 95.25 165.1 0)
			(effects
				(font
					(size 1.27 1.27)
					(thickness 0.15)
				)
				(justify left bottom)
				(hide yes)
			)
		)
		(property "Author" "Antmicro"
			(at 97.79 165.1 0)
			(effects
				(font
					(size 1.27 1.27)
					(thickness 0.15)
				)
				(justify left bottom)
				(hide yes)
			)
		)
		(pin "2"
		)
		(pin "1"
		)
		(instances
			(project "OCuLink to 10GbE adapter"
				(path ""
					(reference "C171")
					(unit 1)
				)
			)
			(project "thunderbolt-to-10gbe-adapter"
				(path ""
					(reference "C164")
					(unit 1)
				)
			)
		)
	)
	(symbol
		(lib_id "antmicroCapacitorspol:C_Pol_100u_6V_KEMET-T490-A")
		(at 30.48 148.59 270)
		(unit 1)
		(exclude_from_sim no)
		(in_bom yes)
		(on_board yes)
		(dnp no)
		(fields_autoplaced yes)
		(property "Reference" "C327"
			(at 33.02 149.3266 90)
			(effects
				(font
					(size 1.27 1.27)
					(thickness 0.15)
				)
				(justify left)
			)
		)
		(property "Value" "C_Pol_100u_6V_KEMET-T490-A"
			(at 27.94 162.56 0)
			(effects
				(font
					(size 1.27 1.27)
					(thickness 0.15)
				)
				(justify left bottom)
				(hide yes)
			)
		)
		(property "Footprint" "antmicro-footprints:C_Pol_EIA-A"
			(at 22.86 162.56 0)
			(effects
				(font
					(size 1.27 1.27)
					(thickness 0.15)
				)
				(justify left bottom)
				(hide yes)
			)
		)
		(property "Datasheet" "https://www.kemet.com/en/us/capacitors/product/T490A107M006ATE800.html"
			(at 20.32 162.56 0)
			(effects
				(font
					(size 1.27 1.27)
					(thickness 0.15)
				)
				(justify left bottom)
				(hide yes)
			)
		)
		(property "Description" "Surface Mount Tantalum Capacitor,  Solid SMD 6V 100uF 1206 20% ESR=800mOhms"
			(at 5.08 162.56 0)
			(effects
				(font
					(size 1.27 1.27)
				)
				(justify left bottom)
				(hide yes)
			)
		)
		(property "Val" "100u"
			(at 33.02 151.8666 90)
			(effects
				(font
					(size 1.27 1.27)
					(thickness 0.15)
				)
				(justify left)
			)
		)
		(property "MPN" "T490A107M006ATE800"
			(at 17.78 162.56 0)
			(effects
				(font
					(size 1.27 1.27)
					(thickness 0.15)
				)
				(justify left bottom)
				(hide yes)
			)
		)
		(property "Manufacturer" "KEMET"
			(at 15.24 162.56 0)
			(effects
				(font
					(size 1.27 1.27)
					(thickness 0.15)
				)
				(justify left bottom)
				(hide yes)
			)
		)
		(property "License" "Apache-2.0"
			(at 12.7 162.56 0)
			(effects
				(font
					(size 1.27 1.27)
					(thickness 0.15)
				)
				(justify left bottom)
				(hide yes)
			)
		)
		(property "Author" "Antmicro"
			(at 10.16 162.56 0)
			(effects
				(font
					(size 1.27 1.27)
					(thickness 0.15)
				)
				(justify left bottom)
				(hide yes)
			)
		)
		(property "Voltage" "6V"
			(at 7.62 162.56 0)
			(effects
				(font
					(size 1.27 1.27)
				)
				(justify left bottom)
				(hide yes)
			)
		)
		(property "Dielectric" "template_dielectric"
			(at 5.08 162.56 0)
			(effects
				(font
					(size 1.27 1.27)
				)
				(justify left bottom)
				(hide yes)
			)
		)
		(pin "2"
		)
		(pin "1"
		)
		(instances
			(project "thunderbolt-to-10gbe-adapter"
				(path ""
					(reference "C327")
					(unit 1)
				)
			)
		)
	)
	(symbol
		(lib_id "antmicroCapacitors0402:C_1u_25V_0402")
		(at 151.13 153.67 90)
		(unit 1)
		(exclude_from_sim no)
		(in_bom yes)
		(on_board yes)
		(dnp no)
		(property "Reference" "C205"
			(at 153.162 149.86 90)
			(effects
				(font
					(size 1.27 1.27)
					(thickness 0.15)
				)
				(justify right)
			)
		)
		(property "Value" "C_1u_25V_0402"
			(at 161.29 133.35 0)
			(effects
				(font
					(size 1.27 1.27)
					(thickness 0.15)
				)
				(justify left bottom)
				(hide yes)
			)
		)
		(property "Footprint" "antmicro-footprints:C_0402_1005Metric"
			(at 163.83 133.35 0)
			(effects
				(font
					(size 1.27 1.27)
					(thickness 0.15)
				)
				(justify left bottom)
				(hide yes)
			)
		)
		(property "Datasheet" "https://www.murata.com/products/productdetail?partno=GRM155R61E105KE11%23"
			(at 166.37 133.35 0)
			(effects
				(font
					(size 1.27 1.27)
					(thickness 0.15)
				)
				(justify left bottom)
				(hide yes)
			)
		)
		(property "Description" "SMD Multilayer Ceramic Capacitor, 1 µF, 25 V, 0402 [1005 Metric], ± 10%, X5R, GRM Series"
			(at 151.13 153.67 0)
			(effects
				(font
					(size 1.27 1.27)
				)
				(hide yes)
			)
		)
		(property "MPN" "GRM155R61E105KE11J"
			(at 168.91 133.35 0)
			(effects
				(font
					(size 1.27 1.27)
					(thickness 0.15)
				)
				(justify left bottom)
				(hide yes)
			)
		)
		(property "Manufacturer" "Murata"
			(at 171.45 133.35 0)
			(effects
				(font
					(size 1.27 1.27)
					(thickness 0.15)
				)
				(justify left bottom)
				(hide yes)
			)
		)
		(property "License" "Apache-2.0"
			(at 173.99 133.35 0)
			(effects
				(font
					(size 1.27 1.27)
					(thickness 0.15)
				)
				(justify left bottom)
				(hide yes)
			)
		)
		(property "Author" "Antmicro"
			(at 176.53 133.35 0)
			(effects
				(font
					(size 1.27 1.27)
					(thickness 0.15)
				)
				(justify left bottom)
				(hide yes)
			)
		)
		(property "Val" "1u"
			(at 153.162 152.4 90)
			(effects
				(font
					(size 1.27 1.27)
					(thickness 0.15)
				)
				(justify right)
			)
		)
		(property "Voltage" "25V"
			(at 179.07 133.35 0)
			(effects
				(font
					(size 1.27 1.27)
				)
				(justify left bottom)
				(hide yes)
			)
		)
		(property "Dielectric" "X5R"
			(at 181.61 133.35 0)
			(effects
				(font
					(size 1.27 1.27)
				)
				(justify left bottom)
				(hide yes)
			)
		)
		(pin "2"
		)
		(pin "1"
		)
		(instances
			(project "OCuLink to 10GbE adapter"
				(path ""
					(reference "C169")
					(unit 1)
				)
			)
			(project "thunderbolt-to-10gbe-adapter"
				(path ""
					(reference "C205")
					(unit 1)
				)
			)
		)
	)
	(symbol
		(lib_id "antmicroCapacitors0402:C_1u_25V_0402")
		(at 151.13 207.01 90)
		(unit 1)
		(exclude_from_sim no)
		(in_bom yes)
		(on_board yes)
		(dnp no)
		(property "Reference" "C207"
			(at 153.162 203.2 90)
			(effects
				(font
					(size 1.27 1.27)
					(thickness 0.15)
				)
				(justify right)
			)
		)
		(property "Value" "C_1u_25V_0402"
			(at 161.29 186.69 0)
			(effects
				(font
					(size 1.27 1.27)
					(thickness 0.15)
				)
				(justify left bottom)
				(hide yes)
			)
		)
		(property "Footprint" "antmicro-footprints:C_0402_1005Metric"
			(at 163.83 186.69 0)
			(effects
				(font
					(size 1.27 1.27)
					(thickness 0.15)
				)
				(justify left bottom)
				(hide yes)
			)
		)
		(property "Datasheet" "https://www.murata.com/products/productdetail?partno=GRM155R61E105KE11%23"
			(at 166.37 186.69 0)
			(effects
				(font
					(size 1.27 1.27)
					(thickness 0.15)
				)
				(justify left bottom)
				(hide yes)
			)
		)
		(property "Description" "SMD Multilayer Ceramic Capacitor, 1 µF, 25 V, 0402 [1005 Metric], ± 10%, X5R, GRM Series"
			(at 151.13 207.01 0)
			(effects
				(font
					(size 1.27 1.27)
				)
				(hide yes)
			)
		)
		(property "MPN" "GRM155R61E105KE11J"
			(at 168.91 186.69 0)
			(effects
				(font
					(size 1.27 1.27)
					(thickness 0.15)
				)
				(justify left bottom)
				(hide yes)
			)
		)
		(property "Manufacturer" "Murata"
			(at 171.45 186.69 0)
			(effects
				(font
					(size 1.27 1.27)
					(thickness 0.15)
				)
				(justify left bottom)
				(hide yes)
			)
		)
		(property "License" "Apache-2.0"
			(at 173.99 186.69 0)
			(effects
				(font
					(size 1.27 1.27)
					(thickness 0.15)
				)
				(justify left bottom)
				(hide yes)
			)
		)
		(property "Author" "Antmicro"
			(at 176.53 186.69 0)
			(effects
				(font
					(size 1.27 1.27)
					(thickness 0.15)
				)
				(justify left bottom)
				(hide yes)
			)
		)
		(property "Val" "1u"
			(at 153.162 205.74 90)
			(effects
				(font
					(size 1.27 1.27)
					(thickness 0.15)
				)
				(justify right)
			)
		)
		(property "Voltage" "25V"
			(at 179.07 186.69 0)
			(effects
				(font
					(size 1.27 1.27)
				)
				(justify left bottom)
				(hide yes)
			)
		)
		(property "Dielectric" "X5R"
			(at 181.61 186.69 0)
			(effects
				(font
					(size 1.27 1.27)
				)
				(justify left bottom)
				(hide yes)
			)
		)
		(pin "2"
		)
		(pin "1"
		)
		(instances
			(project "OCuLink to 10GbE adapter"
				(path ""
					(reference "C184")
					(unit 1)
				)
			)
			(project "thunderbolt-to-10gbe-adapter"
				(path ""
					(reference "C207")
					(unit 1)
				)
			)
		)
	)
	(symbol
		(lib_id "antmicroCapacitors0402:C_1u_25V_0402")
		(at 133.35 52.07 90)
		(unit 1)
		(exclude_from_sim no)
		(in_bom yes)
		(on_board yes)
		(dnp no)
		(property "Reference" "C190"
			(at 135.382 48.26 90)
			(effects
				(font
					(size 1.27 1.27)
					(thickness 0.15)
				)
				(justify right)
			)
		)
		(property "Value" "C_1u_25V_0402"
			(at 143.51 31.75 0)
			(effects
				(font
					(size 1.27 1.27)
					(thickness 0.15)
				)
				(justify left bottom)
				(hide yes)
			)
		)
		(property "Footprint" "antmicro-footprints:C_0402_1005Metric"
			(at 146.05 31.75 0)
			(effects
				(font
					(size 1.27 1.27)
					(thickness 0.15)
				)
				(justify left bottom)
				(hide yes)
			)
		)
		(property "Datasheet" "https://www.murata.com/products/productdetail?partno=GRM155R61E105KE11%23"
			(at 148.59 31.75 0)
			(effects
				(font
					(size 1.27 1.27)
					(thickness 0.15)
				)
				(justify left bottom)
				(hide yes)
			)
		)
		(property "Description" "SMD Multilayer Ceramic Capacitor, 1 µF, 25 V, 0402 [1005 Metric], ± 10%, X5R, GRM Series"
			(at 133.35 52.07 0)
			(effects
				(font
					(size 1.27 1.27)
				)
				(hide yes)
			)
		)
		(property "MPN" "GRM155R61E105KE11J"
			(at 151.13 31.75 0)
			(effects
				(font
					(size 1.27 1.27)
					(thickness 0.15)
				)
				(justify left bottom)
				(hide yes)
			)
		)
		(property "Manufacturer" "Murata"
			(at 153.67 31.75 0)
			(effects
				(font
					(size 1.27 1.27)
					(thickness 0.15)
				)
				(justify left bottom)
				(hide yes)
			)
		)
		(property "License" "Apache-2.0"
			(at 156.21 31.75 0)
			(effects
				(font
					(size 1.27 1.27)
					(thickness 0.15)
				)
				(justify left bottom)
				(hide yes)
			)
		)
		(property "Author" "Antmicro"
			(at 158.75 31.75 0)
			(effects
				(font
					(size 1.27 1.27)
					(thickness 0.15)
				)
				(justify left bottom)
				(hide yes)
			)
		)
		(property "Val" "1u"
			(at 135.382 50.8 90)
			(effects
				(font
					(size 1.27 1.27)
					(thickness 0.15)
				)
				(justify right)
			)
		)
		(property "Voltage" "25V"
			(at 161.29 31.75 0)
			(effects
				(font
					(size 1.27 1.27)
				)
				(justify left bottom)
				(hide yes)
			)
		)
		(property "Dielectric" "X5R"
			(at 163.83 31.75 0)
			(effects
				(font
					(size 1.27 1.27)
				)
				(justify left bottom)
				(hide yes)
			)
		)
		(pin "2"
		)
		(pin "1"
		)
		(instances
			(project "OCuLink to 10GbE adapter"
				(path ""
					(reference "C84")
					(unit 1)
				)
			)
			(project "thunderbolt-to-10gbe-adapter"
				(path ""
					(reference "C190")
					(unit 1)
				)
			)
		)
	)
	(symbol
		(lib_id "antmicroCapacitors0402:C_1u_25V_0402")
		(at 151.13 233.68 90)
		(unit 1)
		(exclude_from_sim no)
		(in_bom yes)
		(on_board yes)
		(dnp no)
		(property "Reference" "C208"
			(at 153.162 229.87 90)
			(effects
				(font
					(size 1.27 1.27)
					(thickness 0.15)
				)
				(justify right)
			)
		)
		(property "Value" "C_1u_25V_0402"
			(at 161.29 213.36 0)
			(effects
				(font
					(size 1.27 1.27)
					(thickness 0.15)
				)
				(justify left bottom)
				(hide yes)
			)
		)
		(property "Footprint" "antmicro-footprints:C_0402_1005Metric"
			(at 163.83 213.36 0)
			(effects
				(font
					(size 1.27 1.27)
					(thickness 0.15)
				)
				(justify left bottom)
				(hide yes)
			)
		)
		(property "Datasheet" "https://www.murata.com/products/productdetail?partno=GRM155R61E105KE11%23"
			(at 166.37 213.36 0)
			(effects
				(font
					(size 1.27 1.27)
					(thickness 0.15)
				)
				(justify left bottom)
				(hide yes)
			)
		)
		(property "Description" "SMD Multilayer Ceramic Capacitor, 1 µF, 25 V, 0402 [1005 Metric], ± 10%, X5R, GRM Series"
			(at 151.13 233.68 0)
			(effects
				(font
					(size 1.27 1.27)
				)
				(hide yes)
			)
		)
		(property "MPN" "GRM155R61E105KE11J"
			(at 168.91 213.36 0)
			(effects
				(font
					(size 1.27 1.27)
					(thickness 0.15)
				)
				(justify left bottom)
				(hide yes)
			)
		)
		(property "Manufacturer" "Murata"
			(at 171.45 213.36 0)
			(effects
				(font
					(size 1.27 1.27)
					(thickness 0.15)
				)
				(justify left bottom)
				(hide yes)
			)
		)
		(property "License" "Apache-2.0"
			(at 173.99 213.36 0)
			(effects
				(font
					(size 1.27 1.27)
					(thickness 0.15)
				)
				(justify left bottom)
				(hide yes)
			)
		)
		(property "Author" "Antmicro"
			(at 176.53 213.36 0)
			(effects
				(font
					(size 1.27 1.27)
					(thickness 0.15)
				)
				(justify left bottom)
				(hide yes)
			)
		)
		(property "Val" "1u"
			(at 153.162 232.41 90)
			(effects
				(font
					(size 1.27 1.27)
					(thickness 0.15)
				)
				(justify right)
			)
		)
		(property "Voltage" "25V"
			(at 179.07 213.36 0)
			(effects
				(font
					(size 1.27 1.27)
				)
				(justify left bottom)
				(hide yes)
			)
		)
		(property "Dielectric" "X5R"
			(at 181.61 213.36 0)
			(effects
				(font
					(size 1.27 1.27)
				)
				(justify left bottom)
				(hide yes)
			)
		)
		(pin "2"
		)
		(pin "1"
		)
		(instances
			(project "OCuLink to 10GbE adapter"
				(path ""
					(reference "C187")
					(unit 1)
				)
			)
			(project "thunderbolt-to-10gbe-adapter"
				(path ""
					(reference "C208")
					(unit 1)
				)
			)
		)
	)
	(symbol
		(lib_id "antmicropower:GND")
		(at 353.06 133.35 0)
		(unit 1)
		(exclude_from_sim no)
		(in_bom yes)
		(on_board yes)
		(dnp no)
		(property "Reference" "#PWR0330"
			(at 361.95 135.89 0)
			(effects
				(font
					(size 1.27 1.27)
					(thickness 0.15)
				)
				(justify left bottom)
				(hide yes)
			)
		)
		(property "Value" "GND"
			(at 353.06 137.16 0)
			(effects
				(font
					(size 1.27 1.27)
					(thickness 0.15)
				)
			)
		)
		(property "Footprint" ""
			(at 361.95 140.97 0)
			(effects
				(font
					(size 1.27 1.27)
					(thickness 0.15)
				)
				(justify left bottom)
				(hide yes)
			)
		)
		(property "Datasheet" ""
			(at 361.95 146.05 0)
			(effects
				(font
					(size 1.27 1.27)
					(thickness 0.15)
				)
				(justify left bottom)
				(hide yes)
			)
		)
		(property "Description" ""
			(at 353.06 133.35 0)
			(effects
				(font
					(size 1.27 1.27)
				)
				(hide yes)
			)
		)
		(property "Author" "Antmicro"
			(at 361.95 140.97 0)
			(effects
				(font
					(size 1.27 1.27)
					(thickness 0.15)
				)
				(justify left bottom)
				(hide yes)
			)
		)
		(property "License" "Apache-2.0"
			(at 361.95 143.51 0)
			(effects
				(font
					(size 1.27 1.27)
					(thickness 0.15)
				)
				(justify left bottom)
				(hide yes)
			)
		)
		(pin "1"
		)
		(instances
			(project "OCuLink to 10GbE adapter"
				(path ""
					(reference "#PWR0200")
					(unit 1)
				)
			)
			(project "thunderbolt-to-10gbe-adapter"
				(path ""
					(reference "#PWR0330")
					(unit 1)
				)
			)
		)
	)
	(symbol
		(lib_id "antmicroCapacitors0402:C_1u_25V_0402")
		(at 308.61 52.07 90)
		(unit 1)
		(exclude_from_sim no)
		(in_bom yes)
		(on_board yes)
		(dnp no)
		(property "Reference" "C217"
			(at 310.642 48.26 90)
			(effects
				(font
					(size 1.27 1.27)
					(thickness 0.15)
				)
				(justify right)
			)
		)
		(property "Value" "C_1u_25V_0402"
			(at 318.77 31.75 0)
			(effects
				(font
					(size 1.27 1.27)
					(thickness 0.15)
				)
				(justify left bottom)
				(hide yes)
			)
		)
		(property "Footprint" "antmicro-footprints:C_0402_1005Metric"
			(at 321.31 31.75 0)
			(effects
				(font
					(size 1.27 1.27)
					(thickness 0.15)
				)
				(justify left bottom)
				(hide yes)
			)
		)
		(property "Datasheet" "https://www.murata.com/products/productdetail?partno=GRM155R61E105KE11%23"
			(at 323.85 31.75 0)
			(effects
				(font
					(size 1.27 1.27)
					(thickness 0.15)
				)
				(justify left bottom)
				(hide yes)
			)
		)
		(property "Description" "SMD Multilayer Ceramic Capacitor, 1 µF, 25 V, 0402 [1005 Metric], ± 10%, X5R, GRM Series"
			(at 308.61 52.07 0)
			(effects
				(font
					(size 1.27 1.27)
				)
				(hide yes)
			)
		)
		(property "MPN" "GRM155R61E105KE11J"
			(at 326.39 31.75 0)
			(effects
				(font
					(size 1.27 1.27)
					(thickness 0.15)
				)
				(justify left bottom)
				(hide yes)
			)
		)
		(property "Manufacturer" "Murata"
			(at 328.93 31.75 0)
			(effects
				(font
					(size 1.27 1.27)
					(thickness 0.15)
				)
				(justify left bottom)
				(hide yes)
			)
		)
		(property "License" "Apache-2.0"
			(at 331.47 31.75 0)
			(effects
				(font
					(size 1.27 1.27)
					(thickness 0.15)
				)
				(justify left bottom)
				(hide yes)
			)
		)
		(property "Author" "Antmicro"
			(at 334.01 31.75 0)
			(effects
				(font
					(size 1.27 1.27)
					(thickness 0.15)
				)
				(justify left bottom)
				(hide yes)
			)
		)
		(property "Val" "1u"
			(at 310.642 50.8 90)
			(effects
				(font
					(size 1.27 1.27)
					(thickness 0.15)
				)
				(justify right)
			)
		)
		(property "Voltage" "25V"
			(at 336.55 31.75 0)
			(effects
				(font
					(size 1.27 1.27)
				)
				(justify left bottom)
				(hide yes)
			)
		)
		(property "Dielectric" "X5R"
			(at 339.09 31.75 0)
			(effects
				(font
					(size 1.27 1.27)
				)
				(justify left bottom)
				(hide yes)
			)
		)
		(pin "2"
		)
		(pin "1"
		)
		(instances
			(project "OCuLink to 10GbE adapter"
				(path ""
					(reference "C88")
					(unit 1)
				)
			)
			(project "thunderbolt-to-10gbe-adapter"
				(path ""
					(reference "C217")
					(unit 1)
				)
			)
		)
	)
	(symbol
		(lib_id "antmicroCapacitors0402:C_1u_25V_0402")
		(at 90.17 260.35 90)
		(unit 1)
		(exclude_from_sim no)
		(in_bom yes)
		(on_board yes)
		(dnp no)
		(property "Reference" "C174"
			(at 92.202 256.54 90)
			(effects
				(font
					(size 1.27 1.27)
					(thickness 0.15)
				)
				(justify right)
			)
		)
		(property "Value" "C_1u_25V_0402"
			(at 100.33 240.03 0)
			(effects
				(font
					(size 1.27 1.27)
					(thickness 0.15)
				)
				(justify left bottom)
				(hide yes)
			)
		)
		(property "Footprint" "antmicro-footprints:C_0402_1005Metric"
			(at 102.87 240.03 0)
			(effects
				(font
					(size 1.27 1.27)
					(thickness 0.15)
				)
				(justify left bottom)
				(hide yes)
			)
		)
		(property "Datasheet" "https://www.murata.com/products/productdetail?partno=GRM155R61E105KE11%23"
			(at 105.41 240.03 0)
			(effects
				(font
					(size 1.27 1.27)
					(thickness 0.15)
				)
				(justify left bottom)
				(hide yes)
			)
		)
		(property "Description" "SMD Multilayer Ceramic Capacitor, 1 µF, 25 V, 0402 [1005 Metric], ± 10%, X5R, GRM Series"
			(at 90.17 260.35 0)
			(effects
				(font
					(size 1.27 1.27)
				)
				(hide yes)
			)
		)
		(property "MPN" "GRM155R61E105KE11J"
			(at 107.95 240.03 0)
			(effects
				(font
					(size 1.27 1.27)
					(thickness 0.15)
				)
				(justify left bottom)
				(hide yes)
			)
		)
		(property "Manufacturer" "Murata"
			(at 110.49 240.03 0)
			(effects
				(font
					(size 1.27 1.27)
					(thickness 0.15)
				)
				(justify left bottom)
				(hide yes)
			)
		)
		(property "License" "Apache-2.0"
			(at 113.03 240.03 0)
			(effects
				(font
					(size 1.27 1.27)
					(thickness 0.15)
				)
				(justify left bottom)
				(hide yes)
			)
		)
		(property "Author" "Antmicro"
			(at 115.57 240.03 0)
			(effects
				(font
					(size 1.27 1.27)
					(thickness 0.15)
				)
				(justify left bottom)
				(hide yes)
			)
		)
		(property "Val" "1u"
			(at 92.202 259.08 90)
			(effects
				(font
					(size 1.27 1.27)
					(thickness 0.15)
				)
				(justify right)
			)
		)
		(property "Voltage" "25V"
			(at 118.11 240.03 0)
			(effects
				(font
					(size 1.27 1.27)
				)
				(justify left bottom)
				(hide yes)
			)
		)
		(property "Dielectric" "X5R"
			(at 120.65 240.03 0)
			(effects
				(font
					(size 1.27 1.27)
				)
				(justify left bottom)
				(hide yes)
			)
		)
		(pin "2"
		)
		(pin "1"
		)
		(instances
			(project "OCuLink to 10GbE adapter"
				(path ""
					(reference "C189")
					(unit 1)
				)
			)
			(project "thunderbolt-to-10gbe-adapter"
				(path ""
					(reference "C174")
					(unit 1)
				)
			)
		)
	)
	(symbol
		(lib_id "antmicroCapacitors0402:C_1u_25V_0402")
		(at 142.24 127 90)
		(unit 1)
		(exclude_from_sim no)
		(in_bom yes)
		(on_board yes)
		(dnp no)
		(property "Reference" "C198"
			(at 144.018 123.19 90)
			(effects
				(font
					(size 1.27 1.27)
					(thickness 0.15)
				)
				(justify right)
			)
		)
		(property "Value" "C_1u_25V_0402"
			(at 152.4 106.68 0)
			(effects
				(font
					(size 1.27 1.27)
					(thickness 0.15)
				)
				(justify left bottom)
				(hide yes)
			)
		)
		(property "Footprint" "antmicro-footprints:C_0402_1005Metric"
			(at 154.94 106.68 0)
			(effects
				(font
					(size 1.27 1.27)
					(thickness 0.15)
				)
				(justify left bottom)
				(hide yes)
			)
		)
		(property "Datasheet" "https://www.murata.com/products/productdetail?partno=GRM155R61E105KE11%23"
			(at 157.48 106.68 0)
			(effects
				(font
					(size 1.27 1.27)
					(thickness 0.15)
				)
				(justify left bottom)
				(hide yes)
			)
		)
		(property "Description" "SMD Multilayer Ceramic Capacitor, 1 µF, 25 V, 0402 [1005 Metric], ± 10%, X5R, GRM Series"
			(at 142.24 127 0)
			(effects
				(font
					(size 1.27 1.27)
				)
				(hide yes)
			)
		)
		(property "MPN" "GRM155R61E105KE11J"
			(at 160.02 106.68 0)
			(effects
				(font
					(size 1.27 1.27)
					(thickness 0.15)
				)
				(justify left bottom)
				(hide yes)
			)
		)
		(property "Manufacturer" "Murata"
			(at 162.56 106.68 0)
			(effects
				(font
					(size 1.27 1.27)
					(thickness 0.15)
				)
				(justify left bottom)
				(hide yes)
			)
		)
		(property "License" "Apache-2.0"
			(at 165.1 106.68 0)
			(effects
				(font
					(size 1.27 1.27)
					(thickness 0.15)
				)
				(justify left bottom)
				(hide yes)
			)
		)
		(property "Author" "Antmicro"
			(at 167.64 106.68 0)
			(effects
				(font
					(size 1.27 1.27)
					(thickness 0.15)
				)
				(justify left bottom)
				(hide yes)
			)
		)
		(property "Val" "1u"
			(at 144.018 125.73 90)
			(effects
				(font
					(size 1.27 1.27)
					(thickness 0.15)
				)
				(justify right)
			)
		)
		(property "Voltage" "25V"
			(at 170.18 106.68 0)
			(effects
				(font
					(size 1.27 1.27)
				)
				(justify left bottom)
				(hide yes)
			)
		)
		(property "Dielectric" "X5R"
			(at 172.72 106.68 0)
			(effects
				(font
					(size 1.27 1.27)
				)
				(justify left bottom)
				(hide yes)
			)
		)
		(pin "2"
		)
		(pin "1"
		)
		(instances
			(project "OCuLink to 10GbE adapter"
				(path ""
					(reference "C144")
					(unit 1)
				)
			)
			(project "thunderbolt-to-10gbe-adapter"
				(path ""
					(reference "C198")
					(unit 1)
				)
			)
		)
	)
	(symbol
		(lib_id "antmicropower:GND")
		(at 317.5 76.2 0)
		(unit 1)
		(exclude_from_sim no)
		(in_bom yes)
		(on_board yes)
		(dnp no)
		(property "Reference" "#PWR0309"
			(at 326.39 78.74 0)
			(effects
				(font
					(size 1.27 1.27)
					(thickness 0.15)
				)
				(justify left bottom)
				(hide yes)
			)
		)
		(property "Value" "GND"
			(at 317.5 80.01 0)
			(effects
				(font
					(size 1.27 1.27)
					(thickness 0.15)
				)
			)
		)
		(property "Footprint" ""
			(at 326.39 83.82 0)
			(effects
				(font
					(size 1.27 1.27)
					(thickness 0.15)
				)
				(justify left bottom)
				(hide yes)
			)
		)
		(property "Datasheet" ""
			(at 326.39 88.9 0)
			(effects
				(font
					(size 1.27 1.27)
					(thickness 0.15)
				)
				(justify left bottom)
				(hide yes)
			)
		)
		(property "Description" ""
			(at 317.5 76.2 0)
			(effects
				(font
					(size 1.27 1.27)
				)
				(hide yes)
			)
		)
		(property "Author" "Antmicro"
			(at 326.39 83.82 0)
			(effects
				(font
					(size 1.27 1.27)
					(thickness 0.15)
				)
				(justify left bottom)
				(hide yes)
			)
		)
		(property "License" "Apache-2.0"
			(at 326.39 86.36 0)
			(effects
				(font
					(size 1.27 1.27)
					(thickness 0.15)
				)
				(justify left bottom)
				(hide yes)
			)
		)
		(pin "1"
		)
		(instances
			(project "OCuLink to 10GbE adapter"
				(path ""
					(reference "#PWR0141")
					(unit 1)
				)
			)
			(project "thunderbolt-to-10gbe-adapter"
				(path ""
					(reference "#PWR0309")
					(unit 1)
				)
			)
		)
	)
	(symbol
		(lib_id "antmicropower:VDD")
		(at 180.34 116.84 0)
		(unit 1)
		(exclude_from_sim no)
		(in_bom yes)
		(on_board yes)
		(dnp no)
		(property "Reference" "#PWR0281"
			(at 180.34 120.65 0)
			(effects
				(font
					(size 1.27 1.27)
				)
				(hide yes)
			)
		)
		(property "Value" "XFI_PVDD"
			(at 180.34 113.03 0)
			(effects
				(font
					(size 1.27 1.27)
				)
			)
		)
		(property "Footprint" ""
			(at 180.34 116.84 0)
			(effects
				(font
					(size 1.27 1.27)
				)
				(hide yes)
			)
		)
		(property "Datasheet" ""
			(at 180.34 116.84 0)
			(effects
				(font
					(size 1.27 1.27)
				)
				(hide yes)
			)
		)
		(property "Description" ""
			(at 180.34 116.84 0)
			(effects
				(font
					(size 1.27 1.27)
				)
				(hide yes)
			)
		)
		(pin "1"
		)
		(instances
			(project "OCuLink to 10GbE adapter"
				(path ""
					(reference "#PWR0152")
					(unit 1)
				)
			)
			(project "thunderbolt-to-10gbe-adapter"
				(path ""
					(reference "#PWR0281")
					(unit 1)
				)
			)
		)
	)
	(symbol
		(lib_id "antmicropower:GND")
		(at 370.84 76.2 0)
		(unit 1)
		(exclude_from_sim no)
		(in_bom yes)
		(on_board yes)
		(dnp no)
		(property "Reference" "#PWR0337"
			(at 379.73 78.74 0)
			(effects
				(font
					(size 1.27 1.27)
					(thickness 0.15)
				)
				(justify left bottom)
				(hide yes)
			)
		)
		(property "Value" "GND"
			(at 370.84 80.01 0)
			(effects
				(font
					(size 1.27 1.27)
					(thickness 0.15)
				)
			)
		)
		(property "Footprint" ""
			(at 379.73 83.82 0)
			(effects
				(font
					(size 1.27 1.27)
					(thickness 0.15)
				)
				(justify left bottom)
				(hide yes)
			)
		)
		(property "Datasheet" ""
			(at 379.73 88.9 0)
			(effects
				(font
					(size 1.27 1.27)
					(thickness 0.15)
				)
				(justify left bottom)
				(hide yes)
			)
		)
		(property "Description" ""
			(at 370.84 76.2 0)
			(effects
				(font
					(size 1.27 1.27)
				)
				(hide yes)
			)
		)
		(property "Author" "Antmicro"
			(at 379.73 83.82 0)
			(effects
				(font
					(size 1.27 1.27)
					(thickness 0.15)
				)
				(justify left bottom)
				(hide yes)
			)
		)
		(property "License" "Apache-2.0"
			(at 379.73 86.36 0)
			(effects
				(font
					(size 1.27 1.27)
					(thickness 0.15)
				)
				(justify left bottom)
				(hide yes)
			)
		)
		(pin "1"
		)
		(instances
			(project "OCuLink to 10GbE adapter"
				(path ""
					(reference "#PWR0147")
					(unit 1)
				)
			)
			(project "thunderbolt-to-10gbe-adapter"
				(path ""
					(reference "#PWR0337")
					(unit 1)
				)
			)
		)
	)
	(symbol
		(lib_id "antmicropower:GND")
		(at 88.9 76.2 0)
		(unit 1)
		(exclude_from_sim no)
		(in_bom yes)
		(on_board yes)
		(dnp no)
		(property "Reference" "#PWR0238"
			(at 97.79 78.74 0)
			(effects
				(font
					(size 1.27 1.27)
					(thickness 0.15)
				)
				(justify left bottom)
				(hide yes)
			)
		)
		(property "Value" "GND"
			(at 88.9 80.01 0)
			(effects
				(font
					(size 1.27 1.27)
					(thickness 0.15)
				)
			)
		)
		(property "Footprint" ""
			(at 97.79 83.82 0)
			(effects
				(font
					(size 1.27 1.27)
					(thickness 0.15)
				)
				(justify left bottom)
				(hide yes)
			)
		)
		(property "Datasheet" ""
			(at 97.79 88.9 0)
			(effects
				(font
					(size 1.27 1.27)
					(thickness 0.15)
				)
				(justify left bottom)
				(hide yes)
			)
		)
		(property "Description" ""
			(at 88.9 76.2 0)
			(effects
				(font
					(size 1.27 1.27)
				)
				(hide yes)
			)
		)
		(property "Author" "Antmicro"
			(at 97.79 83.82 0)
			(effects
				(font
					(size 1.27 1.27)
					(thickness 0.15)
				)
				(justify left bottom)
				(hide yes)
			)
		)
		(property "License" "Apache-2.0"
			(at 97.79 86.36 0)
			(effects
				(font
					(size 1.27 1.27)
					(thickness 0.15)
				)
				(justify left bottom)
				(hide yes)
			)
		)
		(pin "1"
		)
		(instances
			(project "OCuLink to 10GbE adapter"
				(path ""
					(reference "#PWR0133")
					(unit 1)
				)
			)
			(project "thunderbolt-to-10gbe-adapter"
				(path ""
					(reference "#PWR0238")
					(unit 1)
				)
			)
		)
	)
	(symbol
		(lib_id "antmicroCapacitors0402:C_100n_0402")
		(at 74.93 207.01 90)
		(unit 1)
		(exclude_from_sim no)
		(in_bom yes)
		(on_board yes)
		(dnp no)
		(property "Reference" "C158"
			(at 76.962 203.2 90)
			(effects
				(font
					(size 1.27 1.27)
					(thickness 0.15)
				)
				(justify right)
			)
		)
		(property "Value" "C_100n_0402"
			(at 97.79 191.77 0)
			(effects
				(font
					(size 1.27 1.27)
					(thickness 0.15)
				)
				(justify left bottom)
				(hide yes)
			)
		)
		(property "Footprint" "antmicro-footprints:C_0402_1005Metric"
			(at 100.33 191.77 0)
			(effects
				(font
					(size 1.27 1.27)
					(thickness 0.15)
				)
				(justify left bottom)
				(hide yes)
			)
		)
		(property "Datasheet" "https://www.murata.com/products/productdetail?partno=GRM155R61H104KE14%23"
			(at 102.87 191.77 0)
			(effects
				(font
					(size 1.27 1.27)
					(thickness 0.15)
				)
				(justify left bottom)
				(hide yes)
			)
		)
		(property "Description" "SMD Multilayer Ceramic Capacitor, 0.1 µF, 50 V, 0402 [1005 Metric], ± 10%, X5R, GRM Series"
			(at 74.93 207.01 0)
			(effects
				(font
					(size 1.27 1.27)
				)
				(hide yes)
			)
		)
		(property "MPN" "GRM155R61H104KE14D"
			(at 105.41 191.77 0)
			(effects
				(font
					(size 1.27 1.27)
					(thickness 0.15)
				)
				(justify left bottom)
				(hide yes)
			)
		)
		(property "Val" "100n"
			(at 76.962 205.74 90)
			(effects
				(font
					(size 1.27 1.27)
					(thickness 0.15)
				)
				(justify right)
			)
		)
		(property "Voltage" "50V"
			(at 85.09 191.77 0)
			(effects
				(font
					(size 1.27 1.27)
					(thickness 0.15)
				)
				(justify left bottom)
				(hide yes)
			)
		)
		(property "Dielectric" "X5R"
			(at 87.63 191.77 0)
			(effects
				(font
					(size 1.27 1.27)
					(thickness 0.15)
				)
				(justify left bottom)
				(hide yes)
			)
		)
		(property "Manufacturer" "Murata"
			(at 90.17 191.77 0)
			(effects
				(font
					(size 1.27 1.27)
					(thickness 0.15)
				)
				(justify left bottom)
				(hide yes)
			)
		)
		(property "License" "Apache-2.0"
			(at 92.71 191.77 0)
			(effects
				(font
					(size 1.27 1.27)
					(thickness 0.15)
				)
				(justify left bottom)
				(hide yes)
			)
		)
		(property "Author" "Antmicro"
			(at 95.25 191.77 0)
			(effects
				(font
					(size 1.27 1.27)
					(thickness 0.15)
				)
				(justify left bottom)
				(hide yes)
			)
		)
		(pin "2"
		)
		(pin "1"
		)
		(instances
			(project "OCuLink to 10GbE adapter"
				(path ""
					(reference "C179")
					(unit 1)
				)
			)
			(project "thunderbolt-to-10gbe-adapter"
				(path ""
					(reference "C158")
					(unit 1)
				)
			)
		)
	)
	(symbol
		(lib_id "antmicropower:GND")
		(at 344.17 76.2 0)
		(unit 1)
		(exclude_from_sim no)
		(in_bom yes)
		(on_board yes)
		(dnp no)
		(property "Reference" "#PWR0323"
			(at 353.06 78.74 0)
			(effects
				(font
					(size 1.27 1.27)
					(thickness 0.15)
				)
				(justify left bottom)
				(hide yes)
			)
		)
		(property "Value" "GND"
			(at 344.17 80.01 0)
			(effects
				(font
					(size 1.27 1.27)
					(thickness 0.15)
				)
			)
		)
		(property "Footprint" ""
			(at 353.06 83.82 0)
			(effects
				(font
					(size 1.27 1.27)
					(thickness 0.15)
				)
				(justify left bottom)
				(hide yes)
			)
		)
		(property "Datasheet" ""
			(at 353.06 88.9 0)
			(effects
				(font
					(size 1.27 1.27)
					(thickness 0.15)
				)
				(justify left bottom)
				(hide yes)
			)
		)
		(property "Description" ""
			(at 344.17 76.2 0)
			(effects
				(font
					(size 1.27 1.27)
				)
				(hide yes)
			)
		)
		(property "Author" "Antmicro"
			(at 353.06 83.82 0)
			(effects
				(font
					(size 1.27 1.27)
					(thickness 0.15)
				)
				(justify left bottom)
				(hide yes)
			)
		)
		(property "License" "Apache-2.0"
			(at 353.06 86.36 0)
			(effects
				(font
					(size 1.27 1.27)
					(thickness 0.15)
				)
				(justify left bottom)
				(hide yes)
			)
		)
		(pin "1"
		)
		(instances
			(project "OCuLink to 10GbE adapter"
				(path ""
					(reference "#PWR0144")
					(unit 1)
				)
			)
			(project "thunderbolt-to-10gbe-adapter"
				(path ""
					(reference "#PWR0323")
					(unit 1)
				)
			)
		)
	)
	(symbol
		(lib_id "antmicropower:GND")
		(at 326.39 115.57 0)
		(unit 1)
		(exclude_from_sim no)
		(in_bom yes)
		(on_board yes)
		(dnp no)
		(property "Reference" "#PWR0316"
			(at 335.28 118.11 0)
			(effects
				(font
					(size 1.27 1.27)
					(thickness 0.15)
				)
				(justify left bottom)
				(hide yes)
			)
		)
		(property "Value" "GND"
			(at 326.39 119.38 0)
			(effects
				(font
					(size 1.27 1.27)
					(thickness 0.15)
				)
			)
		)
		(property "Footprint" ""
			(at 335.28 123.19 0)
			(effects
				(font
					(size 1.27 1.27)
					(thickness 0.15)
				)
				(justify left bottom)
				(hide yes)
			)
		)
		(property "Datasheet" ""
			(at 335.28 128.27 0)
			(effects
				(font
					(size 1.27 1.27)
					(thickness 0.15)
				)
				(justify left bottom)
				(hide yes)
			)
		)
		(property "Description" ""
			(at 326.39 115.57 0)
			(effects
				(font
					(size 1.27 1.27)
				)
				(hide yes)
			)
		)
		(property "Author" "Antmicro"
			(at 335.28 123.19 0)
			(effects
				(font
					(size 1.27 1.27)
					(thickness 0.15)
				)
				(justify left bottom)
				(hide yes)
			)
		)
		(property "License" "Apache-2.0"
			(at 335.28 125.73 0)
			(effects
				(font
					(size 1.27 1.27)
					(thickness 0.15)
				)
				(justify left bottom)
				(hide yes)
			)
		)
		(pin "1"
		)
		(instances
			(project "OCuLink to 10GbE adapter"
				(path ""
					(reference "#PWR0180")
					(unit 1)
				)
			)
			(project "thunderbolt-to-10gbe-adapter"
				(path ""
					(reference "#PWR0316")
					(unit 1)
				)
			)
		)
	)
	(symbol
		(lib_id "antmicropower:GND")
		(at 74.93 209.55 0)
		(unit 1)
		(exclude_from_sim no)
		(in_bom yes)
		(on_board yes)
		(dnp no)
		(property "Reference" "#PWR0229"
			(at 83.82 212.09 0)
			(effects
				(font
					(size 1.27 1.27)
					(thickness 0.15)
				)
				(justify left bottom)
				(hide yes)
			)
		)
		(property "Value" "GND"
			(at 74.93 213.36 0)
			(effects
				(font
					(size 1.27 1.27)
					(thickness 0.15)
				)
			)
		)
		(property "Footprint" ""
			(at 83.82 217.17 0)
			(effects
				(font
					(size 1.27 1.27)
					(thickness 0.15)
				)
				(justify left bottom)
				(hide yes)
			)
		)
		(property "Datasheet" ""
			(at 83.82 222.25 0)
			(effects
				(font
					(size 1.27 1.27)
					(thickness 0.15)
				)
				(justify left bottom)
				(hide yes)
			)
		)
		(property "Description" ""
			(at 74.93 209.55 0)
			(effects
				(font
					(size 1.27 1.27)
				)
				(hide yes)
			)
		)
		(property "Author" "Antmicro"
			(at 83.82 217.17 0)
			(effects
				(font
					(size 1.27 1.27)
					(thickness 0.15)
				)
				(justify left bottom)
				(hide yes)
			)
		)
		(property "License" "Apache-2.0"
			(at 83.82 219.71 0)
			(effects
				(font
					(size 1.27 1.27)
					(thickness 0.15)
				)
				(justify left bottom)
				(hide yes)
			)
		)
		(pin "1"
		)
		(instances
			(project "OCuLink to 10GbE adapter"
				(path ""
					(reference "#PWR0232")
					(unit 1)
				)
			)
			(project "thunderbolt-to-10gbe-adapter"
				(path ""
					(reference "#PWR0229")
					(unit 1)
				)
			)
		)
	)
	(symbol
		(lib_id "antmicropower:GND")
		(at 379.73 133.35 0)
		(unit 1)
		(exclude_from_sim no)
		(in_bom yes)
		(on_board yes)
		(dnp no)
		(property "Reference" "#PWR0344"
			(at 388.62 135.89 0)
			(effects
				(font
					(size 1.27 1.27)
					(thickness 0.15)
				)
				(justify left bottom)
				(hide yes)
			)
		)
		(property "Value" "GND"
			(at 379.73 137.16 0)
			(effects
				(font
					(size 1.27 1.27)
					(thickness 0.15)
				)
			)
		)
		(property "Footprint" ""
			(at 388.62 140.97 0)
			(effects
				(font
					(size 1.27 1.27)
					(thickness 0.15)
				)
				(justify left bottom)
				(hide yes)
			)
		)
		(property "Datasheet" ""
			(at 388.62 146.05 0)
			(effects
				(font
					(size 1.27 1.27)
					(thickness 0.15)
				)
				(justify left bottom)
				(hide yes)
			)
		)
		(property "Description" ""
			(at 379.73 133.35 0)
			(effects
				(font
					(size 1.27 1.27)
				)
				(hide yes)
			)
		)
		(property "Author" "Antmicro"
			(at 388.62 140.97 0)
			(effects
				(font
					(size 1.27 1.27)
					(thickness 0.15)
				)
				(justify left bottom)
				(hide yes)
			)
		)
		(property "License" "Apache-2.0"
			(at 388.62 143.51 0)
			(effects
				(font
					(size 1.27 1.27)
					(thickness 0.15)
				)
				(justify left bottom)
				(hide yes)
			)
		)
		(pin "1"
		)
		(instances
			(project "OCuLink to 10GbE adapter"
				(path ""
					(reference "#PWR0203")
					(unit 1)
				)
			)
			(project "thunderbolt-to-10gbe-adapter"
				(path ""
					(reference "#PWR0344")
					(unit 1)
				)
			)
		)
	)
	(symbol
		(lib_id "antmicropower:GND")
		(at 361.95 93.98 0)
		(unit 1)
		(exclude_from_sim no)
		(in_bom yes)
		(on_board yes)
		(dnp no)
		(property "Reference" "#PWR0333"
			(at 370.84 96.52 0)
			(effects
				(font
					(size 1.27 1.27)
					(thickness 0.15)
				)
				(justify left bottom)
				(hide yes)
			)
		)
		(property "Value" "GND"
			(at 361.95 97.79 0)
			(effects
				(font
					(size 1.27 1.27)
					(thickness 0.15)
				)
			)
		)
		(property "Footprint" ""
			(at 370.84 101.6 0)
			(effects
				(font
					(size 1.27 1.27)
					(thickness 0.15)
				)
				(justify left bottom)
				(hide yes)
			)
		)
		(property "Datasheet" ""
			(at 370.84 106.68 0)
			(effects
				(font
					(size 1.27 1.27)
					(thickness 0.15)
				)
				(justify left bottom)
				(hide yes)
			)
		)
		(property "Description" ""
			(at 361.95 93.98 0)
			(effects
				(font
					(size 1.27 1.27)
				)
				(hide yes)
			)
		)
		(property "Author" "Antmicro"
			(at 370.84 101.6 0)
			(effects
				(font
					(size 1.27 1.27)
					(thickness 0.15)
				)
				(justify left bottom)
				(hide yes)
			)
		)
		(property "License" "Apache-2.0"
			(at 370.84 104.14 0)
			(effects
				(font
					(size 1.27 1.27)
					(thickness 0.15)
				)
				(justify left bottom)
				(hide yes)
			)
		)
		(pin "1"
		)
		(instances
			(project "OCuLink to 10GbE adapter"
				(path ""
					(reference "#PWR0170")
					(unit 1)
				)
			)
			(project "thunderbolt-to-10gbe-adapter"
				(path ""
					(reference "#PWR0333")
					(unit 1)
				)
			)
		)
	)
	(symbol
		(lib_id "antmicroCapacitors0402:C_1u_25V_0402")
		(at 124.46 73.66 90)
		(unit 1)
		(exclude_from_sim no)
		(in_bom yes)
		(on_board yes)
		(dnp no)
		(property "Reference" "C185"
			(at 126.492 69.85 90)
			(effects
				(font
					(size 1.27 1.27)
					(thickness 0.15)
				)
				(justify right)
			)
		)
		(property "Value" "C_1u_25V_0402"
			(at 134.62 53.34 0)
			(effects
				(font
					(size 1.27 1.27)
					(thickness 0.15)
				)
				(justify left bottom)
				(hide yes)
			)
		)
		(property "Footprint" "antmicro-footprints:C_0402_1005Metric"
			(at 137.16 53.34 0)
			(effects
				(font
					(size 1.27 1.27)
					(thickness 0.15)
				)
				(justify left bottom)
				(hide yes)
			)
		)
		(property "Datasheet" "https://www.murata.com/products/productdetail?partno=GRM155R61E105KE11%23"
			(at 139.7 53.34 0)
			(effects
				(font
					(size 1.27 1.27)
					(thickness 0.15)
				)
				(justify left bottom)
				(hide yes)
			)
		)
		(property "Description" "SMD Multilayer Ceramic Capacitor, 1 µF, 25 V, 0402 [1005 Metric], ± 10%, X5R, GRM Series"
			(at 124.46 73.66 0)
			(effects
				(font
					(size 1.27 1.27)
				)
				(hide yes)
			)
		)
		(property "MPN" "GRM155R61E105KE11J"
			(at 142.24 53.34 0)
			(effects
				(font
					(size 1.27 1.27)
					(thickness 0.15)
				)
				(justify left bottom)
				(hide yes)
			)
		)
		(property "Manufacturer" "Murata"
			(at 144.78 53.34 0)
			(effects
				(font
					(size 1.27 1.27)
					(thickness 0.15)
				)
				(justify left bottom)
				(hide yes)
			)
		)
		(property "License" "Apache-2.0"
			(at 147.32 53.34 0)
			(effects
				(font
					(size 1.27 1.27)
					(thickness 0.15)
				)
				(justify left bottom)
				(hide yes)
			)
		)
		(property "Author" "Antmicro"
			(at 149.86 53.34 0)
			(effects
				(font
					(size 1.27 1.27)
					(thickness 0.15)
				)
				(justify left bottom)
				(hide yes)
			)
		)
		(property "Val" "1u"
			(at 126.492 72.39 90)
			(effects
				(font
					(size 1.27 1.27)
					(thickness 0.15)
				)
				(justify right)
			)
		)
		(property "Voltage" "25V"
			(at 152.4 53.34 0)
			(effects
				(font
					(size 1.27 1.27)
				)
				(justify left bottom)
				(hide yes)
			)
		)
		(property "Dielectric" "X5R"
			(at 154.94 53.34 0)
			(effects
				(font
					(size 1.27 1.27)
				)
				(justify left bottom)
				(hide yes)
			)
		)
		(pin "2"
		)
		(pin "1"
		)
		(instances
			(project "OCuLink to 10GbE adapter"
				(path ""
					(reference "C101")
					(unit 1)
				)
			)
			(project "thunderbolt-to-10gbe-adapter"
				(path ""
					(reference "C185")
					(unit 1)
				)
			)
		)
	)
	(symbol
		(lib_id "antmicroCapacitors0603:C_10u_10V_X7R_0603")
		(at 88.9 73.66 90)
		(unit 1)
		(exclude_from_sim no)
		(in_bom yes)
		(on_board yes)
		(dnp no)
		(property "Reference" "C167"
			(at 90.678 69.85 90)
			(effects
				(font
					(size 1.27 1.27)
					(thickness 0.15)
				)
				(justify right)
			)
		)
		(property "Value" "C_10u_10V_X7R_0603"
			(at 99.06 58.42 0)
			(effects
				(font
					(size 1.27 1.27)
					(thickness 0.15)
				)
				(justify left bottom)
				(hide yes)
			)
		)
		(property "Footprint" "antmicro-footprints:C_0603_1608Metric"
			(at 101.6 58.42 0)
			(effects
				(font
					(size 1.27 1.27)
					(thickness 0.15)
				)
				(justify left bottom)
				(hide yes)
			)
		)
		(property "Datasheet" "https://www.murata.com/products/productdetail?partno=GRM188Z71A106KA73%23"
			(at 104.14 58.42 0)
			(effects
				(font
					(size 1.27 1.27)
					(thickness 0.15)
				)
				(justify left bottom)
				(hide yes)
			)
		)
		(property "Description" "SMD Multilayer Ceramic Capacitor,  10µF, 10V, 0603, ±10%, X7R"
			(at 88.9 73.66 0)
			(effects
				(font
					(size 1.27 1.27)
				)
				(hide yes)
			)
		)
		(property "MPN" "GRM188Z71A106KA73D"
			(at 106.68 58.42 0)
			(effects
				(font
					(size 1.27 1.27)
					(thickness 0.15)
				)
				(justify left bottom)
				(hide yes)
			)
		)
		(property "Val" "10u"
			(at 90.678 72.39 90)
			(effects
				(font
					(size 1.27 1.27)
					(thickness 0.15)
				)
				(justify right)
			)
		)
		(property "Voltage" "10V"
			(at 109.22 58.42 0)
			(effects
				(font
					(size 1.27 1.27)
					(thickness 0.15)
				)
				(justify left bottom)
				(hide yes)
			)
		)
		(property "Dielectric" "X7R"
			(at 111.76 58.42 0)
			(effects
				(font
					(size 1.27 1.27)
					(thickness 0.15)
				)
				(justify left bottom)
				(hide yes)
			)
		)
		(property "Manufacturer" "Murata"
			(at 114.3 58.42 0)
			(effects
				(font
					(size 1.27 1.27)
					(thickness 0.15)
				)
				(justify left bottom)
				(hide yes)
			)
		)
		(property "License" "Apache-2.0"
			(at 116.84 58.42 0)
			(effects
				(font
					(size 1.27 1.27)
					(thickness 0.15)
				)
				(justify left bottom)
				(hide yes)
			)
		)
		(property "Author" "Antmicro"
			(at 119.38 58.42 0)
			(effects
				(font
					(size 1.27 1.27)
					(thickness 0.15)
				)
				(justify left bottom)
				(hide yes)
			)
		)
		(pin "1"
		)
		(pin "2"
		)
		(instances
			(project "OCuLink to 10GbE adapter"
				(path ""
					(reference "C99")
					(unit 1)
				)
			)
			(project "thunderbolt-to-10gbe-adapter"
				(path ""
					(reference "C167")
					(unit 1)
				)
			)
		)
	)
	(symbol
		(lib_id "antmicropower:PWR_FLAG")
		(at 102.87 91.44 0)
		(unit 1)
		(exclude_from_sim no)
		(in_bom yes)
		(on_board yes)
		(dnp no)
		(fields_autoplaced yes)
		(property "Reference" "#FLG030"
			(at 102.87 89.535 0)
			(effects
				(font
					(size 1.27 1.27)
				)
				(hide yes)
			)
		)
		(property "Value" "PWR_FLAG"
			(at 102.87 86.36 0)
			(effects
				(font
					(size 1.27 1.27)
				)
			)
		)
		(property "Footprint" ""
			(at 102.87 91.44 0)
			(effects
				(font
					(size 1.27 1.27)
				)
				(hide yes)
			)
		)
		(property "Datasheet" ""
			(at 102.87 91.44 0)
			(effects
				(font
					(size 1.27 1.27)
				)
				(hide yes)
			)
		)
		(property "Description" ""
			(at 102.87 93.98 0)
			(effects
				(font
					(size 1.27 1.27)
				)
				(justify left bottom)
				(hide yes)
			)
		)
		(pin "1"
		)
		(instances
			(project ""
				(path ""
					(reference "#FLG012")
					(unit 1)
				)
			)
			(project "thunderbolt-to-10gbe-adapter"
				(path ""
					(reference "#FLG030")
					(unit 1)
				)
			)
		)
	)
	(symbol
		(lib_id "antmicropower:GND")
		(at 299.72 76.2 0)
		(unit 1)
		(exclude_from_sim no)
		(in_bom yes)
		(on_board yes)
		(dnp no)
		(property "Reference" "#PWR0298"
			(at 308.61 78.74 0)
			(effects
				(font
					(size 1.27 1.27)
					(thickness 0.15)
				)
				(justify left bottom)
				(hide yes)
			)
		)
		(property "Value" "GND"
			(at 299.72 80.01 0)
			(effects
				(font
					(size 1.27 1.27)
					(thickness 0.15)
				)
			)
		)
		(property "Footprint" ""
			(at 308.61 83.82 0)
			(effects
				(font
					(size 1.27 1.27)
					(thickness 0.15)
				)
				(justify left bottom)
				(hide yes)
			)
		)
		(property "Datasheet" ""
			(at 308.61 88.9 0)
			(effects
				(font
					(size 1.27 1.27)
					(thickness 0.15)
				)
				(justify left bottom)
				(hide yes)
			)
		)
		(property "Description" ""
			(at 299.72 76.2 0)
			(effects
				(font
					(size 1.27 1.27)
				)
				(hide yes)
			)
		)
		(property "Author" "Antmicro"
			(at 308.61 83.82 0)
			(effects
				(font
					(size 1.27 1.27)
					(thickness 0.15)
				)
				(justify left bottom)
				(hide yes)
			)
		)
		(property "License" "Apache-2.0"
			(at 308.61 86.36 0)
			(effects
				(font
					(size 1.27 1.27)
					(thickness 0.15)
				)
				(justify left bottom)
				(hide yes)
			)
		)
		(pin "1"
		)
		(instances
			(project "OCuLink to 10GbE adapter"
				(path ""
					(reference "#PWR0139")
					(unit 1)
				)
			)
			(project "thunderbolt-to-10gbe-adapter"
				(path ""
					(reference "#PWR0298")
					(unit 1)
				)
			)
		)
	)
	(symbol
		(lib_id "antmicropower:GND")
		(at 46.99 54.61 0)
		(mirror y)
		(unit 1)
		(exclude_from_sim no)
		(in_bom yes)
		(on_board yes)
		(dnp no)
		(property "Reference" "#PWR0504"
			(at 38.1 57.15 0)
			(effects
				(font
					(size 1.27 1.27)
					(thickness 0.15)
				)
				(justify left bottom)
				(hide yes)
			)
		)
		(property "Value" "GND"
			(at 46.99 58.42 0)
			(effects
				(font
					(size 1.27 1.27)
					(thickness 0.15)
				)
			)
		)
		(property "Footprint" ""
			(at 38.1 62.23 0)
			(effects
				(font
					(size 1.27 1.27)
					(thickness 0.15)
				)
				(justify left bottom)
				(hide yes)
			)
		)
		(property "Datasheet" ""
			(at 38.1 67.31 0)
			(effects
				(font
					(size 1.27 1.27)
					(thickness 0.15)
				)
				(justify left bottom)
				(hide yes)
			)
		)
		(property "Description" ""
			(at 46.99 54.61 0)
			(effects
				(font
					(size 1.27 1.27)
				)
				(hide yes)
			)
		)
		(property "Author" "Antmicro"
			(at 38.1 62.23 0)
			(effects
				(font
					(size 1.27 1.27)
					(thickness 0.15)
				)
				(justify left bottom)
				(hide yes)
			)
		)
		(property "License" "Apache-2.0"
			(at 38.1 64.77 0)
			(effects
				(font
					(size 1.27 1.27)
					(thickness 0.15)
				)
				(justify left bottom)
				(hide yes)
			)
		)
		(pin "1"
		)
		(instances
			(project "thunderbolt-to-10gbe-adapter"
				(path ""
					(reference "#PWR0504")
					(unit 1)
				)
			)
		)
	)
	(symbol
		(lib_id "antmicropower:GND")
		(at 361.95 133.35 0)
		(unit 1)
		(exclude_from_sim no)
		(in_bom yes)
		(on_board yes)
		(dnp no)
		(property "Reference" "#PWR0335"
			(at 370.84 135.89 0)
			(effects
				(font
					(size 1.27 1.27)
					(thickness 0.15)
				)
				(justify left bottom)
				(hide yes)
			)
		)
		(property "Value" "GND"
			(at 361.95 137.16 0)
			(effects
				(font
					(size 1.27 1.27)
					(thickness 0.15)
				)
			)
		)
		(property "Footprint" ""
			(at 370.84 140.97 0)
			(effects
				(font
					(size 1.27 1.27)
					(thickness 0.15)
				)
				(justify left bottom)
				(hide yes)
			)
		)
		(property "Datasheet" ""
			(at 370.84 146.05 0)
			(effects
				(font
					(size 1.27 1.27)
					(thickness 0.15)
				)
				(justify left bottom)
				(hide yes)
			)
		)
		(property "Description" ""
			(at 361.95 133.35 0)
			(effects
				(font
					(size 1.27 1.27)
				)
				(hide yes)
			)
		)
		(property "Author" "Antmicro"
			(at 370.84 140.97 0)
			(effects
				(font
					(size 1.27 1.27)
					(thickness 0.15)
				)
				(justify left bottom)
				(hide yes)
			)
		)
		(property "License" "Apache-2.0"
			(at 370.84 143.51 0)
			(effects
				(font
					(size 1.27 1.27)
					(thickness 0.15)
				)
				(justify left bottom)
				(hide yes)
			)
		)
		(pin "1"
		)
		(instances
			(project "OCuLink to 10GbE adapter"
				(path ""
					(reference "#PWR0201")
					(unit 1)
				)
			)
			(project "thunderbolt-to-10gbe-adapter"
				(path ""
					(reference "#PWR0335")
					(unit 1)
				)
			)
		)
	)
	(symbol
		(lib_id "antmicropower:GND")
		(at 388.62 54.61 0)
		(unit 1)
		(exclude_from_sim no)
		(in_bom yes)
		(on_board yes)
		(dnp no)
		(property "Reference" "#PWR0345"
			(at 397.51 57.15 0)
			(effects
				(font
					(size 1.27 1.27)
					(thickness 0.15)
				)
				(justify left bottom)
				(hide yes)
			)
		)
		(property "Value" "GND"
			(at 388.62 58.42 0)
			(effects
				(font
					(size 1.27 1.27)
					(thickness 0.15)
				)
			)
		)
		(property "Footprint" ""
			(at 397.51 62.23 0)
			(effects
				(font
					(size 1.27 1.27)
					(thickness 0.15)
				)
				(justify left bottom)
				(hide yes)
			)
		)
		(property "Datasheet" ""
			(at 397.51 67.31 0)
			(effects
				(font
					(size 1.27 1.27)
					(thickness 0.15)
				)
				(justify left bottom)
				(hide yes)
			)
		)
		(property "Description" ""
			(at 388.62 54.61 0)
			(effects
				(font
					(size 1.27 1.27)
				)
				(hide yes)
			)
		)
		(property "Author" "Antmicro"
			(at 397.51 62.23 0)
			(effects
				(font
					(size 1.27 1.27)
					(thickness 0.15)
				)
				(justify left bottom)
				(hide yes)
			)
		)
		(property "License" "Apache-2.0"
			(at 397.51 64.77 0)
			(effects
				(font
					(size 1.27 1.27)
					(thickness 0.15)
				)
				(justify left bottom)
				(hide yes)
			)
		)
		(pin "1"
		)
		(instances
			(project "OCuLink to 10GbE adapter"
				(path ""
					(reference "#PWR0131")
					(unit 1)
				)
			)
			(project "thunderbolt-to-10gbe-adapter"
				(path ""
					(reference "#PWR0345")
					(unit 1)
				)
			)
		)
	)
	(symbol
		(lib_id "antmicropower:PWR_FLAG")
		(at 101.6 251.46 0)
		(unit 1)
		(exclude_from_sim no)
		(in_bom yes)
		(on_board yes)
		(dnp no)
		(fields_autoplaced yes)
		(property "Reference" "#FLG029"
			(at 101.6 249.555 0)
			(effects
				(font
					(size 1.27 1.27)
				)
				(hide yes)
			)
		)
		(property "Value" "PWR_FLAG"
			(at 101.6 246.38 0)
			(effects
				(font
					(size 1.27 1.27)
				)
			)
		)
		(property "Footprint" ""
			(at 101.6 251.46 0)
			(effects
				(font
					(size 1.27 1.27)
				)
				(hide yes)
			)
		)
		(property "Datasheet" ""
			(at 101.6 251.46 0)
			(effects
				(font
					(size 1.27 1.27)
				)
				(hide yes)
			)
		)
		(property "Description" ""
			(at 101.6 254 0)
			(effects
				(font
					(size 1.27 1.27)
				)
				(justify left bottom)
				(hide yes)
			)
		)
		(pin "1"
		)
		(instances
			(project "OCuLink to 10GbE adapter"
				(path ""
					(reference "#FLG019")
					(unit 1)
				)
			)
			(project "thunderbolt-to-10gbe-adapter"
				(path ""
					(reference "#FLG029")
					(unit 1)
				)
			)
		)
	)
	(symbol
		(lib_id "antmicroCapacitors0402:C_1u_25V_0402")
		(at 299.72 73.66 90)
		(unit 1)
		(exclude_from_sim no)
		(in_bom yes)
		(on_board yes)
		(dnp no)
		(property "Reference" "C212"
			(at 301.752 69.85 90)
			(effects
				(font
					(size 1.27 1.27)
					(thickness 0.15)
				)
				(justify right)
			)
		)
		(property "Value" "C_1u_25V_0402"
			(at 309.88 53.34 0)
			(effects
				(font
					(size 1.27 1.27)
					(thickness 0.15)
				)
				(justify left bottom)
				(hide yes)
			)
		)
		(property "Footprint" "antmicro-footprints:C_0402_1005Metric"
			(at 312.42 53.34 0)
			(effects
				(font
					(size 1.27 1.27)
					(thickness 0.15)
				)
				(justify left bottom)
				(hide yes)
			)
		)
		(property "Datasheet" "https://www.murata.com/products/productdetail?partno=GRM155R61E105KE11%23"
			(at 314.96 53.34 0)
			(effects
				(font
					(size 1.27 1.27)
					(thickness 0.15)
				)
				(justify left bottom)
				(hide yes)
			)
		)
		(property "Description" "SMD Multilayer Ceramic Capacitor, 1 µF, 25 V, 0402 [1005 Metric], ± 10%, X5R, GRM Series"
			(at 299.72 73.66 0)
			(effects
				(font
					(size 1.27 1.27)
				)
				(hide yes)
			)
		)
		(property "MPN" "GRM155R61E105KE11J"
			(at 317.5 53.34 0)
			(effects
				(font
					(size 1.27 1.27)
					(thickness 0.15)
				)
				(justify left bottom)
				(hide yes)
			)
		)
		(property "Manufacturer" "Murata"
			(at 320.04 53.34 0)
			(effects
				(font
					(size 1.27 1.27)
					(thickness 0.15)
				)
				(justify left bottom)
				(hide yes)
			)
		)
		(property "License" "Apache-2.0"
			(at 322.58 53.34 0)
			(effects
				(font
					(size 1.27 1.27)
					(thickness 0.15)
				)
				(justify left bottom)
				(hide yes)
			)
		)
		(property "Author" "Antmicro"
			(at 325.12 53.34 0)
			(effects
				(font
					(size 1.27 1.27)
					(thickness 0.15)
				)
				(justify left bottom)
				(hide yes)
			)
		)
		(property "Val" "1u"
			(at 301.752 72.39 90)
			(effects
				(font
					(size 1.27 1.27)
					(thickness 0.15)
				)
				(justify right)
			)
		)
		(property "Voltage" "25V"
			(at 327.66 53.34 0)
			(effects
				(font
					(size 1.27 1.27)
				)
				(justify left bottom)
				(hide yes)
			)
		)
		(property "Dielectric" "X5R"
			(at 330.2 53.34 0)
			(effects
				(font
					(size 1.27 1.27)
				)
				(justify left bottom)
				(hide yes)
			)
		)
		(pin "2"
		)
		(pin "1"
		)
		(instances
			(project "OCuLink to 10GbE adapter"
				(path ""
					(reference "C105")
					(unit 1)
				)
			)
			(project "thunderbolt-to-10gbe-adapter"
				(path ""
					(reference "C212")
					(unit 1)
				)
			)
		)
	)
	(symbol
		(lib_id "antmicroCapacitors0402:C_1u_25V_0402")
		(at 142.24 180.34 90)
		(unit 1)
		(exclude_from_sim no)
		(in_bom yes)
		(on_board yes)
		(dnp no)
		(property "Reference" "C200"
			(at 144.272 176.53 90)
			(effects
				(font
					(size 1.27 1.27)
					(thickness 0.15)
				)
				(justify right)
			)
		)
		(property "Value" "C_1u_25V_0402"
			(at 152.4 160.02 0)
			(effects
				(font
					(size 1.27 1.27)
					(thickness 0.15)
				)
				(justify left bottom)
				(hide yes)
			)
		)
		(property "Footprint" "antmicro-footprints:C_0402_1005Metric"
			(at 154.94 160.02 0)
			(effects
				(font
					(size 1.27 1.27)
					(thickness 0.15)
				)
				(justify left bottom)
				(hide yes)
			)
		)
		(property "Datasheet" "https://www.murata.com/products/productdetail?partno=GRM155R61E105KE11%23"
			(at 157.48 160.02 0)
			(effects
				(font
					(size 1.27 1.27)
					(thickness 0.15)
				)
				(justify left bottom)
				(hide yes)
			)
		)
		(property "Description" "SMD Multilayer Ceramic Capacitor, 1 µF, 25 V, 0402 [1005 Metric], ± 10%, X5R, GRM Series"
			(at 142.24 180.34 0)
			(effects
				(font
					(size 1.27 1.27)
				)
				(hide yes)
			)
		)
		(property "MPN" "GRM155R61E105KE11J"
			(at 160.02 160.02 0)
			(effects
				(font
					(size 1.27 1.27)
					(thickness 0.15)
				)
				(justify left bottom)
				(hide yes)
			)
		)
		(property "Manufacturer" "Murata"
			(at 162.56 160.02 0)
			(effects
				(font
					(size 1.27 1.27)
					(thickness 0.15)
				)
				(justify left bottom)
				(hide yes)
			)
		)
		(property "License" "Apache-2.0"
			(at 165.1 160.02 0)
			(effects
				(font
					(size 1.27 1.27)
					(thickness 0.15)
				)
				(justify left bottom)
				(hide yes)
			)
		)
		(property "Author" "Antmicro"
			(at 167.64 160.02 0)
			(effects
				(font
					(size 1.27 1.27)
					(thickness 0.15)
				)
				(justify left bottom)
				(hide yes)
			)
		)
		(property "Val" "1u"
			(at 144.272 179.07 90)
			(effects
				(font
					(size 1.27 1.27)
					(thickness 0.15)
				)
				(justify right)
			)
		)
		(property "Voltage" "25V"
			(at 170.18 160.02 0)
			(effects
				(font
					(size 1.27 1.27)
				)
				(justify left bottom)
				(hide yes)
			)
		)
		(property "Dielectric" "X5R"
			(at 172.72 160.02 0)
			(effects
				(font
					(size 1.27 1.27)
				)
				(justify left bottom)
				(hide yes)
			)
		)
		(pin "2"
		)
		(pin "1"
		)
		(instances
			(project "OCuLink to 10GbE adapter"
				(path ""
					(reference "C177")
					(unit 1)
				)
			)
			(project "thunderbolt-to-10gbe-adapter"
				(path ""
					(reference "C200")
					(unit 1)
				)
			)
		)
	)
	(symbol
		(lib_id "antmicropower:GND")
		(at 124.46 209.55 0)
		(unit 1)
		(exclude_from_sim no)
		(in_bom yes)
		(on_board yes)
		(dnp no)
		(property "Reference" "#PWR0260"
			(at 133.35 212.09 0)
			(effects
				(font
					(size 1.27 1.27)
					(thickness 0.15)
				)
				(justify left bottom)
				(hide yes)
			)
		)
		(property "Value" "GND"
			(at 124.46 213.36 0)
			(effects
				(font
					(size 1.27 1.27)
					(thickness 0.15)
				)
			)
		)
		(property "Footprint" ""
			(at 133.35 217.17 0)
			(effects
				(font
					(size 1.27 1.27)
					(thickness 0.15)
				)
				(justify left bottom)
				(hide yes)
			)
		)
		(property "Datasheet" ""
			(at 133.35 222.25 0)
			(effects
				(font
					(size 1.27 1.27)
					(thickness 0.15)
				)
				(justify left bottom)
				(hide yes)
			)
		)
		(property "Description" ""
			(at 124.46 209.55 0)
			(effects
				(font
					(size 1.27 1.27)
				)
				(hide yes)
			)
		)
		(property "Author" "Antmicro"
			(at 133.35 217.17 0)
			(effects
				(font
					(size 1.27 1.27)
					(thickness 0.15)
				)
				(justify left bottom)
				(hide yes)
			)
		)
		(property "License" "Apache-2.0"
			(at 133.35 219.71 0)
			(effects
				(font
					(size 1.27 1.27)
					(thickness 0.15)
				)
				(justify left bottom)
				(hide yes)
			)
		)
		(pin "1"
		)
		(instances
			(project "OCuLink to 10GbE adapter"
				(path ""
					(reference "#PWR0234")
					(unit 1)
				)
			)
			(project "thunderbolt-to-10gbe-adapter"
				(path ""
					(reference "#PWR0260")
					(unit 1)
				)
			)
		)
	)
	(symbol
		(lib_id "antmicropower:GND")
		(at 344.17 133.35 0)
		(unit 1)
		(exclude_from_sim no)
		(in_bom yes)
		(on_board yes)
		(dnp no)
		(property "Reference" "#PWR0325"
			(at 353.06 135.89 0)
			(effects
				(font
					(size 1.27 1.27)
					(thickness 0.15)
				)
				(justify left bottom)
				(hide yes)
			)
		)
		(property "Value" "GND"
			(at 344.17 137.16 0)
			(effects
				(font
					(size 1.27 1.27)
					(thickness 0.15)
				)
			)
		)
		(property "Footprint" ""
			(at 353.06 140.97 0)
			(effects
				(font
					(size 1.27 1.27)
					(thickness 0.15)
				)
				(justify left bottom)
				(hide yes)
			)
		)
		(property "Datasheet" ""
			(at 353.06 146.05 0)
			(effects
				(font
					(size 1.27 1.27)
					(thickness 0.15)
				)
				(justify left bottom)
				(hide yes)
			)
		)
		(property "Description" ""
			(at 344.17 133.35 0)
			(effects
				(font
					(size 1.27 1.27)
				)
				(hide yes)
			)
		)
		(property "Author" "Antmicro"
			(at 353.06 140.97 0)
			(effects
				(font
					(size 1.27 1.27)
					(thickness 0.15)
				)
				(justify left bottom)
				(hide yes)
			)
		)
		(property "License" "Apache-2.0"
			(at 353.06 143.51 0)
			(effects
				(font
					(size 1.27 1.27)
					(thickness 0.15)
				)
				(justify left bottom)
				(hide yes)
			)
		)
		(pin "1"
		)
		(instances
			(project "OCuLink to 10GbE adapter"
				(path ""
					(reference "#PWR0199")
					(unit 1)
				)
			)
			(project "thunderbolt-to-10gbe-adapter"
				(path ""
					(reference "#PWR0325")
					(unit 1)
				)
			)
		)
	)
	(symbol
		(lib_id "antmicropower:GND")
		(at 142.24 129.54 0)
		(unit 1)
		(exclude_from_sim no)
		(in_bom yes)
		(on_board yes)
		(dnp no)
		(property "Reference" "#PWR0269"
			(at 151.13 132.08 0)
			(effects
				(font
					(size 1.27 1.27)
					(thickness 0.15)
				)
				(justify left bottom)
				(hide yes)
			)
		)
		(property "Value" "GND"
			(at 142.24 133.35 0)
			(effects
				(font
					(size 1.27 1.27)
					(thickness 0.15)
				)
			)
		)
		(property "Footprint" ""
			(at 151.13 137.16 0)
			(effects
				(font
					(size 1.27 1.27)
					(thickness 0.15)
				)
				(justify left bottom)
				(hide yes)
			)
		)
		(property "Datasheet" ""
			(at 151.13 142.24 0)
			(effects
				(font
					(size 1.27 1.27)
					(thickness 0.15)
				)
				(justify left bottom)
				(hide yes)
			)
		)
		(property "Description" ""
			(at 142.24 129.54 0)
			(effects
				(font
					(size 1.27 1.27)
				)
				(hide yes)
			)
		)
		(property "Author" "Antmicro"
			(at 151.13 137.16 0)
			(effects
				(font
					(size 1.27 1.27)
					(thickness 0.15)
				)
				(justify left bottom)
				(hide yes)
			)
		)
		(property "License" "Apache-2.0"
			(at 151.13 139.7 0)
			(effects
				(font
					(size 1.27 1.27)
					(thickness 0.15)
				)
				(justify left bottom)
				(hide yes)
			)
		)
		(pin "1"
		)
		(instances
			(project "OCuLink to 10GbE adapter"
				(path ""
					(reference "#PWR0193")
					(unit 1)
				)
			)
			(project "thunderbolt-to-10gbe-adapter"
				(path ""
					(reference "#PWR0269")
					(unit 1)
				)
			)
		)
	)
	(symbol
		(lib_id "antmicropower:GND")
		(at 39.37 156.21 0)
		(unit 1)
		(exclude_from_sim no)
		(in_bom yes)
		(on_board yes)
		(dnp no)
		(property "Reference" "#PWR0500"
			(at 48.26 158.75 0)
			(effects
				(font
					(size 1.27 1.27)
					(thickness 0.15)
				)
				(justify left bottom)
				(hide yes)
			)
		)
		(property "Value" "GND"
			(at 39.37 160.02 0)
			(effects
				(font
					(size 1.27 1.27)
					(thickness 0.15)
				)
			)
		)
		(property "Footprint" ""
			(at 48.26 163.83 0)
			(effects
				(font
					(size 1.27 1.27)
					(thickness 0.15)
				)
				(justify left bottom)
				(hide yes)
			)
		)
		(property "Datasheet" ""
			(at 48.26 168.91 0)
			(effects
				(font
					(size 1.27 1.27)
					(thickness 0.15)
				)
				(justify left bottom)
				(hide yes)
			)
		)
		(property "Description" ""
			(at 39.37 156.21 0)
			(effects
				(font
					(size 1.27 1.27)
				)
				(hide yes)
			)
		)
		(property "Author" "Antmicro"
			(at 48.26 163.83 0)
			(effects
				(font
					(size 1.27 1.27)
					(thickness 0.15)
				)
				(justify left bottom)
				(hide yes)
			)
		)
		(property "License" "Apache-2.0"
			(at 48.26 166.37 0)
			(effects
				(font
					(size 1.27 1.27)
					(thickness 0.15)
				)
				(justify left bottom)
				(hide yes)
			)
		)
		(pin "1"
		)
		(instances
			(project "thunderbolt-to-10gbe-adapter"
				(path ""
					(reference "#PWR0500")
					(unit 1)
				)
			)
		)
	)
	(symbol
		(lib_id "antmicropower:GND")
		(at 388.62 133.35 0)
		(unit 1)
		(exclude_from_sim no)
		(in_bom yes)
		(on_board yes)
		(dnp no)
		(property "Reference" "#PWR0348"
			(at 397.51 135.89 0)
			(effects
				(font
					(size 1.27 1.27)
					(thickness 0.15)
				)
				(justify left bottom)
				(hide yes)
			)
		)
		(property "Value" "GND"
			(at 388.62 137.16 0)
			(effects
				(font
					(size 1.27 1.27)
					(thickness 0.15)
				)
			)
		)
		(property "Footprint" ""
			(at 397.51 140.97 0)
			(effects
				(font
					(size 1.27 1.27)
					(thickness 0.15)
				)
				(justify left bottom)
				(hide yes)
			)
		)
		(property "Datasheet" ""
			(at 397.51 146.05 0)
			(effects
				(font
					(size 1.27 1.27)
					(thickness 0.15)
				)
				(justify left bottom)
				(hide yes)
			)
		)
		(property "Description" ""
			(at 388.62 133.35 0)
			(effects
				(font
					(size 1.27 1.27)
				)
				(hide yes)
			)
		)
		(property "Author" "Antmicro"
			(at 397.51 140.97 0)
			(effects
				(font
					(size 1.27 1.27)
					(thickness 0.15)
				)
				(justify left bottom)
				(hide yes)
			)
		)
		(property "License" "Apache-2.0"
			(at 397.51 143.51 0)
			(effects
				(font
					(size 1.27 1.27)
					(thickness 0.15)
				)
				(justify left bottom)
				(hide yes)
			)
		)
		(pin "1"
		)
		(instances
			(project "OCuLink to 10GbE adapter"
				(path ""
					(reference "#PWR0204")
					(unit 1)
				)
			)
			(project "thunderbolt-to-10gbe-adapter"
				(path ""
					(reference "#PWR0348")
					(unit 1)
				)
			)
		)
	)
	(symbol
		(lib_id "antmicroCapacitors0402:C_1u_25V_0402")
		(at 361.95 73.66 90)
		(unit 1)
		(exclude_from_sim no)
		(in_bom yes)
		(on_board yes)
		(dnp no)
		(property "Reference" "C246"
			(at 363.982 69.85 90)
			(effects
				(font
					(size 1.27 1.27)
					(thickness 0.15)
				)
				(justify right)
			)
		)
		(property "Value" "C_1u_25V_0402"
			(at 372.11 53.34 0)
			(effects
				(font
					(size 1.27 1.27)
					(thickness 0.15)
				)
				(justify left bottom)
				(hide yes)
			)
		)
		(property "Footprint" "antmicro-footprints:C_0402_1005Metric"
			(at 374.65 53.34 0)
			(effects
				(font
					(size 1.27 1.27)
					(thickness 0.15)
				)
				(justify left bottom)
				(hide yes)
			)
		)
		(property "Datasheet" "https://www.murata.com/products/productdetail?partno=GRM155R61E105KE11%23"
			(at 377.19 53.34 0)
			(effects
				(font
					(size 1.27 1.27)
					(thickness 0.15)
				)
				(justify left bottom)
				(hide yes)
			)
		)
		(property "Description" "SMD Multilayer Ceramic Capacitor, 1 µF, 25 V, 0402 [1005 Metric], ± 10%, X5R, GRM Series"
			(at 361.95 73.66 0)
			(effects
				(font
					(size 1.27 1.27)
				)
				(hide yes)
			)
		)
		(property "MPN" "GRM155R61E105KE11J"
			(at 379.73 53.34 0)
			(effects
				(font
					(size 1.27 1.27)
					(thickness 0.15)
				)
				(justify left bottom)
				(hide yes)
			)
		)
		(property "Manufacturer" "Murata"
			(at 382.27 53.34 0)
			(effects
				(font
					(size 1.27 1.27)
					(thickness 0.15)
				)
				(justify left bottom)
				(hide yes)
			)
		)
		(property "License" "Apache-2.0"
			(at 384.81 53.34 0)
			(effects
				(font
					(size 1.27 1.27)
					(thickness 0.15)
				)
				(justify left bottom)
				(hide yes)
			)
		)
		(property "Author" "Antmicro"
			(at 387.35 53.34 0)
			(effects
				(font
					(size 1.27 1.27)
					(thickness 0.15)
				)
				(justify left bottom)
				(hide yes)
			)
		)
		(property "Val" "1u"
			(at 363.982 72.39 90)
			(effects
				(font
					(size 1.27 1.27)
					(thickness 0.15)
				)
				(justify right)
			)
		)
		(property "Voltage" "25V"
			(at 389.89 53.34 0)
			(effects
				(font
					(size 1.27 1.27)
				)
				(justify left bottom)
				(hide yes)
			)
		)
		(property "Dielectric" "X5R"
			(at 392.43 53.34 0)
			(effects
				(font
					(size 1.27 1.27)
				)
				(justify left bottom)
				(hide yes)
			)
		)
		(pin "2"
		)
		(pin "1"
		)
		(instances
			(project "OCuLink to 10GbE adapter"
				(path ""
					(reference "C112")
					(unit 1)
				)
			)
			(project "thunderbolt-to-10gbe-adapter"
				(path ""
					(reference "C246")
					(unit 1)
				)
			)
		)
	)
	(symbol
		(lib_id "antmicropower:GND")
		(at 77.47 129.54 0)
		(unit 1)
		(exclude_from_sim no)
		(in_bom yes)
		(on_board yes)
		(dnp no)
		(property "Reference" "#PWR0233"
			(at 86.36 132.08 0)
			(effects
				(font
					(size 1.27 1.27)
					(thickness 0.15)
				)
				(justify left bottom)
				(hide yes)
			)
		)
		(property "Value" "GND"
			(at 77.47 133.35 0)
			(effects
				(font
					(size 1.27 1.27)
					(thickness 0.15)
				)
			)
		)
		(property "Footprint" ""
			(at 86.36 137.16 0)
			(effects
				(font
					(size 1.27 1.27)
					(thickness 0.15)
				)
				(justify left bottom)
				(hide yes)
			)
		)
		(property "Datasheet" ""
			(at 86.36 142.24 0)
			(effects
				(font
					(size 1.27 1.27)
					(thickness 0.15)
				)
				(justify left bottom)
				(hide yes)
			)
		)
		(property "Description" ""
			(at 77.47 129.54 0)
			(effects
				(font
					(size 1.27 1.27)
				)
				(hide yes)
			)
		)
		(property "Author" "Antmicro"
			(at 86.36 137.16 0)
			(effects
				(font
					(size 1.27 1.27)
					(thickness 0.15)
				)
				(justify left bottom)
				(hide yes)
			)
		)
		(property "License" "Apache-2.0"
			(at 86.36 139.7 0)
			(effects
				(font
					(size 1.27 1.27)
					(thickness 0.15)
				)
				(justify left bottom)
				(hide yes)
			)
		)
		(pin "1"
		)
		(instances
			(project "OCuLink to 10GbE adapter"
				(path ""
					(reference "#PWR0187")
					(unit 1)
				)
			)
			(project "thunderbolt-to-10gbe-adapter"
				(path ""
					(reference "#PWR0233")
					(unit 1)
				)
			)
		)
	)
	(symbol
		(lib_id "antmicroCapacitors0603:C_10u_10V_X7R_0603")
		(at 308.61 130.81 90)
		(unit 1)
		(exclude_from_sim no)
		(in_bom yes)
		(on_board yes)
		(dnp no)
		(property "Reference" "C220"
			(at 310.642 127 90)
			(effects
				(font
					(size 1.27 1.27)
					(thickness 0.15)
				)
				(justify right)
			)
		)
		(property "Value" "C_10u_10V_X7R_0603"
			(at 318.77 115.57 0)
			(effects
				(font
					(size 1.27 1.27)
					(thickness 0.15)
				)
				(justify left bottom)
				(hide yes)
			)
		)
		(property "Footprint" "antmicro-footprints:C_0603_1608Metric"
			(at 321.31 115.57 0)
			(effects
				(font
					(size 1.27 1.27)
					(thickness 0.15)
				)
				(justify left bottom)
				(hide yes)
			)
		)
		(property "Datasheet" "https://www.murata.com/products/productdetail?partno=GRM188Z71A106KA73%23"
			(at 323.85 115.57 0)
			(effects
				(font
					(size 1.27 1.27)
					(thickness 0.15)
				)
				(justify left bottom)
				(hide yes)
			)
		)
		(property "Description" "SMD Multilayer Ceramic Capacitor,  10µF, 10V, 0603, ±10%, X7R"
			(at 308.61 130.81 0)
			(effects
				(font
					(size 1.27 1.27)
				)
				(hide yes)
			)
		)
		(property "MPN" "GRM188Z71A106KA73D"
			(at 326.39 115.57 0)
			(effects
				(font
					(size 1.27 1.27)
					(thickness 0.15)
				)
				(justify left bottom)
				(hide yes)
			)
		)
		(property "Val" "10u"
			(at 310.642 129.54 90)
			(effects
				(font
					(size 1.27 1.27)
					(thickness 0.15)
				)
				(justify right)
			)
		)
		(property "Voltage" "10V"
			(at 328.93 115.57 0)
			(effects
				(font
					(size 1.27 1.27)
					(thickness 0.15)
				)
				(justify left bottom)
				(hide yes)
			)
		)
		(property "Dielectric" "X7R"
			(at 331.47 115.57 0)
			(effects
				(font
					(size 1.27 1.27)
					(thickness 0.15)
				)
				(justify left bottom)
				(hide yes)
			)
		)
		(property "Manufacturer" "Murata"
			(at 334.01 115.57 0)
			(effects
				(font
					(size 1.27 1.27)
					(thickness 0.15)
				)
				(justify left bottom)
				(hide yes)
			)
		)
		(property "License" "Apache-2.0"
			(at 336.55 115.57 0)
			(effects
				(font
					(size 1.27 1.27)
					(thickness 0.15)
				)
				(justify left bottom)
				(hide yes)
			)
		)
		(property "Author" "Antmicro"
			(at 339.09 115.57 0)
			(effects
				(font
					(size 1.27 1.27)
					(thickness 0.15)
				)
				(justify left bottom)
				(hide yes)
			)
		)
		(pin "1"
		)
		(pin "2"
		)
		(instances
			(project "OCuLink to 10GbE adapter"
				(path ""
					(reference "C147")
					(unit 1)
				)
			)
			(project "thunderbolt-to-10gbe-adapter"
				(path ""
					(reference "C220")
					(unit 1)
				)
			)
		)
	)
	(symbol
		(lib_id "antmicropower:GND")
		(at 299.72 133.35 0)
		(unit 1)
		(exclude_from_sim no)
		(in_bom yes)
		(on_board yes)
		(dnp no)
		(property "Reference" "#PWR0301"
			(at 308.61 135.89 0)
			(effects
				(font
					(size 1.27 1.27)
					(thickness 0.15)
				)
				(justify left bottom)
				(hide yes)
			)
		)
		(property "Value" "GND"
			(at 299.72 137.16 0)
			(effects
				(font
					(size 1.27 1.27)
					(thickness 0.15)
				)
			)
		)
		(property "Footprint" ""
			(at 308.61 140.97 0)
			(effects
				(font
					(size 1.27 1.27)
					(thickness 0.15)
				)
				(justify left bottom)
				(hide yes)
			)
		)
		(property "Datasheet" ""
			(at 308.61 146.05 0)
			(effects
				(font
					(size 1.27 1.27)
					(thickness 0.15)
				)
				(justify left bottom)
				(hide yes)
			)
		)
		(property "Description" ""
			(at 299.72 133.35 0)
			(effects
				(font
					(size 1.27 1.27)
				)
				(hide yes)
			)
		)
		(property "Author" "Antmicro"
			(at 308.61 140.97 0)
			(effects
				(font
					(size 1.27 1.27)
					(thickness 0.15)
				)
				(justify left bottom)
				(hide yes)
			)
		)
		(property "License" "Apache-2.0"
			(at 308.61 143.51 0)
			(effects
				(font
					(size 1.27 1.27)
					(thickness 0.15)
				)
				(justify left bottom)
				(hide yes)
			)
		)
		(pin "1"
		)
		(instances
			(project "OCuLink to 10GbE adapter"
				(path ""
					(reference "#PWR0195")
					(unit 1)
				)
			)
			(project "thunderbolt-to-10gbe-adapter"
				(path ""
					(reference "#PWR0301")
					(unit 1)
				)
			)
		)
	)
	(symbol
		(lib_id "antmicropower:GND")
		(at 308.61 133.35 0)
		(unit 1)
		(exclude_from_sim no)
		(in_bom yes)
		(on_board yes)
		(dnp no)
		(property "Reference" "#PWR0306"
			(at 317.5 135.89 0)
			(effects
				(font
					(size 1.27 1.27)
					(thickness 0.15)
				)
				(justify left bottom)
				(hide yes)
			)
		)
		(property "Value" "GND"
			(at 308.61 137.16 0)
			(effects
				(font
					(size 1.27 1.27)
					(thickness 0.15)
				)
			)
		)
		(property "Footprint" ""
			(at 317.5 140.97 0)
			(effects
				(font
					(size 1.27 1.27)
					(thickness 0.15)
				)
				(justify left bottom)
				(hide yes)
			)
		)
		(property "Datasheet" ""
			(at 317.5 146.05 0)
			(effects
				(font
					(size 1.27 1.27)
					(thickness 0.15)
				)
				(justify left bottom)
				(hide yes)
			)
		)
		(property "Description" ""
			(at 308.61 133.35 0)
			(effects
				(font
					(size 1.27 1.27)
				)
				(hide yes)
			)
		)
		(property "Author" "Antmicro"
			(at 317.5 140.97 0)
			(effects
				(font
					(size 1.27 1.27)
					(thickness 0.15)
				)
				(justify left bottom)
				(hide yes)
			)
		)
		(property "License" "Apache-2.0"
			(at 317.5 143.51 0)
			(effects
				(font
					(size 1.27 1.27)
					(thickness 0.15)
				)
				(justify left bottom)
				(hide yes)
			)
		)
		(pin "1"
		)
		(instances
			(project "OCuLink to 10GbE adapter"
				(path ""
					(reference "#PWR0196")
					(unit 1)
				)
			)
			(project "thunderbolt-to-10gbe-adapter"
				(path ""
					(reference "#PWR0306")
					(unit 1)
				)
			)
		)
	)
	(symbol
		(lib_id "antmicropower:VCC")
		(at 234.95 179.07 90)
		(unit 1)
		(exclude_from_sim no)
		(in_bom yes)
		(on_board yes)
		(dnp no)
		(fields_autoplaced yes)
		(property "Reference" "#PWR0289"
			(at 238.76 179.07 0)
			(effects
				(font
					(size 1.27 1.27)
				)
				(hide yes)
			)
		)
		(property "Value" "VCCA"
			(at 231.14 179.0699 90)
			(effects
				(font
					(size 1.27 1.27)
				)
				(justify left)
			)
		)
		(property "Footprint" ""
			(at 234.95 179.07 0)
			(effects
				(font
					(size 1.27 1.27)
				)
				(hide yes)
			)
		)
		(property "Datasheet" ""
			(at 234.95 179.07 0)
			(effects
				(font
					(size 1.27 1.27)
				)
				(hide yes)
			)
		)
		(property "Description" ""
			(at 234.95 179.07 0)
			(effects
				(font
					(size 1.27 1.27)
				)
				(hide yes)
			)
		)
		(pin "1"
		)
		(instances
			(project "oculink-to-10gbe-adapter"
				(path ""
					(reference "#PWR0310")
					(unit 1)
				)
			)
			(project "thunderbolt-to-10gbe-adapter"
				(path ""
					(reference "#PWR0289")
					(unit 1)
				)
			)
		)
	)
	(symbol
		(lib_id "antmicroInterfaceControllers:EZX710AT2_S_LMR5")
		(at 217.17 90.17 0)
		(unit 8)
		(exclude_from_sim no)
		(in_bom yes)
		(on_board yes)
		(dnp no)
		(fields_autoplaced yes)
		(property "Reference" "U14"
			(at 242.57 82.55 0)
			(effects
				(font
					(size 1.27 1.27)
					(thickness 0.15)
				)
			)
		)
		(property "Value" "EZX710AT2_S_LMR5"
			(at 293.37 95.25 0)
			(effects
				(font
					(size 1.27 1.27)
					(thickness 0.15)
				)
				(justify left bottom)
				(hide yes)
			)
		)
		(property "Footprint" "antmicro-footprints:FCBGA-503_22x22mm_Layout21x24_P1mm"
			(at 293.37 97.79 0)
			(effects
				(font
					(size 1.27 1.27)
					(thickness 0.15)
				)
				(justify left bottom)
				(hide yes)
			)
		)
		(property "Datasheet" "https://www.google.com/url?sa=t&source=web&rct=j&opi=89978449&url=https://cdrdv2-public.intel.com/596333/596333_X710-TM4_Datasheet_v_2_4.pdf&ved=2ahUKEwiSuv20_sCOAxXVCRAIHdxGO_UQFnoECBEQAQ&usg=AOvVaw1CjGyrGWE8ZvOdw4VBsY6U"
			(at 293.37 100.33 0)
			(effects
				(font
					(size 1.27 1.27)
					(thickness 0.15)
				)
				(justify left bottom)
				(hide yes)
			)
		)
		(property "Description" "Ethernet ICs Intel Ethernet Controller 10 Gigabit X7"
			(at 293.37 102.87 0)
			(effects
				(font
					(size 1.27 1.27)
					(thickness 0.15)
				)
				(justify left bottom)
				(hide yes)
			)
		)
		(property "MPN" "EZX710AT2 S LMR5"
			(at 242.57 85.09 0)
			(effects
				(font
					(size 1.27 1.27)
					(thickness 0.15)
				)
			)
		)
		(property "Manufacturer" "Intel"
			(at 293.37 105.41 0)
			(effects
				(font
					(size 1.27 1.27)
					(thickness 0.15)
				)
				(justify left bottom)
				(hide yes)
			)
		)
		(property "Author" "Antmicro"
			(at 293.37 107.95 0)
			(effects
				(font
					(size 1.27 1.27)
					(thickness 0.15)
				)
				(justify left bottom)
				(hide yes)
			)
		)
		(property "License" "Apache-2.0"
			(at 293.37 110.49 0)
			(effects
				(font
					(size 1.27 1.27)
					(thickness 0.15)
				)
				(justify left bottom)
				(hide yes)
			)
		)
		(pin "N3"
		)
		(pin "V38"
		)
		(pin "T38"
		)
		(pin "B38"
		)
		(pin "L31"
		)
		(pin "D6"
		)
		(pin "R27"
		)
		(pin "W41"
		)
		(pin "V42"
		)
		(pin "F14"
		)
		(pin "D22"
		)
		(pin "D8"
		)
		(pin "AD26"
		)
		(pin "L25"
		)
		(pin "B40"
		)
		(pin "B34"
		)
		(pin "G11"
		)
		(pin "H16"
		)
		(pin "P36"
		)
		(pin "L11"
		)
		(pin "L13"
		)
		(pin "G29"
		)
		(pin "G31"
		)
		(pin "C13"
		)
		(pin "C15"
		)
		(pin "J31"
		)
		(pin "J35"
		)
		(pin "V36"
		)
		(pin "P22"
		)
		(pin "AC27"
		)
		(pin "AC29"
		)
		(pin "R29"
		)
		(pin "T32"
		)
		(pin "T36"
		)
		(pin "AD32"
		)
		(pin "G3"
		)
		(pin "K4"
		)
		(pin "Y12"
		)
		(pin "U7"
		)
		(pin "AB10"
		)
		(pin "AD20"
		)
		(pin "M8"
		)
		(pin "A5"
		)
		(pin "A33"
		)
		(pin "AC31"
		)
		(pin "AA27"
		)
		(pin "G5"
		)
		(pin "U33"
		)
		(pin "U31"
		)
		(pin "A17"
		)
		(pin "AD22"
		)
		(pin "A27"
		)
		(pin "V28"
		)
		(pin "AC23"
		)
		(pin "AC25"
		)
		(pin "H12"
		)
		(pin "Y30"
		)
		(pin "W15"
		)
		(pin "W17"
		)
		(pin "J27"
		)
		(pin "J29"
		)
		(pin "P30"
		)
		(pin "R31"
		)
		(pin "K6"
		)
		(pin "E35"
		)
		(pin "E37"
		)
		(pin "U27"
		)
		(pin "F2"
		)
		(pin "J41"
		)
		(pin "A13"
		)
		(pin "H14"
		)
		(pin "J1"
		)
		(pin "G17"
		)
		(pin "K22"
		)
		(pin "R41"
		)
		(pin "F36"
		)
		(pin "K18"
		)
		(pin "K20"
		)
		(pin "R39"
		)
		(pin "M14"
		)
		(pin "M16"
		)
		(pin "D2"
		)
		(pin "R23"
		)
		(pin "V40"
		)
		(pin "L41"
		)
		(pin "F6"
		)
		(pin "M24"
		)
		(pin "P28"
		)
		(pin "J23"
		)
		(pin "J17"
		)
		(pin "U3"
		)
		(pin "L35"
		)
		(pin "G15"
		)
		(pin "AD38"
		)
		(pin "AD42"
		)
		(pin "AB28"
		)
		(pin "AB12"
		)
		(pin "AB24"
		)
		(pin "N29"
		)
		(pin "P32"
		)
		(pin "M40"
		)
		(pin "B28"
		)
		(pin "K40"
		)
		(pin "B36"
		)
		(pin "V8"
		)
		(pin "V10"
		)
		(pin "P26"
		)
		(pin "E39"
		)
		(pin "AB34"
		)
		(pin "AB36"
		)
		(pin "H10"
		)
		(pin "Y16"
		)
		(pin "B30"
		)
		(pin "B6"
		)
		(pin "J37"
		)
		(pin "N9"
		)
		(pin "M2"
		)
		(pin "W7"
		)
		(pin "E15"
		)
		(pin "AB18"
		)
		(pin "C33"
		)
		(pin "C35"
		)
		(pin "Y22"
		)
		(pin "AB42"
		)
		(pin "W3"
		)
		(pin "U1"
		)
		(pin "Y2"
		)
		(pin "F12"
		)
		(pin "P6"
		)
		(pin "E3"
		)
		(pin "L23"
		)
		(pin "M22"
		)
		(pin "V34"
		)
		(pin "G27"
		)
		(pin "H18"
		)
		(pin "A39"
		)
		(pin "B26"
		)
		(pin "E11"
		)
		(pin "J19"
		)
		(pin "L19"
		)
		(pin "L21"
		)
		(pin "H36"
		)
		(pin "H38"
		)
		(pin "H32"
		)
		(pin "H34"
		)
		(pin "K42"
		)
		(pin "G21"
		)
		(pin "AB16"
		)
		(pin "J21"
		)
		(pin "AA17"
		)
		(pin "AA19"
		)
		(pin "M28"
		)
		(pin "P12"
		)
		(pin "P14"
		)
		(pin "P16"
		)
		(pin "P18"
		)
		(pin "P20"
		)
		(pin "R35"
		)
		(pin "D20"
		)
		(pin "C21"
		)
		(pin "T34"
		)
		(pin "U21"
		)
		(pin "M42"
		)
		(pin "V22"
		)
		(pin "AC7"
		)
		(pin "AC9"
		)
		(pin "F30"
		)
		(pin "F32"
		)
		(pin "F34"
		)
		(pin "E9"
		)
		(pin "D12"
		)
		(pin "AD40"
		)
		(pin "E41"
		)
		(pin "A29"
		)
		(pin "A25"
		)
		(pin "F22"
		)
		(pin "D4"
		)
		(pin "W23"
		)
		(pin "U11"
		)
		(pin "U13"
		)
		(pin "R19"
		)
		(pin "R21"
		)
		(pin "AA5"
		)
		(pin "AC5"
		)
		(pin "AD4"
		)
		(pin "AB2"
		)
		(pin "AA1"
		)
		(pin "T28"
		)
		(pin "AB30"
		)
		(pin "AB32"
		)
		(pin "N15"
		)
		(pin "W13"
		)
		(pin "N37"
		)
		(pin "U41"
		)
		(pin "H8"
		)
		(pin "G19"
		)
		(pin "E13"
		)
		(pin "N39"
		)
		(pin "N7"
		)
		(pin "M4"
		)
		(pin "AA31"
		)
		(pin "AD8"
		)
		(pin "B14"
		)
		(pin "E5"
		)
		(pin "V16"
		)
		(pin "V18"
		)
		(pin "M36"
		)
		(pin "U23"
		)
		(pin "Y28"
		)
		(pin "Y32"
		)
		(pin "Y36"
		)
		(pin "F24"
		)
		(pin "F26"
		)
		(pin "F28"
		)
		(pin "L3"
		)
		(pin "H2"
		)
		(pin "M18"
		)
		(pin "M20"
		)
		(pin "P10"
		)
		(pin "U29"
		)
		(pin "N11"
		)
		(pin "N13"
		)
		(pin "Y24"
		)
		(pin "D10"
		)
		(pin "C9"
		)
		(pin "H26"
		)
		(pin "C3"
		)
		(pin "R5"
		)
		(pin "AC15"
		)
		(pin "AC17"
		)
		(pin "K32"
		)
		(pin "V12"
		)
		(pin "V14"
		)
		(pin "K14"
		)
		(pin "K16"
		)
		(pin "F38"
		)
		(pin "D32"
		)
		(pin "AC11"
		)
		(pin "AC13"
		)
		(pin "U15"
		)
		(pin "U17"
		)
		(pin "D18"
		)
		(pin "Y8"
		)
		(pin "A21"
		)
		(pin "A31"
		)
		(pin "AC39"
		)
		(pin "U5"
		)
		(pin "B16"
		)
		(pin "B2"
		)
		(pin "T16"
		)
		(pin "T18"
		)
		(pin "T20"
		)
		(pin "U19"
		)
		(pin "W9"
		)
		(pin "L27"
		)
		(pin "AA21"
		)
		(pin "AA23"
		)
		(pin "E21"
		)
		(pin "E19"
		)
		(pin "M10"
		)
		(pin "M12"
		)
		(pin "P2"
		)
		(pin "R1"
		)
		(pin "T40"
		)
		(pin "U25"
		)
		(pin "R9"
		)
		(pin "N27"
		)
		(pin "W31"
		)
		(pin "W33"
		)
		(pin "V6"
		)
		(pin "N1"
		)
		(pin "J13"
		)
		(pin "P8"
		)
		(pin "B10"
		)
		(pin "N5"
		)
		(pin "B8"
		)
		(pin "C11"
		)
		(pin "Y4"
		)
		(pin "Y40"
		)
		(pin "Y6"
		)
		(pin "M34"
		)
		(pin "A19"
		)
		(pin "A3"
		)
		(pin "T4"
		)
		(pin "C37"
		)
		(pin "C39"
		)
		(pin "T6"
		)
		(pin "F4"
		)
		(pin "P4"
		)
		(pin "L29"
		)
		(pin "M32"
		)
		(pin "W35"
		)
		(pin "W37"
		)
		(pin "R7"
		)
		(pin "K30"
		)
		(pin "M6"
		)
		(pin "P38"
		)
		(pin "G33"
		)
		(pin "G35"
		)
		(pin "J11"
		)
		(pin "T24"
		)
		(pin "B18"
		)
		(pin "B24"
		)
		(pin "U37"
		)
		(pin "Y42"
		)
		(pin "AD12"
		)
		(pin "AD18"
		)
		(pin "G9"
		)
		(pin "R33"
		)
		(pin "E27"
		)
		(pin "E29"
		)
		(pin "AD36"
		)
		(pin "M30"
		)
		(pin "N31"
		)
		(pin "AC19"
		)
		(pin "AC21"
		)
		(pin "V32"
		)
		(pin "V30"
		)
		(pin "N21"
		)
		(pin "R13"
		)
		(pin "Y10"
		)
		(pin "T26"
		)
		(pin "D28"
		)
		(pin "D36"
		)
		(pin "D38"
		)
		(pin "AC37"
		)
		(pin "AC41"
		)
		(pin "K10"
		)
		(pin "K12"
		)
		(pin "K38"
		)
		(pin "K8"
		)
		(pin "AB40"
		)
		(pin "AB6"
		)
		(pin "F20"
		)
		(pin "AA13"
		)
		(pin "AA15"
		)
		(pin "T22"
		)
		(pin "K24"
		)
		(pin "R3"
		)
		(pin "N33"
		)
		(pin "F10"
		)
		(pin "Y34"
		)
		(pin "V26"
		)
		(pin "W5"
		)
		(pin "G7"
		)
		(pin "G13"
		)
		(pin "A11"
		)
		(pin "A15"
		)
		(pin "T30"
		)
		(pin "U35"
		)
		(pin "AD28"
		)
		(pin "C17"
		)
		(pin "C19"
		)
		(pin "N35"
		)
		(pin "H40"
		)
		(pin "AA7"
		)
		(pin "H4"
		)
		(pin "H6"
		)
		(pin "AC35"
		)
		(pin "J33"
		)
		(pin "G39"
		)
		(pin "T8"
		)
		(pin "R11"
		)
		(pin "AA39"
		)
		(pin "F40"
		)
		(pin "F42"
		)
		(pin "G41"
		)
		(pin "P34"
		)
		(pin "N25"
		)
		(pin "U9"
		)
		(pin "A37"
		)
		(pin "C23"
		)
		(pin "C25"
		)
		(pin "L33"
		)
		(pin "AB20"
		)
		(pin "AB26"
		)
		(pin "AD30"
		)
		(pin "AD34"
		)
		(pin "J25"
		)
		(pin "AA37"
		)
		(pin "AA41"
		)
		(pin "AD14"
		)
		(pin "M26"
		)
		(pin "T10"
		)
		(pin "T12"
		)
		(pin "T14"
		)
		(pin "E17"
		)
		(pin "B20"
		)
		(pin "B4"
		)
		(pin "G23"
		)
		(pin "H24"
		)
		(pin "A9"
		)
		(pin "N17"
		)
		(pin "N19"
		)
		(pin "R25"
		)
		(pin "AC3"
		)
		(pin "AC33"
		)
		(pin "P24"
		)
		(pin "L7"
		)
		(pin "F18"
		)
		(pin "V20"
		)
		(pin "W29"
		)
		(pin "A35"
		)
		(pin "U39"
		)
		(pin "W39"
		)
		(pin "Y14"
		)
		(pin "Y26"
		)
		(pin "N41"
		)
		(pin "P40"
		)
		(pin "K2"
		)
		(pin "P42"
		)
		(pin "AB22"
		)
		(pin "W19"
		)
		(pin "W21"
		)
		(pin "J15"
		)
		(pin "F16"
		)
		(pin "L39"
		)
		(pin "M38"
		)
		(pin "V24"
		)
		(pin "L37"
		)
		(pin "D14"
		)
		(pin "C5"
		)
		(pin "C7"
		)
		(pin "AA9"
		)
		(pin "AB14"
		)
		(pin "H42"
		)
		(pin "W25"
		)
		(pin "L5"
		)
		(pin "C41"
		)
		(pin "D24"
		)
		(pin "D26"
		)
		(pin "AA25"
		)
		(pin "AA29"
		)
		(pin "E7"
		)
		(pin "V4"
		)
		(pin "AA35"
		)
		(pin "T42"
		)
		(pin "Y18"
		)
		(pin "A23"
		)
		(pin "R15"
		)
		(pin "R17"
		)
		(pin "H22"
		)
		(pin "J3"
		)
		(pin "E1"
		)
		(pin "N23"
		)
		(pin "G1"
		)
		(pin "F8"
		)
		(pin "Y20"
		)
		(pin "H28"
		)
		(pin "H30"
		)
		(pin "C27"
		)
		(pin "C29"
		)
		(pin "J9"
		)
		(pin "J7"
		)
		(pin "AD10"
		)
		(pin "AD6"
		)
		(pin "B12"
		)
		(pin "W27"
		)
		(pin "H20"
		)
		(pin "W11"
		)
		(pin "L9"
		)
		(pin "D40"
		)
		(pin "E31"
		)
		(pin "E33"
		)
		(pin "AD2"
		)
		(pin "AD24"
		)
		(pin "AB38"
		)
		(pin "AB4"
		)
		(pin "D34"
		)
		(pin "D30"
		)
		(pin "L1"
		)
		(pin "D16"
		)
		(pin "G25"
		)
		(pin "G37"
		)
		(pin "L15"
		)
		(pin "L17"
		)
		(pin "K34"
		)
		(pin "K36"
		)
		(pin "C1"
		)
		(pin "B42"
		)
		(pin "A41"
		)
		(pin "K26"
		)
		(pin "K28"
		)
		(pin "AA3"
		)
		(pin "AA33"
		)
		(pin "A7"
		)
		(pin "AA11"
		)
		(pin "AB8"
		)
		(pin "AC1"
		)
		(pin "E23"
		)
		(pin "E25"
		)
		(pin "Y38"
		)
		(pin "B22"
		)
		(pin "B32"
		)
		(pin "C31"
		)
		(pin "J5"
		)
		(pin "T2"
		)
		(pin "V2"
		)
		(pin "R37"
		)
		(pin "J39"
		)
		(pin "D42"
		)
		(pin "AD16"
		)
		(pin "W1"
		)
		(instances
			(project "OCuLink to 10GbE adapter"
				(path ""
					(reference "U9")
					(unit 8)
				)
			)
			(project "thunderbolt-to-10gbe-adapter"
				(path ""
					(reference "U14")
					(unit 8)
				)
			)
		)
	)
	(symbol
		(lib_id "antmicroCapacitors0402:C_100n_0402")
		(at 74.93 233.68 90)
		(unit 1)
		(exclude_from_sim no)
		(in_bom yes)
		(on_board yes)
		(dnp no)
		(property "Reference" "C159"
			(at 76.962 229.87 90)
			(effects
				(font
					(size 1.27 1.27)
					(thickness 0.15)
				)
				(justify right)
			)
		)
		(property "Value" "C_100n_0402"
			(at 97.79 218.44 0)
			(effects
				(font
					(size 1.27 1.27)
					(thickness 0.15)
				)
				(justify left bottom)
				(hide yes)
			)
		)
		(property "Footprint" "antmicro-footprints:C_0402_1005Metric"
			(at 100.33 218.44 0)
			(effects
				(font
					(size 1.27 1.27)
					(thickness 0.15)
				)
				(justify left bottom)
				(hide yes)
			)
		)
		(property "Datasheet" "https://www.murata.com/products/productdetail?partno=GRM155R61H104KE14%23"
			(at 102.87 218.44 0)
			(effects
				(font
					(size 1.27 1.27)
					(thickness 0.15)
				)
				(justify left bottom)
				(hide yes)
			)
		)
		(property "Description" "SMD Multilayer Ceramic Capacitor, 0.1 µF, 50 V, 0402 [1005 Metric], ± 10%, X5R, GRM Series"
			(at 74.93 233.68 0)
			(effects
				(font
					(size 1.27 1.27)
				)
				(hide yes)
			)
		)
		(property "MPN" "GRM155R61H104KE14D"
			(at 105.41 218.44 0)
			(effects
				(font
					(size 1.27 1.27)
					(thickness 0.15)
				)
				(justify left bottom)
				(hide yes)
			)
		)
		(property "Val" "100n"
			(at 76.962 232.41 90)
			(effects
				(font
					(size 1.27 1.27)
					(thickness 0.15)
				)
				(justify right)
			)
		)
		(property "Voltage" "50V"
			(at 85.09 218.44 0)
			(effects
				(font
					(size 1.27 1.27)
					(thickness 0.15)
				)
				(justify left bottom)
				(hide yes)
			)
		)
		(property "Dielectric" "X5R"
			(at 87.63 218.44 0)
			(effects
				(font
					(size 1.27 1.27)
					(thickness 0.15)
				)
				(justify left bottom)
				(hide yes)
			)
		)
		(property "Manufacturer" "Murata"
			(at 90.17 218.44 0)
			(effects
				(font
					(size 1.27 1.27)
					(thickness 0.15)
				)
				(justify left bottom)
				(hide yes)
			)
		)
		(property "License" "Apache-2.0"
			(at 92.71 218.44 0)
			(effects
				(font
					(size 1.27 1.27)
					(thickness 0.15)
				)
				(justify left bottom)
				(hide yes)
			)
		)
		(property "Author" "Antmicro"
			(at 95.25 218.44 0)
			(effects
				(font
					(size 1.27 1.27)
					(thickness 0.15)
				)
				(justify left bottom)
				(hide yes)
			)
		)
		(pin "2"
		)
		(pin "1"
		)
		(instances
			(project "OCuLink to 10GbE adapter"
				(path ""
					(reference "C185")
					(unit 1)
				)
			)
			(project "thunderbolt-to-10gbe-adapter"
				(path ""
					(reference "C159")
					(unit 1)
				)
			)
		)
	)
	(symbol
		(lib_id "antmicroCapacitors0603:C_22u_16V_0603")
		(at 388.62 130.81 90)
		(unit 1)
		(exclude_from_sim no)
		(in_bom yes)
		(on_board yes)
		(dnp no)
		(fields_autoplaced yes)
		(property "Reference" "C262"
			(at 391.16 126.9936 90)
			(effects
				(font
					(size 1.27 1.27)
					(thickness 0.15)
				)
				(justify right)
			)
		)
		(property "Value" "C_22u_16V_0603"
			(at 398.78 110.49 0)
			(effects
				(font
					(size 1.27 1.27)
					(thickness 0.15)
				)
				(justify left bottom)
				(hide yes)
			)
		)
		(property "Footprint" "antmicro-footprints:C_0603_1608Metric_EIA"
			(at 401.32 110.49 0)
			(effects
				(font
					(size 1.27 1.27)
					(thickness 0.15)
				)
				(justify left bottom)
				(hide yes)
			)
		)
		(property "Datasheet" "https://product.samsungsem.com/mlcc/CL10A226MO7JZN.do"
			(at 403.86 110.49 0)
			(effects
				(font
					(size 1.27 1.27)
					(thickness 0.15)
				)
				(justify left bottom)
				(hide yes)
			)
		)
		(property "Description" "SMD Multilayer Ceramic Capacitor"
			(at 388.62 130.81 0)
			(effects
				(font
					(size 1.27 1.27)
				)
				(hide yes)
			)
		)
		(property "MPN" "CL10A226MO7JZNC"
			(at 406.4 110.49 0)
			(effects
				(font
					(size 1.27 1.27)
					(thickness 0.15)
				)
				(justify left bottom)
				(hide yes)
			)
		)
		(property "Manufacturer" "Samsung Electro-Mechanics"
			(at 408.94 110.49 0)
			(effects
				(font
					(size 1.27 1.27)
					(thickness 0.15)
				)
				(justify left bottom)
				(hide yes)
			)
		)
		(property "License" "Apache-2.0"
			(at 411.48 110.49 0)
			(effects
				(font
					(size 1.27 1.27)
					(thickness 0.15)
				)
				(justify left bottom)
				(hide yes)
			)
		)
		(property "Author" "Antmicro"
			(at 414.02 110.49 0)
			(effects
				(font
					(size 1.27 1.27)
					(thickness 0.15)
				)
				(justify left bottom)
				(hide yes)
			)
		)
		(property "Val" "22u"
			(at 391.16 129.5336 90)
			(effects
				(font
					(size 1.27 1.27)
					(thickness 0.15)
				)
				(justify right)
			)
		)
		(property "Voltage" "16V"
			(at 416.56 110.49 0)
			(effects
				(font
					(size 1.27 1.27)
				)
				(justify left bottom)
				(hide yes)
			)
		)
		(property "Dielectric" ""
			(at 419.1 110.49 0)
			(effects
				(font
					(size 1.27 1.27)
				)
				(justify left bottom)
				(hide yes)
			)
		)
		(pin "1"
		)
		(pin "2"
		)
		(instances
			(project "OCuLink to 10GbE adapter"
				(path ""
					(reference "C155")
					(unit 1)
				)
			)
			(project "thunderbolt-to-10gbe-adapter"
				(path ""
					(reference "C262")
					(unit 1)
				)
			)
		)
	)
	(symbol
		(lib_id "antmicropower:PWR_FLAG")
		(at 101.6 171.45 0)
		(unit 1)
		(exclude_from_sim no)
		(in_bom yes)
		(on_board yes)
		(dnp no)
		(fields_autoplaced yes)
		(property "Reference" "#FLG026"
			(at 101.6 169.545 0)
			(effects
				(font
					(size 1.27 1.27)
				)
				(hide yes)
			)
		)
		(property "Value" "PWR_FLAG"
			(at 101.6 166.37 0)
			(effects
				(font
					(size 1.27 1.27)
				)
			)
		)
		(property "Footprint" ""
			(at 101.6 171.45 0)
			(effects
				(font
					(size 1.27 1.27)
				)
				(hide yes)
			)
		)
		(property "Datasheet" ""
			(at 101.6 171.45 0)
			(effects
				(font
					(size 1.27 1.27)
				)
				(hide yes)
			)
		)
		(property "Description" ""
			(at 101.6 173.99 0)
			(effects
				(font
					(size 1.27 1.27)
				)
				(justify left bottom)
				(hide yes)
			)
		)
		(pin "1"
		)
		(instances
			(project "OCuLink to 10GbE adapter"
				(path ""
					(reference "#FLG016")
					(unit 1)
				)
			)
			(project "thunderbolt-to-10gbe-adapter"
				(path ""
					(reference "#FLG026")
					(unit 1)
				)
			)
		)
	)
	(symbol
		(lib_id "antmicroCapacitors0402:C_1u_25V_0402")
		(at 388.62 52.07 90)
		(unit 1)
		(exclude_from_sim no)
		(in_bom yes)
		(on_board yes)
		(dnp no)
		(property "Reference" "C259"
			(at 390.652 48.26 90)
			(effects
				(font
					(size 1.27 1.27)
					(thickness 0.15)
				)
				(justify right)
			)
		)
		(property "Value" "C_1u_25V_0402"
			(at 398.78 31.75 0)
			(effects
				(font
					(size 1.27 1.27)
					(thickness 0.15)
				)
				(justify left bottom)
				(hide yes)
			)
		)
		(property "Footprint" "antmicro-footprints:C_0402_1005Metric"
			(at 401.32 31.75 0)
			(effects
				(font
					(size 1.27 1.27)
					(thickness 0.15)
				)
				(justify left bottom)
				(hide yes)
			)
		)
		(property "Datasheet" "https://www.murata.com/products/productdetail?partno=GRM155R61E105KE11%23"
			(at 403.86 31.75 0)
			(effects
				(font
					(size 1.27 1.27)
					(thickness 0.15)
				)
				(justify left bottom)
				(hide yes)
			)
		)
		(property "Description" "SMD Multilayer Ceramic Capacitor, 1 µF, 25 V, 0402 [1005 Metric], ± 10%, X5R, GRM Series"
			(at 388.62 52.07 0)
			(effects
				(font
					(size 1.27 1.27)
				)
				(hide yes)
			)
		)
		(property "MPN" "GRM155R61E105KE11J"
			(at 406.4 31.75 0)
			(effects
				(font
					(size 1.27 1.27)
					(thickness 0.15)
				)
				(justify left bottom)
				(hide yes)
			)
		)
		(property "Manufacturer" "Murata"
			(at 408.94 31.75 0)
			(effects
				(font
					(size 1.27 1.27)
					(thickness 0.15)
				)
				(justify left bottom)
				(hide yes)
			)
		)
		(property "License" "Apache-2.0"
			(at 411.48 31.75 0)
			(effects
				(font
					(size 1.27 1.27)
					(thickness 0.15)
				)
				(justify left bottom)
				(hide yes)
			)
		)
		(property "Author" "Antmicro"
			(at 414.02 31.75 0)
			(effects
				(font
					(size 1.27 1.27)
					(thickness 0.15)
				)
				(justify left bottom)
				(hide yes)
			)
		)
		(property "Val" "1u"
			(at 390.652 50.8 90)
			(effects
				(font
					(size 1.27 1.27)
					(thickness 0.15)
				)
				(justify right)
			)
		)
		(property "Voltage" "25V"
			(at 416.56 31.75 0)
			(effects
				(font
					(size 1.27 1.27)
				)
				(justify left bottom)
				(hide yes)
			)
		)
		(property "Dielectric" "X5R"
			(at 419.1 31.75 0)
			(effects
				(font
					(size 1.27 1.27)
				)
				(justify left bottom)
				(hide yes)
			)
		)
		(pin "2"
		)
		(pin "1"
		)
		(instances
			(project "OCuLink to 10GbE adapter"
				(path ""
					(reference "C97")
					(unit 1)
				)
			)
			(project "thunderbolt-to-10gbe-adapter"
				(path ""
					(reference "C259")
					(unit 1)
				)
			)
		)
	)
	(symbol
		(lib_id "antmicropower:GND")
		(at 90.17 236.22 0)
		(unit 1)
		(exclude_from_sim no)
		(in_bom yes)
		(on_board yes)
		(dnp no)
		(property "Reference" "#PWR0244"
			(at 99.06 238.76 0)
			(effects
				(font
					(size 1.27 1.27)
					(thickness 0.15)
				)
				(justify left bottom)
				(hide yes)
			)
		)
		(property "Value" "GND"
			(at 90.17 240.03 0)
			(effects
				(font
					(size 1.27 1.27)
					(thickness 0.15)
				)
			)
		)
		(property "Footprint" ""
			(at 99.06 243.84 0)
			(effects
				(font
					(size 1.27 1.27)
					(thickness 0.15)
				)
				(justify left bottom)
				(hide yes)
			)
		)
		(property "Datasheet" ""
			(at 99.06 248.92 0)
			(effects
				(font
					(size 1.27 1.27)
					(thickness 0.15)
				)
				(justify left bottom)
				(hide yes)
			)
		)
		(property "Description" ""
			(at 90.17 236.22 0)
			(effects
				(font
					(size 1.27 1.27)
				)
				(hide yes)
			)
		)
		(property "Author" "Antmicro"
			(at 99.06 243.84 0)
			(effects
				(font
					(size 1.27 1.27)
					(thickness 0.15)
				)
				(justify left bottom)
				(hide yes)
			)
		)
		(property "License" "Apache-2.0"
			(at 99.06 246.38 0)
			(effects
				(font
					(size 1.27 1.27)
					(thickness 0.15)
				)
				(justify left bottom)
				(hide yes)
			)
		)
		(pin "1"
		)
		(instances
			(project "OCuLink to 10GbE adapter"
				(path ""
					(reference "#PWR0240")
					(unit 1)
				)
			)
			(project "thunderbolt-to-10gbe-adapter"
				(path ""
					(reference "#PWR0244")
					(unit 1)
				)
			)
		)
	)
	(symbol
		(lib_id "antmicropower:GND")
		(at 326.39 54.61 0)
		(unit 1)
		(exclude_from_sim no)
		(in_bom yes)
		(on_board yes)
		(dnp no)
		(property "Reference" "#PWR0313"
			(at 335.28 57.15 0)
			(effects
				(font
					(size 1.27 1.27)
					(thickness 0.15)
				)
				(justify left bottom)
				(hide yes)
			)
		)
		(property "Value" "GND"
			(at 326.39 58.42 0)
			(effects
				(font
					(size 1.27 1.27)
					(thickness 0.15)
				)
			)
		)
		(property "Footprint" ""
			(at 335.28 62.23 0)
			(effects
				(font
					(size 1.27 1.27)
					(thickness 0.15)
				)
				(justify left bottom)
				(hide yes)
			)
		)
		(property "Datasheet" ""
			(at 335.28 67.31 0)
			(effects
				(font
					(size 1.27 1.27)
					(thickness 0.15)
				)
				(justify left bottom)
				(hide yes)
			)
		)
		(property "Description" ""
			(at 326.39 54.61 0)
			(effects
				(font
					(size 1.27 1.27)
				)
				(hide yes)
			)
		)
		(property "Author" "Antmicro"
			(at 335.28 62.23 0)
			(effects
				(font
					(size 1.27 1.27)
					(thickness 0.15)
				)
				(justify left bottom)
				(hide yes)
			)
		)
		(property "License" "Apache-2.0"
			(at 335.28 64.77 0)
			(effects
				(font
					(size 1.27 1.27)
					(thickness 0.15)
				)
				(justify left bottom)
				(hide yes)
			)
		)
		(pin "1"
		)
		(instances
			(project "OCuLink to 10GbE adapter"
				(path ""
					(reference "#PWR0124")
					(unit 1)
				)
			)
			(project "thunderbolt-to-10gbe-adapter"
				(path ""
					(reference "#PWR0313")
					(unit 1)
				)
			)
		)
	)
	(symbol
		(lib_id "antmicropower:GND")
		(at 142.24 76.2 0)
		(unit 1)
		(exclude_from_sim no)
		(in_bom yes)
		(on_board yes)
		(dnp no)
		(property "Reference" "#PWR0268"
			(at 151.13 78.74 0)
			(effects
				(font
					(size 1.27 1.27)
					(thickness 0.15)
				)
				(justify left bottom)
				(hide yes)
			)
		)
		(property "Value" "GND"
			(at 142.24 80.01 0)
			(effects
				(font
					(size 1.27 1.27)
					(thickness 0.15)
				)
			)
		)
		(property "Footprint" ""
			(at 151.13 83.82 0)
			(effects
				(font
					(size 1.27 1.27)
					(thickness 0.15)
				)
				(justify left bottom)
				(hide yes)
			)
		)
		(property "Datasheet" ""
			(at 151.13 88.9 0)
			(effects
				(font
					(size 1.27 1.27)
					(thickness 0.15)
				)
				(justify left bottom)
				(hide yes)
			)
		)
		(property "Description" ""
			(at 142.24 76.2 0)
			(effects
				(font
					(size 1.27 1.27)
				)
				(hide yes)
			)
		)
		(property "Author" "Antmicro"
			(at 151.13 83.82 0)
			(effects
				(font
					(size 1.27 1.27)
					(thickness 0.15)
				)
				(justify left bottom)
				(hide yes)
			)
		)
		(property "License" "Apache-2.0"
			(at 151.13 86.36 0)
			(effects
				(font
					(size 1.27 1.27)
					(thickness 0.15)
				)
				(justify left bottom)
				(hide yes)
			)
		)
		(pin "1"
		)
		(instances
			(project "OCuLink to 10GbE adapter"
				(path ""
					(reference "#PWR0137")
					(unit 1)
				)
			)
			(project "thunderbolt-to-10gbe-adapter"
				(path ""
					(reference "#PWR0268")
					(unit 1)
				)
			)
		)
	)
	(symbol
		(lib_id "antmicropower:PWR_FLAG")
		(at 101.6 118.11 0)
		(unit 1)
		(exclude_from_sim no)
		(in_bom yes)
		(on_board yes)
		(dnp no)
		(fields_autoplaced yes)
		(property "Reference" "#FLG024"
			(at 101.6 116.205 0)
			(effects
				(font
					(size 1.27 1.27)
				)
				(hide yes)
			)
		)
		(property "Value" "PWR_FLAG"
			(at 101.6 113.03 0)
			(effects
				(font
					(size 1.27 1.27)
				)
			)
		)
		(property "Footprint" ""
			(at 101.6 118.11 0)
			(effects
				(font
					(size 1.27 1.27)
				)
				(hide yes)
			)
		)
		(property "Datasheet" ""
			(at 101.6 118.11 0)
			(effects
				(font
					(size 1.27 1.27)
				)
				(hide yes)
			)
		)
		(property "Description" ""
			(at 101.6 120.65 0)
			(effects
				(font
					(size 1.27 1.27)
				)
				(justify left bottom)
				(hide yes)
			)
		)
		(pin "1"
		)
		(instances
			(project "OCuLink to 10GbE adapter"
				(path ""
					(reference "#FLG013")
					(unit 1)
				)
			)
			(project "thunderbolt-to-10gbe-adapter"
				(path ""
					(reference "#FLG024")
					(unit 1)
				)
			)
		)
	)
	(symbol
		(lib_id "antmicropower:GND")
		(at 299.72 54.61 0)
		(unit 1)
		(exclude_from_sim no)
		(in_bom yes)
		(on_board yes)
		(dnp no)
		(property "Reference" "#PWR0297"
			(at 308.61 57.15 0)
			(effects
				(font
					(size 1.27 1.27)
					(thickness 0.15)
				)
				(justify left bottom)
				(hide yes)
			)
		)
		(property "Value" "GND"
			(at 299.72 58.42 0)
			(effects
				(font
					(size 1.27 1.27)
					(thickness 0.15)
				)
			)
		)
		(property "Footprint" ""
			(at 308.61 62.23 0)
			(effects
				(font
					(size 1.27 1.27)
					(thickness 0.15)
				)
				(justify left bottom)
				(hide yes)
			)
		)
		(property "Datasheet" ""
			(at 308.61 67.31 0)
			(effects
				(font
					(size 1.27 1.27)
					(thickness 0.15)
				)
				(justify left bottom)
				(hide yes)
			)
		)
		(property "Description" ""
			(at 299.72 54.61 0)
			(effects
				(font
					(size 1.27 1.27)
				)
				(hide yes)
			)
		)
		(property "Author" "Antmicro"
			(at 308.61 62.23 0)
			(effects
				(font
					(size 1.27 1.27)
					(thickness 0.15)
				)
				(justify left bottom)
				(hide yes)
			)
		)
		(property "License" "Apache-2.0"
			(at 308.61 64.77 0)
			(effects
				(font
					(size 1.27 1.27)
					(thickness 0.15)
				)
				(justify left bottom)
				(hide yes)
			)
		)
		(pin "1"
		)
		(instances
			(project "OCuLink to 10GbE adapter"
				(path ""
					(reference "#PWR0121")
					(unit 1)
				)
			)
			(project "thunderbolt-to-10gbe-adapter"
				(path ""
					(reference "#PWR0297")
					(unit 1)
				)
			)
		)
	)
	(symbol
		(lib_id "antmicropower:GND")
		(at 309.88 152.4 0)
		(unit 1)
		(exclude_from_sim no)
		(in_bom yes)
		(on_board yes)
		(dnp no)
		(property "Reference" "#PWR0307"
			(at 318.77 154.94 0)
			(effects
				(font
					(size 1.27 1.27)
					(thickness 0.15)
				)
				(justify left bottom)
				(hide yes)
			)
		)
		(property "Value" "GND"
			(at 309.88 156.21 0)
			(effects
				(font
					(size 1.27 1.27)
					(thickness 0.15)
				)
			)
		)
		(property "Footprint" ""
			(at 318.77 160.02 0)
			(effects
				(font
					(size 1.27 1.27)
					(thickness 0.15)
				)
				(justify left bottom)
				(hide yes)
			)
		)
		(property "Datasheet" ""
			(at 318.77 165.1 0)
			(effects
				(font
					(size 1.27 1.27)
					(thickness 0.15)
				)
				(justify left bottom)
				(hide yes)
			)
		)
		(property "Description" ""
			(at 309.88 152.4 0)
			(effects
				(font
					(size 1.27 1.27)
				)
				(hide yes)
			)
		)
		(property "Author" "Antmicro"
			(at 318.77 160.02 0)
			(effects
				(font
					(size 1.27 1.27)
					(thickness 0.15)
				)
				(justify left bottom)
				(hide yes)
			)
		)
		(property "License" "Apache-2.0"
			(at 318.77 162.56 0)
			(effects
				(font
					(size 1.27 1.27)
					(thickness 0.15)
				)
				(justify left bottom)
				(hide yes)
			)
		)
		(pin "1"
		)
		(instances
			(project "OCuLink to 10GbE adapter"
				(path ""
					(reference "#PWR0210")
					(unit 1)
				)
			)
			(project "thunderbolt-to-10gbe-adapter"
				(path ""
					(reference "#PWR0307")
					(unit 1)
				)
			)
		)
	)
	(symbol
		(lib_id "antmicropower:GND")
		(at 361.95 115.57 0)
		(unit 1)
		(exclude_from_sim no)
		(in_bom yes)
		(on_board yes)
		(dnp no)
		(property "Reference" "#PWR0334"
			(at 370.84 118.11 0)
			(effects
				(font
					(size 1.27 1.27)
					(thickness 0.15)
				)
				(justify left bottom)
				(hide yes)
			)
		)
		(property "Value" "GND"
			(at 361.95 119.38 0)
			(effects
				(font
					(size 1.27 1.27)
					(thickness 0.15)
				)
			)
		)
		(property "Footprint" ""
			(at 370.84 123.19 0)
			(effects
				(font
					(size 1.27 1.27)
					(thickness 0.15)
				)
				(justify left bottom)
				(hide yes)
			)
		)
		(property "Datasheet" ""
			(at 370.84 128.27 0)
			(effects
				(font
					(size 1.27 1.27)
					(thickness 0.15)
				)
				(justify left bottom)
				(hide yes)
			)
		)
		(property "Description" ""
			(at 361.95 115.57 0)
			(effects
				(font
					(size 1.27 1.27)
				)
				(hide yes)
			)
		)
		(property "Author" "Antmicro"
			(at 370.84 123.19 0)
			(effects
				(font
					(size 1.27 1.27)
					(thickness 0.15)
				)
				(justify left bottom)
				(hide yes)
			)
		)
		(property "License" "Apache-2.0"
			(at 370.84 125.73 0)
			(effects
				(font
					(size 1.27 1.27)
					(thickness 0.15)
				)
				(justify left bottom)
				(hide yes)
			)
		)
		(pin "1"
		)
		(instances
			(project "OCuLink to 10GbE adapter"
				(path ""
					(reference "#PWR0184")
					(unit 1)
				)
			)
			(project "thunderbolt-to-10gbe-adapter"
				(path ""
					(reference "#PWR0334")
					(unit 1)
				)
			)
		)
	)
	(symbol
		(lib_id "antmicroCapacitors0603:C_10u_10V_X7R_0603")
		(at 300.99 149.86 270)
		(mirror x)
		(unit 1)
		(exclude_from_sim no)
		(in_bom yes)
		(on_board yes)
		(dnp no)
		(property "Reference" "C216"
			(at 298.958 146.05 90)
			(effects
				(font
					(size 1.27 1.27)
					(thickness 0.15)
				)
				(justify right)
			)
		)
		(property "Value" "C_10u_10V_X7R_0603"
			(at 290.83 134.62 0)
			(effects
				(font
					(size 1.27 1.27)
					(thickness 0.15)
				)
				(justify left bottom)
				(hide yes)
			)
		)
		(property "Footprint" "antmicro-footprints:C_0603_1608Metric"
			(at 288.29 134.62 0)
			(effects
				(font
					(size 1.27 1.27)
					(thickness 0.15)
				)
				(justify left bottom)
				(hide yes)
			)
		)
		(property "Datasheet" "https://www.murata.com/products/productdetail?partno=GRM188Z71A106KA73%23"
			(at 285.75 134.62 0)
			(effects
				(font
					(size 1.27 1.27)
					(thickness 0.15)
				)
				(justify left bottom)
				(hide yes)
			)
		)
		(property "Description" "SMD Multilayer Ceramic Capacitor,  10µF, 10V, 0603, ±10%, X7R"
			(at 300.99 149.86 0)
			(effects
				(font
					(size 1.27 1.27)
				)
				(hide yes)
			)
		)
		(property "MPN" "GRM188Z71A106KA73D"
			(at 283.21 134.62 0)
			(effects
				(font
					(size 1.27 1.27)
					(thickness 0.15)
				)
				(justify left bottom)
				(hide yes)
			)
		)
		(property "Val" "10u"
			(at 298.958 148.59 90)
			(effects
				(font
					(size 1.27 1.27)
					(thickness 0.15)
				)
				(justify right)
			)
		)
		(property "Voltage" "10V"
			(at 280.67 134.62 0)
			(effects
				(font
					(size 1.27 1.27)
					(thickness 0.15)
				)
				(justify left bottom)
				(hide yes)
			)
		)
		(property "Dielectric" "X7R"
			(at 278.13 134.62 0)
			(effects
				(font
					(size 1.27 1.27)
					(thickness 0.15)
				)
				(justify left bottom)
				(hide yes)
			)
		)
		(property "Manufacturer" "Murata"
			(at 275.59 134.62 0)
			(effects
				(font
					(size 1.27 1.27)
					(thickness 0.15)
				)
				(justify left bottom)
				(hide yes)
			)
		)
		(property "License" "Apache-2.0"
			(at 273.05 134.62 0)
			(effects
				(font
					(size 1.27 1.27)
					(thickness 0.15)
				)
				(justify left bottom)
				(hide yes)
			)
		)
		(property "Author" "Antmicro"
			(at 270.51 134.62 0)
			(effects
				(font
					(size 1.27 1.27)
					(thickness 0.15)
				)
				(justify left bottom)
				(hide yes)
			)
		)
		(pin "1"
		)
		(pin "2"
		)
		(instances
			(project "OCuLink to 10GbE adapter"
				(path ""
					(reference "C159")
					(unit 1)
				)
			)
			(project "thunderbolt-to-10gbe-adapter"
				(path ""
					(reference "C216")
					(unit 1)
				)
			)
		)
	)
	(symbol
		(lib_id "antmicroCapacitors0402:C_1u_25V_0402")
		(at 353.06 52.07 90)
		(unit 1)
		(exclude_from_sim no)
		(in_bom yes)
		(on_board yes)
		(dnp no)
		(property "Reference" "C240"
			(at 355.092 48.26 90)
			(effects
				(font
					(size 1.27 1.27)
					(thickness 0.15)
				)
				(justify right)
			)
		)
		(property "Value" "C_1u_25V_0402"
			(at 363.22 31.75 0)
			(effects
				(font
					(size 1.27 1.27)
					(thickness 0.15)
				)
				(justify left bottom)
				(hide yes)
			)
		)
		(property "Footprint" "antmicro-footprints:C_0402_1005Metric"
			(at 365.76 31.75 0)
			(effects
				(font
					(size 1.27 1.27)
					(thickness 0.15)
				)
				(justify left bottom)
				(hide yes)
			)
		)
		(property "Datasheet" "https://www.murata.com/products/productdetail?partno=GRM155R61E105KE11%23"
			(at 368.3 31.75 0)
			(effects
				(font
					(size 1.27 1.27)
					(thickness 0.15)
				)
				(justify left bottom)
				(hide yes)
			)
		)
		(property "Description" "SMD Multilayer Ceramic Capacitor, 1 µF, 25 V, 0402 [1005 Metric], ± 10%, X5R, GRM Series"
			(at 353.06 52.07 0)
			(effects
				(font
					(size 1.27 1.27)
				)
				(hide yes)
			)
		)
		(property "MPN" "GRM155R61E105KE11J"
			(at 370.84 31.75 0)
			(effects
				(font
					(size 1.27 1.27)
					(thickness 0.15)
				)
				(justify left bottom)
				(hide yes)
			)
		)
		(property "Manufacturer" "Murata"
			(at 373.38 31.75 0)
			(effects
				(font
					(size 1.27 1.27)
					(thickness 0.15)
				)
				(justify left bottom)
				(hide yes)
			)
		)
		(property "License" "Apache-2.0"
			(at 375.92 31.75 0)
			(effects
				(font
					(size 1.27 1.27)
					(thickness 0.15)
				)
				(justify left bottom)
				(hide yes)
			)
		)
		(property "Author" "Antmicro"
			(at 378.46 31.75 0)
			(effects
				(font
					(size 1.27 1.27)
					(thickness 0.15)
				)
				(justify left bottom)
				(hide yes)
			)
		)
		(property "Val" "1u"
			(at 355.092 50.8 90)
			(effects
				(font
					(size 1.27 1.27)
					(thickness 0.15)
				)
				(justify right)
			)
		)
		(property "Voltage" "25V"
			(at 381 31.75 0)
			(effects
				(font
					(size 1.27 1.27)
				)
				(justify left bottom)
				(hide yes)
			)
		)
		(property "Dielectric" "X5R"
			(at 383.54 31.75 0)
			(effects
				(font
					(size 1.27 1.27)
				)
				(justify left bottom)
				(hide yes)
			)
		)
		(pin "2"
		)
		(pin "1"
		)
		(instances
			(project "OCuLink to 10GbE adapter"
				(path ""
					(reference "C93")
					(unit 1)
				)
			)
			(project "thunderbolt-to-10gbe-adapter"
				(path ""
					(reference "C240")
					(unit 1)
				)
			)
		)
	)
	(symbol
		(lib_id "antmicroCapacitors0402:C_1u_25V_0402")
		(at 115.57 52.07 90)
		(unit 1)
		(exclude_from_sim no)
		(in_bom yes)
		(on_board yes)
		(dnp no)
		(property "Reference" "C182"
			(at 117.602 48.26 90)
			(effects
				(font
					(size 1.27 1.27)
					(thickness 0.15)
				)
				(justify right)
			)
		)
		(property "Value" "C_1u_25V_0402"
			(at 125.73 31.75 0)
			(effects
				(font
					(size 1.27 1.27)
					(thickness 0.15)
				)
				(justify left bottom)
				(hide yes)
			)
		)
		(property "Footprint" "antmicro-footprints:C_0402_1005Metric"
			(at 128.27 31.75 0)
			(effects
				(font
					(size 1.27 1.27)
					(thickness 0.15)
				)
				(justify left bottom)
				(hide yes)
			)
		)
		(property "Datasheet" "https://www.murata.com/products/productdetail?partno=GRM155R61E105KE11%23"
			(at 130.81 31.75 0)
			(effects
				(font
					(size 1.27 1.27)
					(thickness 0.15)
				)
				(justify left bottom)
				(hide yes)
			)
		)
		(property "Description" "SMD Multilayer Ceramic Capacitor, 1 µF, 25 V, 0402 [1005 Metric], ± 10%, X5R, GRM Series"
			(at 115.57 52.07 0)
			(effects
				(font
					(size 1.27 1.27)
				)
				(hide yes)
			)
		)
		(property "MPN" "GRM155R61E105KE11J"
			(at 133.35 31.75 0)
			(effects
				(font
					(size 1.27 1.27)
					(thickness 0.15)
				)
				(justify left bottom)
				(hide yes)
			)
		)
		(property "Manufacturer" "Murata"
			(at 135.89 31.75 0)
			(effects
				(font
					(size 1.27 1.27)
					(thickness 0.15)
				)
				(justify left bottom)
				(hide yes)
			)
		)
		(property "License" "Apache-2.0"
			(at 138.43 31.75 0)
			(effects
				(font
					(size 1.27 1.27)
					(thickness 0.15)
				)
				(justify left bottom)
				(hide yes)
			)
		)
		(property "Author" "Antmicro"
			(at 140.97 31.75 0)
			(effects
				(font
					(size 1.27 1.27)
					(thickness 0.15)
				)
				(justify left bottom)
				(hide yes)
			)
		)
		(property "Val" "1u"
			(at 117.602 50.8 90)
			(effects
				(font
					(size 1.27 1.27)
					(thickness 0.15)
				)
				(justify right)
			)
		)
		(property "Voltage" "25V"
			(at 143.51 31.75 0)
			(effects
				(font
					(size 1.27 1.27)
				)
				(justify left bottom)
				(hide yes)
			)
		)
		(property "Dielectric" "X5R"
			(at 146.05 31.75 0)
			(effects
				(font
					(size 1.27 1.27)
				)
				(justify left bottom)
				(hide yes)
			)
		)
		(pin "2"
		)
		(pin "1"
		)
		(instances
			(project "OCuLink to 10GbE adapter"
				(path ""
					(reference "C82")
					(unit 1)
				)
			)
			(project "thunderbolt-to-10gbe-adapter"
				(path ""
					(reference "C182")
					(unit 1)
				)
			)
		)
	)
	(symbol
		(lib_id "antmicropower:GND")
		(at 142.24 209.55 0)
		(unit 1)
		(exclude_from_sim no)
		(in_bom yes)
		(on_board yes)
		(dnp no)
		(property "Reference" "#PWR0272"
			(at 151.13 212.09 0)
			(effects
				(font
					(size 1.27 1.27)
					(thickness 0.15)
				)
				(justify left bottom)
				(hide yes)
			)
		)
		(property "Value" "GND"
			(at 142.24 213.36 0)
			(effects
				(font
					(size 1.27 1.27)
					(thickness 0.15)
				)
			)
		)
		(property "Footprint" ""
			(at 151.13 217.17 0)
			(effects
				(font
					(size 1.27 1.27)
					(thickness 0.15)
				)
				(justify left bottom)
				(hide yes)
			)
		)
		(property "Datasheet" ""
			(at 151.13 222.25 0)
			(effects
				(font
					(size 1.27 1.27)
					(thickness 0.15)
				)
				(justify left bottom)
				(hide yes)
			)
		)
		(property "Description" ""
			(at 142.24 209.55 0)
			(effects
				(font
					(size 1.27 1.27)
				)
				(hide yes)
			)
		)
		(property "Author" "Antmicro"
			(at 151.13 217.17 0)
			(effects
				(font
					(size 1.27 1.27)
					(thickness 0.15)
				)
				(justify left bottom)
				(hide yes)
			)
		)
		(property "License" "Apache-2.0"
			(at 151.13 219.71 0)
			(effects
				(font
					(size 1.27 1.27)
					(thickness 0.15)
				)
				(justify left bottom)
				(hide yes)
			)
		)
		(pin "1"
		)
		(instances
			(project "OCuLink to 10GbE adapter"
				(path ""
					(reference "#PWR0236")
					(unit 1)
				)
			)
			(project "thunderbolt-to-10gbe-adapter"
				(path ""
					(reference "#PWR0272")
					(unit 1)
				)
			)
		)
	)
	(symbol
		(lib_id "antmicropower:VCC")
		(at 283.21 115.57 0)
		(unit 1)
		(exclude_from_sim no)
		(in_bom yes)
		(on_board yes)
		(dnp no)
		(property "Reference" "#PWR0294"
			(at 283.21 119.38 0)
			(effects
				(font
					(size 1.27 1.27)
				)
				(hide yes)
			)
		)
		(property "Value" "VCCA"
			(at 283.21 111.76 0)
			(effects
				(font
					(size 1.27 1.27)
				)
			)
		)
		(property "Footprint" ""
			(at 283.21 115.57 0)
			(effects
				(font
					(size 1.27 1.27)
				)
				(hide yes)
			)
		)
		(property "Datasheet" ""
			(at 283.21 115.57 0)
			(effects
				(font
					(size 1.27 1.27)
				)
				(hide yes)
			)
		)
		(property "Description" ""
			(at 283.21 115.57 0)
			(effects
				(font
					(size 1.27 1.27)
				)
				(hide yes)
			)
		)
		(pin "1"
		)
		(instances
			(project "OCuLink to 10GbE adapter"
				(path ""
					(reference "#PWR0177")
					(unit 1)
				)
			)
			(project "thunderbolt-to-10gbe-adapter"
				(path ""
					(reference "#PWR0294")
					(unit 1)
				)
			)
		)
	)
	(symbol
		(lib_id "antmicropower:GND")
		(at 106.68 182.88 0)
		(unit 1)
		(exclude_from_sim no)
		(in_bom yes)
		(on_board yes)
		(dnp no)
		(property "Reference" "#PWR0252"
			(at 115.57 185.42 0)
			(effects
				(font
					(size 1.27 1.27)
					(thickness 0.15)
				)
				(justify left bottom)
				(hide yes)
			)
		)
		(property "Value" "GND"
			(at 106.68 186.69 0)
			(effects
				(font
					(size 1.27 1.27)
					(thickness 0.15)
				)
			)
		)
		(property "Footprint" ""
			(at 115.57 190.5 0)
			(effects
				(font
					(size 1.27 1.27)
					(thickness 0.15)
				)
				(justify left bottom)
				(hide yes)
			)
		)
		(property "Datasheet" ""
			(at 115.57 195.58 0)
			(effects
				(font
					(size 1.27 1.27)
					(thickness 0.15)
				)
				(justify left bottom)
				(hide yes)
			)
		)
		(property "Description" ""
			(at 106.68 182.88 0)
			(effects
				(font
					(size 1.27 1.27)
				)
				(hide yes)
			)
		)
		(property "Author" "Antmicro"
			(at 115.57 190.5 0)
			(effects
				(font
					(size 1.27 1.27)
					(thickness 0.15)
				)
				(justify left bottom)
				(hide yes)
			)
		)
		(property "License" "Apache-2.0"
			(at 115.57 193.04 0)
			(effects
				(font
					(size 1.27 1.27)
					(thickness 0.15)
				)
				(justify left bottom)
				(hide yes)
			)
		)
		(pin "1"
		)
		(instances
			(project "OCuLink to 10GbE adapter"
				(path ""
					(reference "#PWR0226")
					(unit 1)
				)
			)
			(project "thunderbolt-to-10gbe-adapter"
				(path ""
					(reference "#PWR0252")
					(unit 1)
				)
			)
		)
	)
	(symbol
		(lib_id "antmicropower:+1V8")
		(at 26.67 90.17 0)
		(unit 1)
		(exclude_from_sim no)
		(in_bom yes)
		(on_board yes)
		(dnp no)
		(property "Reference" "#PWR0218"
			(at 41.91 92.71 0)
			(effects
				(font
					(size 1.27 1.27)
					(thickness 0.15)
				)
				(justify left bottom)
				(hide yes)
			)
		)
		(property "Value" "+1V88"
			(at 26.67 86.36 0)
			(effects
				(font
					(size 1.27 1.27)
					(thickness 0.15)
				)
			)
		)
		(property "Footprint" ""
			(at 41.91 97.79 0)
			(effects
				(font
					(size 1.27 1.27)
					(thickness 0.15)
				)
				(justify left bottom)
				(hide yes)
			)
		)
		(property "Datasheet" ""
			(at 41.91 100.33 0)
			(effects
				(font
					(size 1.27 1.27)
					(thickness 0.15)
				)
				(justify left bottom)
				(hide yes)
			)
		)
		(property "Description" ""
			(at 26.67 90.17 0)
			(effects
				(font
					(size 1.27 1.27)
				)
				(hide yes)
			)
		)
		(property "Author" "Antmicro"
			(at 41.91 95.25 0)
			(effects
				(font
					(size 1.27 1.27)
					(thickness 0.15)
				)
				(justify left bottom)
				(hide yes)
			)
		)
		(property "License" "Apache-2.0"
			(at 41.91 97.79 0)
			(effects
				(font
					(size 1.27 1.27)
					(thickness 0.15)
				)
				(justify left bottom)
				(hide yes)
			)
		)
		(pin "1"
		)
		(instances
			(project "OCuLink to 10GbE adapter"
				(path ""
					(reference "#PWR0163")
					(unit 1)
				)
			)
			(project "thunderbolt-to-10gbe-adapter"
				(path ""
					(reference "#PWR0218")
					(unit 1)
				)
			)
		)
	)
	(symbol
		(lib_id "antmicropower:GND")
		(at 77.47 182.88 0)
		(unit 1)
		(exclude_from_sim no)
		(in_bom yes)
		(on_board yes)
		(dnp no)
		(property "Reference" "#PWR0235"
			(at 86.36 185.42 0)
			(effects
				(font
					(size 1.27 1.27)
					(thickness 0.15)
				)
				(justify left bottom)
				(hide yes)
			)
		)
		(property "Value" "GND"
			(at 77.47 186.69 0)
			(effects
				(font
					(size 1.27 1.27)
					(thickness 0.15)
				)
			)
		)
		(property "Footprint" ""
			(at 86.36 190.5 0)
			(effects
				(font
					(size 1.27 1.27)
					(thickness 0.15)
				)
				(justify left bottom)
				(hide yes)
			)
		)
		(property "Datasheet" ""
			(at 86.36 195.58 0)
			(effects
				(font
					(size 1.27 1.27)
					(thickness 0.15)
				)
				(justify left bottom)
				(hide yes)
			)
		)
		(property "Description" ""
			(at 77.47 182.88 0)
			(effects
				(font
					(size 1.27 1.27)
				)
				(hide yes)
			)
		)
		(property "Author" "Antmicro"
			(at 86.36 190.5 0)
			(effects
				(font
					(size 1.27 1.27)
					(thickness 0.15)
				)
				(justify left bottom)
				(hide yes)
			)
		)
		(property "License" "Apache-2.0"
			(at 86.36 193.04 0)
			(effects
				(font
					(size 1.27 1.27)
					(thickness 0.15)
				)
				(justify left bottom)
				(hide yes)
			)
		)
		(pin "1"
		)
		(instances
			(project "OCuLink to 10GbE adapter"
				(path ""
					(reference "#PWR0223")
					(unit 1)
				)
			)
			(project "thunderbolt-to-10gbe-adapter"
				(path ""
					(reference "#PWR0235")
					(unit 1)
				)
			)
		)
	)
	(symbol
		(lib_id "antmicropower:GND")
		(at 73.66 54.61 0)
		(mirror y)
		(unit 1)
		(exclude_from_sim no)
		(in_bom yes)
		(on_board yes)
		(dnp no)
		(property "Reference" "#PWR0228"
			(at 64.77 57.15 0)
			(effects
				(font
					(size 1.27 1.27)
					(thickness 0.15)
				)
				(justify left bottom)
				(hide yes)
			)
		)
		(property "Value" "GND"
			(at 73.66 58.42 0)
			(effects
				(font
					(size 1.27 1.27)
					(thickness 0.15)
				)
			)
		)
		(property "Footprint" ""
			(at 64.77 62.23 0)
			(effects
				(font
					(size 1.27 1.27)
					(thickness 0.15)
				)
				(justify left bottom)
				(hide yes)
			)
		)
		(property "Datasheet" ""
			(at 64.77 67.31 0)
			(effects
				(font
					(size 1.27 1.27)
					(thickness 0.15)
				)
				(justify left bottom)
				(hide yes)
			)
		)
		(property "Description" ""
			(at 73.66 54.61 0)
			(effects
				(font
					(size 1.27 1.27)
				)
				(hide yes)
			)
		)
		(property "Author" "Antmicro"
			(at 64.77 62.23 0)
			(effects
				(font
					(size 1.27 1.27)
					(thickness 0.15)
				)
				(justify left bottom)
				(hide yes)
			)
		)
		(property "License" "Apache-2.0"
			(at 64.77 64.77 0)
			(effects
				(font
					(size 1.27 1.27)
					(thickness 0.15)
				)
				(justify left bottom)
				(hide yes)
			)
		)
		(pin "1"
		)
		(instances
			(project "thunderbolt-to-10gbe-adapter"
				(path ""
					(reference "#PWR0228")
					(unit 1)
				)
			)
		)
	)
	(symbol
		(lib_id "antmicropower:GND")
		(at 90.17 262.89 0)
		(unit 1)
		(exclude_from_sim no)
		(in_bom yes)
		(on_board yes)
		(dnp no)
		(property "Reference" "#PWR0245"
			(at 99.06 265.43 0)
			(effects
				(font
					(size 1.27 1.27)
					(thickness 0.15)
				)
				(justify left bottom)
				(hide yes)
			)
		)
		(property "Value" "GND"
			(at 90.17 266.7 0)
			(effects
				(font
					(size 1.27 1.27)
					(thickness 0.15)
				)
			)
		)
		(property "Footprint" ""
			(at 99.06 270.51 0)
			(effects
				(font
					(size 1.27 1.27)
					(thickness 0.15)
				)
				(justify left bottom)
				(hide yes)
			)
		)
		(property "Datasheet" ""
			(at 99.06 275.59 0)
			(effects
				(font
					(size 1.27 1.27)
					(thickness 0.15)
				)
				(justify left bottom)
				(hide yes)
			)
		)
		(property "Description" ""
			(at 90.17 262.89 0)
			(effects
				(font
					(size 1.27 1.27)
				)
				(hide yes)
			)
		)
		(property "Author" "Antmicro"
			(at 99.06 270.51 0)
			(effects
				(font
					(size 1.27 1.27)
					(thickness 0.15)
				)
				(justify left bottom)
				(hide yes)
			)
		)
		(property "License" "Apache-2.0"
			(at 99.06 273.05 0)
			(effects
				(font
					(size 1.27 1.27)
					(thickness 0.15)
				)
				(justify left bottom)
				(hide yes)
			)
		)
		(pin "1"
		)
		(instances
			(project "OCuLink to 10GbE adapter"
				(path ""
					(reference "#PWR0244")
					(unit 1)
				)
			)
			(project "thunderbolt-to-10gbe-adapter"
				(path ""
					(reference "#PWR0245")
					(unit 1)
				)
			)
		)
	)
	(symbol
		(lib_id "antmicropower:VDD")
		(at 199.39 104.14 0)
		(unit 1)
		(exclude_from_sim no)
		(in_bom yes)
		(on_board yes)
		(dnp no)
		(property "Reference" "#PWR0285"
			(at 199.39 107.95 0)
			(effects
				(font
					(size 1.27 1.27)
				)
				(hide yes)
			)
		)
		(property "Value" "AVDDH"
			(at 199.39 100.33 0)
			(effects
				(font
					(size 1.27 1.27)
				)
			)
		)
		(property "Footprint" ""
			(at 199.39 104.14 0)
			(effects
				(font
					(size 1.27 1.27)
				)
				(hide yes)
			)
		)
		(property "Datasheet" ""
			(at 199.39 104.14 0)
			(effects
				(font
					(size 1.27 1.27)
				)
				(hide yes)
			)
		)
		(property "Description" ""
			(at 199.39 104.14 0)
			(effects
				(font
					(size 1.27 1.27)
				)
				(hide yes)
			)
		)
		(pin "1"
		)
		(instances
			(project "OCuLink to 10GbE adapter"
				(path ""
					(reference "#PWR0156")
					(unit 1)
				)
			)
			(project "thunderbolt-to-10gbe-adapter"
				(path ""
					(reference "#PWR0285")
					(unit 1)
				)
			)
		)
	)
	(symbol
		(lib_id "antmicroFixedInductors:L_4u7_1.55A_Bourns-SRP2512A")
		(at 80.01 226.06 0)
		(unit 1)
		(exclude_from_sim no)
		(in_bom yes)
		(on_board yes)
		(dnp no)
		(fields_autoplaced yes)
		(property "Reference" "L10"
			(at 82.55 220.98 0)
			(effects
				(font
					(size 1.27 1.27)
					(thickness 0.15)
				)
			)
		)
		(property "Value" "L_4u7_1.55A_Bourns-SRP2512A"
			(at 95.25 231.14 0)
			(effects
				(font
					(size 1.27 1.27)
					(thickness 0.15)
				)
				(justify left bottom)
				(hide yes)
			)
		)
		(property "Footprint" "antmicro-footprints:L_Bourns-SRP2512A"
			(at 95.25 233.68 0)
			(effects
				(font
					(size 1.27 1.27)
					(thickness 0.15)
				)
				(justify left bottom)
				(hide yes)
			)
		)
		(property "Datasheet" "https://www.bourns.com/docs/Product-Datasheets/srp2512a.pdf"
			(at 95.25 236.22 0)
			(effects
				(font
					(size 1.27 1.27)
					(thickness 0.15)
				)
				(justify left bottom)
				(hide yes)
			)
		)
		(property "Description" "4.7 µH Shielded Drum Core, Wirewound Inductor 1.55 A 235mOhm Max 1008 (2520 Metric)"
			(at 95.25 256.54 0)
			(effects
				(font
					(size 1.27 1.27)
				)
				(justify left bottom)
				(hide yes)
			)
		)
		(property "Val" "4u7/1.55A"
			(at 82.55 223.52 0)
			(effects
				(font
					(size 1.27 1.27)
					(thickness 0.15)
				)
			)
		)
		(property "Manufacturer" "Bourns"
			(at 95.25 238.76 0)
			(effects
				(font
					(size 1.27 1.27)
					(thickness 0.15)
				)
				(justify left bottom)
				(hide yes)
			)
		)
		(property "MPN" "SRP2512A-4R7M"
			(at 95.25 241.3 0)
			(effects
				(font
					(size 1.27 1.27)
					(thickness 0.15)
				)
				(justify left bottom)
				(hide yes)
			)
		)
		(property "ISat" "1.9 A"
			(at 95.25 243.84 0)
			(effects
				(font
					(size 1.27 1.27)
				)
				(justify left bottom)
				(hide yes)
			)
		)
		(property "IMax" "1.55 A"
			(at 95.25 246.38 0)
			(effects
				(font
					(size 1.27 1.27)
				)
				(justify left bottom)
				(hide yes)
			)
		)
		(property "Size" "2.5x2.0"
			(at 95.25 248.92 0)
			(effects
				(font
					(size 1.27 1.27)
				)
				(justify left bottom)
				(hide yes)
			)
		)
		(property "Author" "Antmicro"
			(at 95.25 251.46 0)
			(effects
				(font
					(size 1.27 1.27)
					(thickness 0.15)
				)
				(justify left bottom)
				(hide yes)
			)
		)
		(property "License" "Apache-2.0"
			(at 95.25 254 0)
			(effects
				(font
					(size 1.27 1.27)
					(thickness 0.15)
				)
				(justify left bottom)
				(hide yes)
			)
		)
		(pin "2"
		)
		(pin "1"
		)
		(instances
			(project "oculink-to-10gbe-adapter"
				(path ""
					(reference "L11")
					(unit 1)
				)
			)
			(project "thunderbolt-to-10gbe-adapter"
				(path ""
					(reference "L10")
					(unit 1)
				)
			)
		)
	)
	(symbol
		(lib_id "antmicropower:GND")
		(at 361.95 76.2 0)
		(unit 1)
		(exclude_from_sim no)
		(in_bom yes)
		(on_board yes)
		(dnp no)
		(property "Reference" "#PWR0332"
			(at 370.84 78.74 0)
			(effects
				(font
					(size 1.27 1.27)
					(thickness 0.15)
				)
				(justify left bottom)
				(hide yes)
			)
		)
		(property "Value" "GND"
			(at 361.95 80.01 0)
			(effects
				(font
					(size 1.27 1.27)
					(thickness 0.15)
				)
			)
		)
		(property "Footprint" ""
			(at 370.84 83.82 0)
			(effects
				(font
					(size 1.27 1.27)
					(thickness 0.15)
				)
				(justify left bottom)
				(hide yes)
			)
		)
		(property "Datasheet" ""
			(at 370.84 88.9 0)
			(effects
				(font
					(size 1.27 1.27)
					(thickness 0.15)
				)
				(justify left bottom)
				(hide yes)
			)
		)
		(property "Description" ""
			(at 361.95 76.2 0)
			(effects
				(font
					(size 1.27 1.27)
				)
				(hide yes)
			)
		)
		(property "Author" "Antmicro"
			(at 370.84 83.82 0)
			(effects
				(font
					(size 1.27 1.27)
					(thickness 0.15)
				)
				(justify left bottom)
				(hide yes)
			)
		)
		(property "License" "Apache-2.0"
			(at 370.84 86.36 0)
			(effects
				(font
					(size 1.27 1.27)
					(thickness 0.15)
				)
				(justify left bottom)
				(hide yes)
			)
		)
		(pin "1"
		)
		(instances
			(project "OCuLink to 10GbE adapter"
				(path ""
					(reference "#PWR0146")
					(unit 1)
				)
			)
			(project "thunderbolt-to-10gbe-adapter"
				(path ""
					(reference "#PWR0332")
					(unit 1)
				)
			)
		)
	)
	(symbol
		(lib_id "antmicropower:GND")
		(at 300.99 152.4 0)
		(unit 1)
		(exclude_from_sim no)
		(in_bom yes)
		(on_board yes)
		(dnp no)
		(property "Reference" "#PWR0302"
			(at 309.88 154.94 0)
			(effects
				(font
					(size 1.27 1.27)
					(thickness 0.15)
				)
				(justify left bottom)
				(hide yes)
			)
		)
		(property "Value" "GND"
			(at 300.99 156.21 0)
			(effects
				(font
					(size 1.27 1.27)
					(thickness 0.15)
				)
			)
		)
		(property "Footprint" ""
			(at 309.88 160.02 0)
			(effects
				(font
					(size 1.27 1.27)
					(thickness 0.15)
				)
				(justify left bottom)
				(hide yes)
			)
		)
		(property "Datasheet" ""
			(at 309.88 165.1 0)
			(effects
				(font
					(size 1.27 1.27)
					(thickness 0.15)
				)
				(justify left bottom)
				(hide yes)
			)
		)
		(property "Description" ""
			(at 300.99 152.4 0)
			(effects
				(font
					(size 1.27 1.27)
				)
				(hide yes)
			)
		)
		(property "Author" "Antmicro"
			(at 309.88 160.02 0)
			(effects
				(font
					(size 1.27 1.27)
					(thickness 0.15)
				)
				(justify left bottom)
				(hide yes)
			)
		)
		(property "License" "Apache-2.0"
			(at 309.88 162.56 0)
			(effects
				(font
					(size 1.27 1.27)
					(thickness 0.15)
				)
				(justify left bottom)
				(hide yes)
			)
		)
		(pin "1"
		)
		(instances
			(project "OCuLink to 10GbE adapter"
				(path ""
					(reference "#PWR0209")
					(unit 1)
				)
			)
			(project "thunderbolt-to-10gbe-adapter"
				(path ""
					(reference "#PWR0302")
					(unit 1)
				)
			)
		)
	)
	(symbol
		(lib_id "antmicroCapacitorspol:C_Pol_100u_6V_KEMET-T490-A")
		(at 73.66 46.99 90)
		(mirror x)
		(unit 1)
		(exclude_from_sim no)
		(in_bom yes)
		(on_board yes)
		(dnp no)
		(fields_autoplaced yes)
		(property "Reference" "C157"
			(at 71.12 47.7266 90)
			(effects
				(font
					(size 1.27 1.27)
					(thickness 0.15)
				)
				(justify left)
			)
		)
		(property "Value" "C_Pol_100u_6V_KEMET-T490-A"
			(at 76.2 60.96 0)
			(effects
				(font
					(size 1.27 1.27)
					(thickness 0.15)
				)
				(justify left bottom)
				(hide yes)
			)
		)
		(property "Footprint" "antmicro-footprints:C_Pol_EIA-A"
			(at 81.28 60.96 0)
			(effects
				(font
					(size 1.27 1.27)
					(thickness 0.15)
				)
				(justify left bottom)
				(hide yes)
			)
		)
		(property "Datasheet" "https://www.kemet.com/en/us/capacitors/product/T490A107M006ATE800.html"
			(at 83.82 60.96 0)
			(effects
				(font
					(size 1.27 1.27)
					(thickness 0.15)
				)
				(justify left bottom)
				(hide yes)
			)
		)
		(property "Description" "Surface Mount Tantalum Capacitor,  Solid SMD 6V 100uF 1206 20% ESR=800mOhms"
			(at 99.06 60.96 0)
			(effects
				(font
					(size 1.27 1.27)
				)
				(justify left bottom)
				(hide yes)
			)
		)
		(property "Val" "100u"
			(at 71.12 50.2666 90)
			(effects
				(font
					(size 1.27 1.27)
					(thickness 0.15)
				)
				(justify left)
			)
		)
		(property "MPN" "T490A107M006ATE800"
			(at 86.36 60.96 0)
			(effects
				(font
					(size 1.27 1.27)
					(thickness 0.15)
				)
				(justify left bottom)
				(hide yes)
			)
		)
		(property "Manufacturer" "KEMET"
			(at 88.9 60.96 0)
			(effects
				(font
					(size 1.27 1.27)
					(thickness 0.15)
				)
				(justify left bottom)
				(hide yes)
			)
		)
		(property "License" "Apache-2.0"
			(at 91.44 60.96 0)
			(effects
				(font
					(size 1.27 1.27)
					(thickness 0.15)
				)
				(justify left bottom)
				(hide yes)
			)
		)
		(property "Author" "Antmicro"
			(at 93.98 60.96 0)
			(effects
				(font
					(size 1.27 1.27)
					(thickness 0.15)
				)
				(justify left bottom)
				(hide yes)
			)
		)
		(property "Voltage" "6V"
			(at 96.52 60.96 0)
			(effects
				(font
					(size 1.27 1.27)
				)
				(justify left bottom)
				(hide yes)
			)
		)
		(property "Dielectric" "template_dielectric"
			(at 99.06 60.96 0)
			(effects
				(font
					(size 1.27 1.27)
				)
				(justify left bottom)
				(hide yes)
			)
		)
		(pin "2"
		)
		(pin "1"
		)
		(instances
			(project "thunderbolt-to-10gbe-adapter"
				(path ""
					(reference "C157")
					(unit 1)
				)
			)
		)
	)
	(symbol
		(lib_id "antmicroCapacitorsmisc:C_100u_0805")
		(at 97.79 153.67 90)
		(unit 1)
		(exclude_from_sim no)
		(in_bom yes)
		(on_board yes)
		(dnp no)
		(property "Reference" "C170"
			(at 99.568 149.86 90)
			(effects
				(font
					(size 1.27 1.27)
					(thickness 0.15)
				)
				(justify right)
			)
		)
		(property "Value" "C_100u_0805"
			(at 107.95 133.35 0)
			(effects
				(font
					(size 1.27 1.27)
					(thickness 0.15)
				)
				(justify left bottom)
				(hide yes)
			)
		)
		(property "Footprint" "antmicro-footprints:C_0805_2012Metric"
			(at 110.49 133.35 0)
			(effects
				(font
					(size 1.27 1.27)
					(thickness 0.15)
				)
				(justify left bottom)
				(hide yes)
			)
		)
		(property "Datasheet" "https://www.murata.com/products/productdetail?partno=GRM21BR60J107ME15%23"
			(at 113.03 133.35 0)
			(effects
				(font
					(size 1.27 1.27)
					(thickness 0.15)
				)
				(justify left bottom)
				(hide yes)
			)
		)
		(property "Description" "SMD Multilayer Ceramic Capacitor, 100 µF, 6.3 V, 0805 [2012 Metric], ± 20%, X5R, GRM Series"
			(at 97.79 153.67 0)
			(effects
				(font
					(size 1.27 1.27)
				)
				(hide yes)
			)
		)
		(property "MPN" "GRM21BR60J107ME15L"
			(at 115.57 133.35 0)
			(effects
				(font
					(size 1.27 1.27)
					(thickness 0.15)
				)
				(justify left bottom)
				(hide yes)
			)
		)
		(property "Manufacturer" "Murata"
			(at 118.11 133.35 0)
			(effects
				(font
					(size 1.27 1.27)
					(thickness 0.15)
				)
				(justify left bottom)
				(hide yes)
			)
		)
		(property "License" "Apache-2.0"
			(at 120.65 133.35 0)
			(effects
				(font
					(size 1.27 1.27)
					(thickness 0.15)
				)
				(justify left bottom)
				(hide yes)
			)
		)
		(property "Author" "Antmicro"
			(at 123.19 133.35 0)
			(effects
				(font
					(size 1.27 1.27)
					(thickness 0.15)
				)
				(justify left bottom)
				(hide yes)
			)
		)
		(property "Val" "100u"
			(at 99.568 152.4 90)
			(effects
				(font
					(size 1.27 1.27)
					(thickness 0.15)
				)
				(justify right)
			)
		)
		(property "Voltage" ""
			(at 125.73 133.35 0)
			(effects
				(font
					(size 1.27 1.27)
				)
				(justify left bottom)
				(hide yes)
			)
		)
		(property "Dielectric" ""
			(at 128.27 133.35 0)
			(effects
				(font
					(size 1.27 1.27)
				)
				(justify left bottom)
				(hide yes)
			)
		)
		(property "Public" "False"
			(at 130.81 133.35 0)
			(effects
				(font
					(size 1.27 1.27)
				)
				(justify left bottom)
				(hide yes)
			)
		)
		(pin "1"
		)
		(pin "2"
		)
		(instances
			(project "OCuLink to 10GbE adapter"
				(path ""
					(reference "C163")
					(unit 1)
				)
			)
			(project "thunderbolt-to-10gbe-adapter"
				(path ""
					(reference "C170")
					(unit 1)
				)
			)
		)
	)
	(symbol
		(lib_id "antmicroCapacitors0402:C_1u_25V_0402")
		(at 353.06 73.66 90)
		(unit 1)
		(exclude_from_sim no)
		(in_bom yes)
		(on_board yes)
		(dnp no)
		(property "Reference" "C241"
			(at 355.092 69.85 90)
			(effects
				(font
					(size 1.27 1.27)
					(thickness 0.15)
				)
				(justify right)
			)
		)
		(property "Value" "C_1u_25V_0402"
			(at 363.22 53.34 0)
			(effects
				(font
					(size 1.27 1.27)
					(thickness 0.15)
				)
				(justify left bottom)
				(hide yes)
			)
		)
		(property "Footprint" "antmicro-footprints:C_0402_1005Metric"
			(at 365.76 53.34 0)
			(effects
				(font
					(size 1.27 1.27)
					(thickness 0.15)
				)
				(justify left bottom)
				(hide yes)
			)
		)
		(property "Datasheet" "https://www.murata.com/products/productdetail?partno=GRM155R61E105KE11%23"
			(at 368.3 53.34 0)
			(effects
				(font
					(size 1.27 1.27)
					(thickness 0.15)
				)
				(justify left bottom)
				(hide yes)
			)
		)
		(property "Description" "SMD Multilayer Ceramic Capacitor, 1 µF, 25 V, 0402 [1005 Metric], ± 10%, X5R, GRM Series"
			(at 353.06 73.66 0)
			(effects
				(font
					(size 1.27 1.27)
				)
				(hide yes)
			)
		)
		(property "MPN" "GRM155R61E105KE11J"
			(at 370.84 53.34 0)
			(effects
				(font
					(size 1.27 1.27)
					(thickness 0.15)
				)
				(justify left bottom)
				(hide yes)
			)
		)
		(property "Manufacturer" "Murata"
			(at 373.38 53.34 0)
			(effects
				(font
					(size 1.27 1.27)
					(thickness 0.15)
				)
				(justify left bottom)
				(hide yes)
			)
		)
		(property "License" "Apache-2.0"
			(at 375.92 53.34 0)
			(effects
				(font
					(size 1.27 1.27)
					(thickness 0.15)
				)
				(justify left bottom)
				(hide yes)
			)
		)
		(property "Author" "Antmicro"
			(at 378.46 53.34 0)
			(effects
				(font
					(size 1.27 1.27)
					(thickness 0.15)
				)
				(justify left bottom)
				(hide yes)
			)
		)
		(property "Val" "1u"
			(at 355.092 72.39 90)
			(effects
				(font
					(size 1.27 1.27)
					(thickness 0.15)
				)
				(justify right)
			)
		)
		(property "Voltage" "25V"
			(at 381 53.34 0)
			(effects
				(font
					(size 1.27 1.27)
				)
				(justify left bottom)
				(hide yes)
			)
		)
		(property "Dielectric" "X5R"
			(at 383.54 53.34 0)
			(effects
				(font
					(size 1.27 1.27)
				)
				(justify left bottom)
				(hide yes)
			)
		)
		(pin "2"
		)
		(pin "1"
		)
		(instances
			(project "OCuLink to 10GbE adapter"
				(path ""
					(reference "C111")
					(unit 1)
				)
			)
			(project "thunderbolt-to-10gbe-adapter"
				(path ""
					(reference "C241")
					(unit 1)
				)
			)
		)
	)
	(symbol
		(lib_id "antmicroCapacitors0603:C_22u_16V_0603")
		(at 90.17 52.07 90)
		(unit 1)
		(exclude_from_sim no)
		(in_bom yes)
		(on_board yes)
		(dnp no)
		(property "Reference" "C166"
			(at 92.202 48.26 90)
			(effects
				(font
					(size 1.27 1.27)
					(thickness 0.15)
				)
				(justify right)
			)
		)
		(property "Value" "C_22u_16V_0603"
			(at 100.33 31.75 0)
			(effects
				(font
					(size 1.27 1.27)
					(thickness 0.15)
				)
				(justify left bottom)
				(hide yes)
			)
		)
		(property "Footprint" "antmicro-footprints:C_0603_1608Metric_EIA"
			(at 102.87 31.75 0)
			(effects
				(font
					(size 1.27 1.27)
					(thickness 0.15)
				)
				(justify left bottom)
				(hide yes)
			)
		)
		(property "Datasheet" "https://product.samsungsem.com/mlcc/CL10A226MO7JZN.do"
			(at 105.41 31.75 0)
			(effects
				(font
					(size 1.27 1.27)
					(thickness 0.15)
				)
				(justify left bottom)
				(hide yes)
			)
		)
		(property "Description" "SMD Multilayer Ceramic Capacitor"
			(at 90.17 52.07 0)
			(effects
				(font
					(size 1.27 1.27)
				)
				(hide yes)
			)
		)
		(property "MPN" "CL10A226MO7JZNC"
			(at 107.95 31.75 0)
			(effects
				(font
					(size 1.27 1.27)
					(thickness 0.15)
				)
				(justify left bottom)
				(hide yes)
			)
		)
		(property "Manufacturer" "Samsung Electro-Mechanics"
			(at 110.49 31.75 0)
			(effects
				(font
					(size 1.27 1.27)
					(thickness 0.15)
				)
				(justify left bottom)
				(hide yes)
			)
		)
		(property "License" "Apache-2.0"
			(at 113.03 31.75 0)
			(effects
				(font
					(size 1.27 1.27)
					(thickness 0.15)
				)
				(justify left bottom)
				(hide yes)
			)
		)
		(property "Author" "Antmicro"
			(at 115.57 31.75 0)
			(effects
				(font
					(size 1.27 1.27)
					(thickness 0.15)
				)
				(justify left bottom)
				(hide yes)
			)
		)
		(property "Val" "22u"
			(at 92.202 50.8 90)
			(effects
				(font
					(size 1.27 1.27)
					(thickness 0.15)
				)
				(justify right)
			)
		)
		(property "Voltage" "16V"
			(at 118.11 31.75 0)
			(effects
				(font
					(size 1.27 1.27)
				)
				(justify left bottom)
				(hide yes)
			)
		)
		(property "Dielectric" ""
			(at 120.65 31.75 0)
			(effects
				(font
					(size 1.27 1.27)
				)
				(justify left bottom)
				(hide yes)
			)
		)
		(pin "1"
		)
		(pin "2"
		)
		(instances
			(project "OCuLink to 10GbE adapter"
				(path ""
					(reference "C80")
					(unit 1)
				)
			)
			(project "thunderbolt-to-10gbe-adapter"
				(path ""
					(reference "C166")
					(unit 1)
				)
			)
		)
	)
	(symbol
		(lib_id "antmicropower:PWR_FLAG")
		(at 101.6 224.79 0)
		(unit 1)
		(exclude_from_sim no)
		(in_bom yes)
		(on_board yes)
		(dnp no)
		(fields_autoplaced yes)
		(property "Reference" "#FLG028"
			(at 101.6 222.885 0)
			(effects
				(font
					(size 1.27 1.27)
				)
				(hide yes)
			)
		)
		(property "Value" "PWR_FLAG"
			(at 101.6 219.71 0)
			(effects
				(font
					(size 1.27 1.27)
				)
			)
		)
		(property "Footprint" ""
			(at 101.6 224.79 0)
			(effects
				(font
					(size 1.27 1.27)
				)
				(hide yes)
			)
		)
		(property "Datasheet" ""
			(at 101.6 224.79 0)
			(effects
				(font
					(size 1.27 1.27)
				)
				(hide yes)
			)
		)
		(property "Description" ""
			(at 101.6 227.33 0)
			(effects
				(font
					(size 1.27 1.27)
				)
				(justify left bottom)
				(hide yes)
			)
		)
		(pin "1"
		)
		(instances
			(project "OCuLink to 10GbE adapter"
				(path ""
					(reference "#FLG018")
					(unit 1)
				)
			)
			(project "thunderbolt-to-10gbe-adapter"
				(path ""
					(reference "#FLG028")
					(unit 1)
				)
			)
		)
	)
	(symbol
		(lib_id "antmicroCapacitors0402:C_1u_25V_0402")
		(at 370.84 113.03 90)
		(unit 1)
		(exclude_from_sim no)
		(in_bom yes)
		(on_board yes)
		(dnp no)
		(property "Reference" "C253"
			(at 372.872 109.22 90)
			(effects
				(font
					(size 1.27 1.27)
					(thickness 0.15)
				)
				(justify right)
			)
		)
		(property "Value" "C_1u_25V_0402"
			(at 381 92.71 0)
			(effects
				(font
					(size 1.27 1.27)
					(thickness 0.15)
				)
				(justify left bottom)
				(hide yes)
			)
		)
		(property "Footprint" "antmicro-footprints:C_0402_1005Metric"
			(at 383.54 92.71 0)
			(effects
				(font
					(size 1.27 1.27)
					(thickness 0.15)
				)
				(justify left bottom)
				(hide yes)
			)
		)
		(property "Datasheet" "https://www.murata.com/products/productdetail?partno=GRM155R61E105KE11%23"
			(at 386.08 92.71 0)
			(effects
				(font
					(size 1.27 1.27)
					(thickness 0.15)
				)
				(justify left bottom)
				(hide yes)
			)
		)
		(property "Description" "SMD Multilayer Ceramic Capacitor, 1 µF, 25 V, 0402 [1005 Metric], ± 10%, X5R, GRM Series"
			(at 370.84 113.03 0)
			(effects
				(font
					(size 1.27 1.27)
				)
				(hide yes)
			)
		)
		(property "MPN" "GRM155R61E105KE11J"
			(at 388.62 92.71 0)
			(effects
				(font
					(size 1.27 1.27)
					(thickness 0.15)
				)
				(justify left bottom)
				(hide yes)
			)
		)
		(property "Manufacturer" "Murata"
			(at 391.16 92.71 0)
			(effects
				(font
					(size 1.27 1.27)
					(thickness 0.15)
				)
				(justify left bottom)
				(hide yes)
			)
		)
		(property "License" "Apache-2.0"
			(at 393.7 92.71 0)
			(effects
				(font
					(size 1.27 1.27)
					(thickness 0.15)
				)
				(justify left bottom)
				(hide yes)
			)
		)
		(property "Author" "Antmicro"
			(at 396.24 92.71 0)
			(effects
				(font
					(size 1.27 1.27)
					(thickness 0.15)
				)
				(justify left bottom)
				(hide yes)
			)
		)
		(property "Val" "1u"
			(at 372.872 111.76 90)
			(effects
				(font
					(size 1.27 1.27)
					(thickness 0.15)
				)
				(justify right)
			)
		)
		(property "Voltage" "25V"
			(at 398.78 92.71 0)
			(effects
				(font
					(size 1.27 1.27)
				)
				(justify left bottom)
				(hide yes)
			)
		)
		(property "Dielectric" "X5R"
			(at 401.32 92.71 0)
			(effects
				(font
					(size 1.27 1.27)
				)
				(justify left bottom)
				(hide yes)
			)
		)
		(pin "2"
		)
		(pin "1"
		)
		(instances
			(project "OCuLink to 10GbE adapter"
				(path ""
					(reference "C137")
					(unit 1)
				)
			)
			(project "thunderbolt-to-10gbe-adapter"
				(path ""
					(reference "C253")
					(unit 1)
				)
			)
		)
	)
	(symbol
		(lib_id "antmicropower:GND")
		(at 397.51 54.61 0)
		(unit 1)
		(exclude_from_sim no)
		(in_bom yes)
		(on_board yes)
		(dnp no)
		(property "Reference" "#PWR0349"
			(at 406.4 57.15 0)
			(effects
				(font
					(size 1.27 1.27)
					(thickness 0.15)
				)
				(justify left bottom)
				(hide yes)
			)
		)
		(property "Value" "GND"
			(at 397.51 58.42 0)
			(effects
				(font
					(size 1.27 1.27)
					(thickness 0.15)
				)
			)
		)
		(property "Footprint" ""
			(at 406.4 62.23 0)
			(effects
				(font
					(size 1.27 1.27)
					(thickness 0.15)
				)
				(justify left bottom)
				(hide yes)
			)
		)
		(property "Datasheet" ""
			(at 406.4 67.31 0)
			(effects
				(font
					(size 1.27 1.27)
					(thickness 0.15)
				)
				(justify left bottom)
				(hide yes)
			)
		)
		(property "Description" ""
			(at 397.51 54.61 0)
			(effects
				(font
					(size 1.27 1.27)
				)
				(hide yes)
			)
		)
		(property "Author" "Antmicro"
			(at 406.4 62.23 0)
			(effects
				(font
					(size 1.27 1.27)
					(thickness 0.15)
				)
				(justify left bottom)
				(hide yes)
			)
		)
		(property "License" "Apache-2.0"
			(at 406.4 64.77 0)
			(effects
				(font
					(size 1.27 1.27)
					(thickness 0.15)
				)
				(justify left bottom)
				(hide yes)
			)
		)
		(pin "1"
		)
		(instances
			(project "OCuLink to 10GbE adapter"
				(path ""
					(reference "#PWR0132")
					(unit 1)
				)
			)
			(project "thunderbolt-to-10gbe-adapter"
				(path ""
					(reference "#PWR0349")
					(unit 1)
				)
			)
		)
	)
	(symbol
		(lib_id "antmicropower:VDD")
		(at 189.23 116.84 0)
		(unit 1)
		(exclude_from_sim no)
		(in_bom yes)
		(on_board yes)
		(dnp no)
		(property "Reference" "#PWR0282"
			(at 189.23 120.65 0)
			(effects
				(font
					(size 1.27 1.27)
				)
				(hide yes)
			)
		)
		(property "Value" "XFI_VDD"
			(at 189.23 113.03 0)
			(effects
				(font
					(size 1.27 1.27)
				)
			)
		)
		(property "Footprint" ""
			(at 189.23 116.84 0)
			(effects
				(font
					(size 1.27 1.27)
				)
				(hide yes)
			)
		)
		(property "Datasheet" ""
			(at 189.23 116.84 0)
			(effects
				(font
					(size 1.27 1.27)
				)
				(hide yes)
			)
		)
		(property "Description" ""
			(at 189.23 116.84 0)
			(effects
				(font
					(size 1.27 1.27)
				)
				(hide yes)
			)
		)
		(pin "1"
		)
		(instances
			(project "OCuLink to 10GbE adapter"
				(path ""
					(reference "#PWR0153")
					(unit 1)
				)
			)
			(project "thunderbolt-to-10gbe-adapter"
				(path ""
					(reference "#PWR0282")
					(unit 1)
				)
			)
		)
	)
	(symbol
		(lib_id "antmicroCapacitors0603:C_22u_16V_0603")
		(at 370.84 130.81 90)
		(unit 1)
		(exclude_from_sim no)
		(in_bom yes)
		(on_board yes)
		(dnp no)
		(fields_autoplaced yes)
		(property "Reference" "C254"
			(at 373.38 126.9936 90)
			(effects
				(font
					(size 1.27 1.27)
					(thickness 0.15)
				)
				(justify right)
			)
		)
		(property "Value" "C_22u_16V_0603"
			(at 381 110.49 0)
			(effects
				(font
					(size 1.27 1.27)
					(thickness 0.15)
				)
				(justify left bottom)
				(hide yes)
			)
		)
		(property "Footprint" "antmicro-footprints:C_0603_1608Metric_EIA"
			(at 383.54 110.49 0)
			(effects
				(font
					(size 1.27 1.27)
					(thickness 0.15)
				)
				(justify left bottom)
				(hide yes)
			)
		)
		(property "Datasheet" "https://product.samsungsem.com/mlcc/CL10A226MO7JZN.do"
			(at 386.08 110.49 0)
			(effects
				(font
					(size 1.27 1.27)
					(thickness 0.15)
				)
				(justify left bottom)
				(hide yes)
			)
		)
		(property "Description" "SMD Multilayer Ceramic Capacitor"
			(at 370.84 130.81 0)
			(effects
				(font
					(size 1.27 1.27)
				)
				(hide yes)
			)
		)
		(property "MPN" "CL10A226MO7JZNC"
			(at 388.62 110.49 0)
			(effects
				(font
					(size 1.27 1.27)
					(thickness 0.15)
				)
				(justify left bottom)
				(hide yes)
			)
		)
		(property "Manufacturer" "Samsung Electro-Mechanics"
			(at 391.16 110.49 0)
			(effects
				(font
					(size 1.27 1.27)
					(thickness 0.15)
				)
				(justify left bottom)
				(hide yes)
			)
		)
		(property "License" "Apache-2.0"
			(at 393.7 110.49 0)
			(effects
				(font
					(size 1.27 1.27)
					(thickness 0.15)
				)
				(justify left bottom)
				(hide yes)
			)
		)
		(property "Author" "Antmicro"
			(at 396.24 110.49 0)
			(effects
				(font
					(size 1.27 1.27)
					(thickness 0.15)
				)
				(justify left bottom)
				(hide yes)
			)
		)
		(property "Val" "22u"
			(at 373.38 129.5336 90)
			(effects
				(font
					(size 1.27 1.27)
					(thickness 0.15)
				)
				(justify right)
			)
		)
		(property "Voltage" "16V"
			(at 398.78 110.49 0)
			(effects
				(font
					(size 1.27 1.27)
				)
				(justify left bottom)
				(hide yes)
			)
		)
		(property "Dielectric" ""
			(at 401.32 110.49 0)
			(effects
				(font
					(size 1.27 1.27)
				)
				(justify left bottom)
				(hide yes)
			)
		)
		(pin "1"
		)
		(pin "2"
		)
		(instances
			(project "OCuLink to 10GbE adapter"
				(path ""
					(reference "C153")
					(unit 1)
				)
			)
			(project "thunderbolt-to-10gbe-adapter"
				(path ""
					(reference "C254")
					(unit 1)
				)
			)
		)
	)
	(symbol
		(lib_id "antmicropower:GND")
		(at 88.9 102.87 0)
		(unit 1)
		(exclude_from_sim no)
		(in_bom yes)
		(on_board yes)
		(dnp no)
		(property "Reference" "#PWR0239"
			(at 97.79 105.41 0)
			(effects
				(font
					(size 1.27 1.27)
					(thickness 0.15)
				)
				(justify left bottom)
				(hide yes)
			)
		)
		(property "Value" "GND"
			(at 88.9 106.68 0)
			(effects
				(font
					(size 1.27 1.27)
					(thickness 0.15)
				)
			)
		)
		(property "Footprint" ""
			(at 97.79 110.49 0)
			(effects
				(font
					(size 1.27 1.27)
					(thickness 0.15)
				)
				(justify left bottom)
				(hide yes)
			)
		)
		(property "Datasheet" ""
			(at 97.79 115.57 0)
			(effects
				(font
					(size 1.27 1.27)
					(thickness 0.15)
				)
				(justify left bottom)
				(hide yes)
			)
		)
		(property "Description" ""
			(at 88.9 102.87 0)
			(effects
				(font
					(size 1.27 1.27)
				)
				(hide yes)
			)
		)
		(property "Author" "Antmicro"
			(at 97.79 110.49 0)
			(effects
				(font
					(size 1.27 1.27)
					(thickness 0.15)
				)
				(justify left bottom)
				(hide yes)
			)
		)
		(property "License" "Apache-2.0"
			(at 97.79 113.03 0)
			(effects
				(font
					(size 1.27 1.27)
					(thickness 0.15)
				)
				(justify left bottom)
				(hide yes)
			)
		)
		(pin "1"
		)
		(instances
			(project "OCuLink to 10GbE adapter"
				(path ""
					(reference "#PWR0176")
					(unit 1)
				)
			)
			(project "thunderbolt-to-10gbe-adapter"
				(path ""
					(reference "#PWR0239")
					(unit 1)
				)
			)
		)
	)
	(symbol
		(lib_id "antmicropower:GND")
		(at 335.28 76.2 0)
		(unit 1)
		(exclude_from_sim no)
		(in_bom yes)
		(on_board yes)
		(dnp no)
		(property "Reference" "#PWR0319"
			(at 344.17 78.74 0)
			(effects
				(font
					(size 1.27 1.27)
					(thickness 0.15)
				)
				(justify left bottom)
				(hide yes)
			)
		)
		(property "Value" "GND"
			(at 335.28 80.01 0)
			(effects
				(font
					(size 1.27 1.27)
					(thickness 0.15)
				)
			)
		)
		(property "Footprint" ""
			(at 344.17 83.82 0)
			(effects
				(font
					(size 1.27 1.27)
					(thickness 0.15)
				)
				(justify left bottom)
				(hide yes)
			)
		)
		(property "Datasheet" ""
			(at 344.17 88.9 0)
			(effects
				(font
					(size 1.27 1.27)
					(thickness 0.15)
				)
				(justify left bottom)
				(hide yes)
			)
		)
		(property "Description" ""
			(at 335.28 76.2 0)
			(effects
				(font
					(size 1.27 1.27)
				)
				(hide yes)
			)
		)
		(property "Author" "Antmicro"
			(at 344.17 83.82 0)
			(effects
				(font
					(size 1.27 1.27)
					(thickness 0.15)
				)
				(justify left bottom)
				(hide yes)
			)
		)
		(property "License" "Apache-2.0"
			(at 344.17 86.36 0)
			(effects
				(font
					(size 1.27 1.27)
					(thickness 0.15)
				)
				(justify left bottom)
				(hide yes)
			)
		)
		(pin "1"
		)
		(instances
			(project "OCuLink to 10GbE adapter"
				(path ""
					(reference "#PWR0143")
					(unit 1)
				)
			)
			(project "thunderbolt-to-10gbe-adapter"
				(path ""
					(reference "#PWR0319")
					(unit 1)
				)
			)
		)
	)
	(symbol
		(lib_id "antmicroCapacitors0402:C_1u_25V_0402")
		(at 335.28 73.66 90)
		(unit 1)
		(exclude_from_sim no)
		(in_bom yes)
		(on_board yes)
		(dnp no)
		(property "Reference" "C233"
			(at 337.312 69.85 90)
			(effects
				(font
					(size 1.27 1.27)
					(thickness 0.15)
				)
				(justify right)
			)
		)
		(property "Value" "C_1u_25V_0402"
			(at 345.44 53.34 0)
			(effects
				(font
					(size 1.27 1.27)
					(thickness 0.15)
				)
				(justify left bottom)
				(hide yes)
			)
		)
		(property "Footprint" "antmicro-footprints:C_0402_1005Metric"
			(at 347.98 53.34 0)
			(effects
				(font
					(size 1.27 1.27)
					(thickness 0.15)
				)
				(justify left bottom)
				(hide yes)
			)
		)
		(property "Datasheet" "https://www.murata.com/products/productdetail?partno=GRM155R61E105KE11%23"
			(at 350.52 53.34 0)
			(effects
				(font
					(size 1.27 1.27)
					(thickness 0.15)
				)
				(justify left bottom)
				(hide yes)
			)
		)
		(property "Description" "SMD Multilayer Ceramic Capacitor, 1 µF, 25 V, 0402 [1005 Metric], ± 10%, X5R, GRM Series"
			(at 335.28 73.66 0)
			(effects
				(font
					(size 1.27 1.27)
				)
				(hide yes)
			)
		)
		(property "MPN" "GRM155R61E105KE11J"
			(at 353.06 53.34 0)
			(effects
				(font
					(size 1.27 1.27)
					(thickness 0.15)
				)
				(justify left bottom)
				(hide yes)
			)
		)
		(property "Manufacturer" "Murata"
			(at 355.6 53.34 0)
			(effects
				(font
					(size 1.27 1.27)
					(thickness 0.15)
				)
				(justify left bottom)
				(hide yes)
			)
		)
		(property "License" "Apache-2.0"
			(at 358.14 53.34 0)
			(effects
				(font
					(size 1.27 1.27)
					(thickness 0.15)
				)
				(justify left bottom)
				(hide yes)
			)
		)
		(property "Author" "Antmicro"
			(at 360.68 53.34 0)
			(effects
				(font
					(size 1.27 1.27)
					(thickness 0.15)
				)
				(justify left bottom)
				(hide yes)
			)
		)
		(property "Val" "1u"
			(at 337.312 72.39 90)
			(effects
				(font
					(size 1.27 1.27)
					(thickness 0.15)
				)
				(justify right)
			)
		)
		(property "Voltage" "25V"
			(at 363.22 53.34 0)
			(effects
				(font
					(size 1.27 1.27)
				)
				(justify left bottom)
				(hide yes)
			)
		)
		(property "Dielectric" "X5R"
			(at 365.76 53.34 0)
			(effects
				(font
					(size 1.27 1.27)
				)
				(justify left bottom)
				(hide yes)
			)
		)
		(pin "2"
		)
		(pin "1"
		)
		(instances
			(project "OCuLink to 10GbE adapter"
				(path ""
					(reference "C109")
					(unit 1)
				)
			)
			(project "thunderbolt-to-10gbe-adapter"
				(path ""
					(reference "C233")
					(unit 1)
				)
			)
		)
	)
	(symbol
		(lib_id "antmicroCapacitors0402:C_1u_25V_0402")
		(at 115.57 127 90)
		(unit 1)
		(exclude_from_sim no)
		(in_bom yes)
		(on_board yes)
		(dnp no)
		(property "Reference" "C183"
			(at 117.348 123.19 90)
			(effects
				(font
					(size 1.27 1.27)
					(thickness 0.15)
				)
				(justify right)
			)
		)
		(property "Value" "C_1u_25V_0402"
			(at 125.73 106.68 0)
			(effects
				(font
					(size 1.27 1.27)
					(thickness 0.15)
				)
				(justify left bottom)
				(hide yes)
			)
		)
		(property "Footprint" "antmicro-footprints:C_0402_1005Metric"
			(at 128.27 106.68 0)
			(effects
				(font
					(size 1.27 1.27)
					(thickness 0.15)
				)
				(justify left bottom)
				(hide yes)
			)
		)
		(property "Datasheet" "https://www.murata.com/products/productdetail?partno=GRM155R61E105KE11%23"
			(at 130.81 106.68 0)
			(effects
				(font
					(size 1.27 1.27)
					(thickness 0.15)
				)
				(justify left bottom)
				(hide yes)
			)
		)
		(property "Description" "SMD Multilayer Ceramic Capacitor, 1 µF, 25 V, 0402 [1005 Metric], ± 10%, X5R, GRM Series"
			(at 115.57 127 0)
			(effects
				(font
					(size 1.27 1.27)
				)
				(hide yes)
			)
		)
		(property "MPN" "GRM155R61E105KE11J"
			(at 133.35 106.68 0)
			(effects
				(font
					(size 1.27 1.27)
					(thickness 0.15)
				)
				(justify left bottom)
				(hide yes)
			)
		)
		(property "Manufacturer" "Murata"
			(at 135.89 106.68 0)
			(effects
				(font
					(size 1.27 1.27)
					(thickness 0.15)
				)
				(justify left bottom)
				(hide yes)
			)
		)
		(property "License" "Apache-2.0"
			(at 138.43 106.68 0)
			(effects
				(font
					(size 1.27 1.27)
					(thickness 0.15)
				)
				(justify left bottom)
				(hide yes)
			)
		)
		(property "Author" "Antmicro"
			(at 140.97 106.68 0)
			(effects
				(font
					(size 1.27 1.27)
					(thickness 0.15)
				)
				(justify left bottom)
				(hide yes)
			)
		)
		(property "Val" "1u"
			(at 117.348 125.73 90)
			(effects
				(font
					(size 1.27 1.27)
					(thickness 0.15)
				)
				(justify right)
			)
		)
		(property "Voltage" "25V"
			(at 143.51 106.68 0)
			(effects
				(font
					(size 1.27 1.27)
				)
				(justify left bottom)
				(hide yes)
			)
		)
		(property "Dielectric" "X5R"
			(at 146.05 106.68 0)
			(effects
				(font
					(size 1.27 1.27)
				)
				(justify left bottom)
				(hide yes)
			)
		)
		(pin "2"
		)
		(pin "1"
		)
		(instances
			(project "OCuLink to 10GbE adapter"
				(path ""
					(reference "C141")
					(unit 1)
				)
			)
			(project "thunderbolt-to-10gbe-adapter"
				(path ""
					(reference "C183")
					(unit 1)
				)
			)
		)
	)
	(symbol
		(lib_id "antmicroCapacitors0402:C_1u_25V_0402")
		(at 124.46 180.34 90)
		(unit 1)
		(exclude_from_sim no)
		(in_bom yes)
		(on_board yes)
		(dnp no)
		(property "Reference" "C188"
			(at 126.492 176.53 90)
			(effects
				(font
					(size 1.27 1.27)
					(thickness 0.15)
				)
				(justify right)
			)
		)
		(property "Value" "C_1u_25V_0402"
			(at 134.62 160.02 0)
			(effects
				(font
					(size 1.27 1.27)
					(thickness 0.15)
				)
				(justify left bottom)
				(hide yes)
			)
		)
		(property "Footprint" "antmicro-footprints:C_0402_1005Metric"
			(at 137.16 160.02 0)
			(effects
				(font
					(size 1.27 1.27)
					(thickness 0.15)
				)
				(justify left bottom)
				(hide yes)
			)
		)
		(property "Datasheet" "https://www.murata.com/products/productdetail?partno=GRM155R61E105KE11%23"
			(at 139.7 160.02 0)
			(effects
				(font
					(size 1.27 1.27)
					(thickness 0.15)
				)
				(justify left bottom)
				(hide yes)
			)
		)
		(property "Description" "SMD Multilayer Ceramic Capacitor, 1 µF, 25 V, 0402 [1005 Metric], ± 10%, X5R, GRM Series"
			(at 124.46 180.34 0)
			(effects
				(font
					(size 1.27 1.27)
				)
				(hide yes)
			)
		)
		(property "MPN" "GRM155R61E105KE11J"
			(at 142.24 160.02 0)
			(effects
				(font
					(size 1.27 1.27)
					(thickness 0.15)
				)
				(justify left bottom)
				(hide yes)
			)
		)
		(property "Manufacturer" "Murata"
			(at 144.78 160.02 0)
			(effects
				(font
					(size 1.27 1.27)
					(thickness 0.15)
				)
				(justify left bottom)
				(hide yes)
			)
		)
		(property "License" "Apache-2.0"
			(at 147.32 160.02 0)
			(effects
				(font
					(size 1.27 1.27)
					(thickness 0.15)
				)
				(justify left bottom)
				(hide yes)
			)
		)
		(property "Author" "Antmicro"
			(at 149.86 160.02 0)
			(effects
				(font
					(size 1.27 1.27)
					(thickness 0.15)
				)
				(justify left bottom)
				(hide yes)
			)
		)
		(property "Val" "1u"
			(at 126.492 179.07 90)
			(effects
				(font
					(size 1.27 1.27)
					(thickness 0.15)
				)
				(justify right)
			)
		)
		(property "Voltage" "25V"
			(at 152.4 160.02 0)
			(effects
				(font
					(size 1.27 1.27)
				)
				(justify left bottom)
				(hide yes)
			)
		)
		(property "Dielectric" "X5R"
			(at 154.94 160.02 0)
			(effects
				(font
					(size 1.27 1.27)
				)
				(justify left bottom)
				(hide yes)
			)
		)
		(pin "2"
		)
		(pin "1"
		)
		(instances
			(project "OCuLink to 10GbE adapter"
				(path ""
					(reference "C175")
					(unit 1)
				)
			)
			(project "thunderbolt-to-10gbe-adapter"
				(path ""
					(reference "C188")
					(unit 1)
				)
			)
		)
	)
	(symbol
		(lib_id "antmicroCapacitorsmisc:C_100u_0805")
		(at 88.9 180.34 90)
		(unit 1)
		(exclude_from_sim no)
		(in_bom yes)
		(on_board yes)
		(dnp no)
		(property "Reference" "C171"
			(at 90.678 176.53 90)
			(effects
				(font
					(size 1.27 1.27)
					(thickness 0.15)
				)
				(justify right)
			)
		)
		(property "Value" "C_100u_0805"
			(at 99.06 160.02 0)
			(effects
				(font
					(size 1.27 1.27)
					(thickness 0.15)
				)
				(justify left bottom)
				(hide yes)
			)
		)
		(property "Footprint" "antmicro-footprints:C_0805_2012Metric"
			(at 101.6 160.02 0)
			(effects
				(font
					(size 1.27 1.27)
					(thickness 0.15)
				)
				(justify left bottom)
				(hide yes)
			)
		)
		(property "Datasheet" "https://www.murata.com/products/productdetail?partno=GRM21BR60J107ME15%23"
			(at 104.14 160.02 0)
			(effects
				(font
					(size 1.27 1.27)
					(thickness 0.15)
				)
				(justify left bottom)
				(hide yes)
			)
		)
		(property "Description" "SMD Multilayer Ceramic Capacitor, 100 µF, 6.3 V, 0805 [2012 Metric], ± 20%, X5R, GRM Series"
			(at 88.9 180.34 0)
			(effects
				(font
					(size 1.27 1.27)
				)
				(hide yes)
			)
		)
		(property "MPN" "GRM21BR60J107ME15L"
			(at 106.68 160.02 0)
			(effects
				(font
					(size 1.27 1.27)
					(thickness 0.15)
				)
				(justify left bottom)
				(hide yes)
			)
		)
		(property "Manufacturer" "Murata"
			(at 109.22 160.02 0)
			(effects
				(font
					(size 1.27 1.27)
					(thickness 0.15)
				)
				(justify left bottom)
				(hide yes)
			)
		)
		(property "License" "Apache-2.0"
			(at 111.76 160.02 0)
			(effects
				(font
					(size 1.27 1.27)
					(thickness 0.15)
				)
				(justify left bottom)
				(hide yes)
			)
		)
		(property "Author" "Antmicro"
			(at 114.3 160.02 0)
			(effects
				(font
					(size 1.27 1.27)
					(thickness 0.15)
				)
				(justify left bottom)
				(hide yes)
			)
		)
		(property "Val" "100u"
			(at 90.678 179.07 90)
			(effects
				(font
					(size 1.27 1.27)
					(thickness 0.15)
				)
				(justify right)
			)
		)
		(property "Voltage" ""
			(at 116.84 160.02 0)
			(effects
				(font
					(size 1.27 1.27)
				)
				(justify left bottom)
				(hide yes)
			)
		)
		(property "Dielectric" ""
			(at 119.38 160.02 0)
			(effects
				(font
					(size 1.27 1.27)
				)
				(justify left bottom)
				(hide yes)
			)
		)
		(property "Public" "False"
			(at 121.92 160.02 0)
			(effects
				(font
					(size 1.27 1.27)
				)
				(justify left bottom)
				(hide yes)
			)
		)
		(pin "1"
		)
		(pin "2"
		)
		(instances
			(project "OCuLink to 10GbE adapter"
				(path ""
					(reference "C172")
					(unit 1)
				)
			)
			(project "thunderbolt-to-10gbe-adapter"
				(path ""
					(reference "C171")
					(unit 1)
				)
			)
		)
	)
	(symbol
		(lib_id "antmicroCapacitors0402:C_1u_25V_0402")
		(at 388.62 73.66 90)
		(unit 1)
		(exclude_from_sim no)
		(in_bom yes)
		(on_board yes)
		(dnp no)
		(property "Reference" "C260"
			(at 390.652 69.85 90)
			(effects
				(font
					(size 1.27 1.27)
					(thickness 0.15)
				)
				(justify right)
			)
		)
		(property "Value" "C_1u_25V_0402"
			(at 398.78 53.34 0)
			(effects
				(font
					(size 1.27 1.27)
					(thickness 0.15)
				)
				(justify left bottom)
				(hide yes)
			)
		)
		(property "Footprint" "antmicro-footprints:C_0402_1005Metric"
			(at 401.32 53.34 0)
			(effects
				(font
					(size 1.27 1.27)
					(thickness 0.15)
				)
				(justify left bottom)
				(hide yes)
			)
		)
		(property "Datasheet" "https://www.murata.com/products/productdetail?partno=GRM155R61E105KE11%23"
			(at 403.86 53.34 0)
			(effects
				(font
					(size 1.27 1.27)
					(thickness 0.15)
				)
				(justify left bottom)
				(hide yes)
			)
		)
		(property "Description" "SMD Multilayer Ceramic Capacitor, 1 µF, 25 V, 0402 [1005 Metric], ± 10%, X5R, GRM Series"
			(at 388.62 73.66 0)
			(effects
				(font
					(size 1.27 1.27)
				)
				(hide yes)
			)
		)
		(property "MPN" "GRM155R61E105KE11J"
			(at 406.4 53.34 0)
			(effects
				(font
					(size 1.27 1.27)
					(thickness 0.15)
				)
				(justify left bottom)
				(hide yes)
			)
		)
		(property "Manufacturer" "Murata"
			(at 408.94 53.34 0)
			(effects
				(font
					(size 1.27 1.27)
					(thickness 0.15)
				)
				(justify left bottom)
				(hide yes)
			)
		)
		(property "License" "Apache-2.0"
			(at 411.48 53.34 0)
			(effects
				(font
					(size 1.27 1.27)
					(thickness 0.15)
				)
				(justify left bottom)
				(hide yes)
			)
		)
		(property "Author" "Antmicro"
			(at 414.02 53.34 0)
			(effects
				(font
					(size 1.27 1.27)
					(thickness 0.15)
				)
				(justify left bottom)
				(hide yes)
			)
		)
		(property "Val" "1u"
			(at 390.652 72.39 90)
			(effects
				(font
					(size 1.27 1.27)
					(thickness 0.15)
				)
				(justify right)
			)
		)
		(property "Voltage" "25V"
			(at 416.56 53.34 0)
			(effects
				(font
					(size 1.27 1.27)
				)
				(justify left bottom)
				(hide yes)
			)
		)
		(property "Dielectric" "X5R"
			(at 419.1 53.34 0)
			(effects
				(font
					(size 1.27 1.27)
				)
				(justify left bottom)
				(hide yes)
			)
		)
		(pin "2"
		)
		(pin "1"
		)
		(instances
			(project "OCuLink to 10GbE adapter"
				(path ""
					(reference "C115")
					(unit 1)
				)
			)
			(project "thunderbolt-to-10gbe-adapter"
				(path ""
					(reference "C260")
					(unit 1)
				)
			)
		)
	)
	(symbol
		(lib_id "antmicropower:GND")
		(at 379.73 76.2 0)
		(unit 1)
		(exclude_from_sim no)
		(in_bom yes)
		(on_board yes)
		(dnp no)
		(property "Reference" "#PWR0342"
			(at 388.62 78.74 0)
			(effects
				(font
					(size 1.27 1.27)
					(thickness 0.15)
				)
				(justify left bottom)
				(hide yes)
			)
		)
		(property "Value" "GND"
			(at 379.73 80.01 0)
			(effects
				(font
					(size 1.27 1.27)
					(thickness 0.15)
				)
			)
		)
		(property "Footprint" ""
			(at 388.62 83.82 0)
			(effects
				(font
					(size 1.27 1.27)
					(thickness 0.15)
				)
				(justify left bottom)
				(hide yes)
			)
		)
		(property "Datasheet" ""
			(at 388.62 88.9 0)
			(effects
				(font
					(size 1.27 1.27)
					(thickness 0.15)
				)
				(justify left bottom)
				(hide yes)
			)
		)
		(property "Description" ""
			(at 379.73 76.2 0)
			(effects
				(font
					(size 1.27 1.27)
				)
				(hide yes)
			)
		)
		(property "Author" "Antmicro"
			(at 388.62 83.82 0)
			(effects
				(font
					(size 1.27 1.27)
					(thickness 0.15)
				)
				(justify left bottom)
				(hide yes)
			)
		)
		(property "License" "Apache-2.0"
			(at 388.62 86.36 0)
			(effects
				(font
					(size 1.27 1.27)
					(thickness 0.15)
				)
				(justify left bottom)
				(hide yes)
			)
		)
		(pin "1"
		)
		(instances
			(project "OCuLink to 10GbE adapter"
				(path ""
					(reference "#PWR0148")
					(unit 1)
				)
			)
			(project "thunderbolt-to-10gbe-adapter"
				(path ""
					(reference "#PWR0342")
					(unit 1)
				)
			)
		)
	)
	(symbol
		(lib_id "antmicropower:GND")
		(at 133.35 76.2 0)
		(unit 1)
		(exclude_from_sim no)
		(in_bom yes)
		(on_board yes)
		(dnp no)
		(property "Reference" "#PWR0262"
			(at 142.24 78.74 0)
			(effects
				(font
					(size 1.27 1.27)
					(thickness 0.15)
				)
				(justify left bottom)
				(hide yes)
			)
		)
		(property "Value" "GND"
			(at 133.35 80.01 0)
			(effects
				(font
					(size 1.27 1.27)
					(thickness 0.15)
				)
			)
		)
		(property "Footprint" ""
			(at 142.24 83.82 0)
			(effects
				(font
					(size 1.27 1.27)
					(thickness 0.15)
				)
				(justify left bottom)
				(hide yes)
			)
		)
		(property "Datasheet" ""
			(at 142.24 88.9 0)
			(effects
				(font
					(size 1.27 1.27)
					(thickness 0.15)
				)
				(justify left bottom)
				(hide yes)
			)
		)
		(property "Description" ""
			(at 133.35 76.2 0)
			(effects
				(font
					(size 1.27 1.27)
				)
				(hide yes)
			)
		)
		(property "Author" "Antmicro"
			(at 142.24 83.82 0)
			(effects
				(font
					(size 1.27 1.27)
					(thickness 0.15)
				)
				(justify left bottom)
				(hide yes)
			)
		)
		(property "License" "Apache-2.0"
			(at 142.24 86.36 0)
			(effects
				(font
					(size 1.27 1.27)
					(thickness 0.15)
				)
				(justify left bottom)
				(hide yes)
			)
		)
		(pin "1"
		)
		(instances
			(project "OCuLink to 10GbE adapter"
				(path ""
					(reference "#PWR0136")
					(unit 1)
				)
			)
			(project "thunderbolt-to-10gbe-adapter"
				(path ""
					(reference "#PWR0262")
					(unit 1)
				)
			)
		)
	)
	(symbol
		(lib_id "antmicropower:PWR_FLAG")
		(at 289.56 139.7 0)
		(unit 1)
		(exclude_from_sim no)
		(in_bom yes)
		(on_board yes)
		(dnp no)
		(property "Reference" "#FLG031"
			(at 289.56 137.795 0)
			(effects
				(font
					(size 1.27 1.27)
				)
				(hide yes)
			)
		)
		(property "Value" "PWR_FLAG"
			(at 289.56 135.89 0)
			(effects
				(font
					(size 1.27 1.27)
				)
			)
		)
		(property "Footprint" ""
			(at 289.56 139.7 0)
			(effects
				(font
					(size 1.27 1.27)
				)
				(hide yes)
			)
		)
		(property "Datasheet" ""
			(at 289.56 139.7 0)
			(effects
				(font
					(size 1.27 1.27)
				)
				(hide yes)
			)
		)
		(property "Description" ""
			(at 289.56 139.7 0)
			(effects
				(font
					(size 1.27 1.27)
				)
				(hide yes)
			)
		)
		(pin "1"
		)
		(instances
			(project "OCuLink to 10GbE adapter"
				(path ""
					(reference "#FLG014")
					(unit 1)
				)
			)
			(project "thunderbolt-to-10gbe-adapter"
				(path ""
					(reference "#FLG031")
					(unit 1)
				)
			)
		)
	)
	(symbol
		(lib_id "antmicroCapacitorspol:C_Pol_100u_6V_KEMET-T490-A")
		(at 46.99 46.99 90)
		(mirror x)
		(unit 1)
		(exclude_from_sim no)
		(in_bom yes)
		(on_board yes)
		(dnp no)
		(fields_autoplaced yes)
		(property "Reference" "C330"
			(at 44.45 47.7266 90)
			(effects
				(font
					(size 1.27 1.27)
					(thickness 0.15)
				)
				(justify left)
			)
		)
		(property "Value" "C_Pol_100u_6V_KEMET-T490-A"
			(at 49.53 60.96 0)
			(effects
				(font
					(size 1.27 1.27)
					(thickness 0.15)
				)
				(justify left bottom)
				(hide yes)
			)
		)
		(property "Footprint" "antmicro-footprints:C_Pol_EIA-A"
			(at 54.61 60.96 0)
			(effects
				(font
					(size 1.27 1.27)
					(thickness 0.15)
				)
				(justify left bottom)
				(hide yes)
			)
		)
		(property "Datasheet" "https://www.kemet.com/en/us/capacitors/product/T490A107M006ATE800.html"
			(at 57.15 60.96 0)
			(effects
				(font
					(size 1.27 1.27)
					(thickness 0.15)
				)
				(justify left bottom)
				(hide yes)
			)
		)
		(property "Description" "Surface Mount Tantalum Capacitor,  Solid SMD 6V 100uF 1206 20% ESR=800mOhms"
			(at 72.39 60.96 0)
			(effects
				(font
					(size 1.27 1.27)
				)
				(justify left bottom)
				(hide yes)
			)
		)
		(property "Val" "100u"
			(at 44.45 50.2666 90)
			(effects
				(font
					(size 1.27 1.27)
					(thickness 0.15)
				)
				(justify left)
			)
		)
		(property "MPN" "T490A107M006ATE800"
			(at 59.69 60.96 0)
			(effects
				(font
					(size 1.27 1.27)
					(thickness 0.15)
				)
				(justify left bottom)
				(hide yes)
			)
		)
		(property "Manufacturer" "KEMET"
			(at 62.23 60.96 0)
			(effects
				(font
					(size 1.27 1.27)
					(thickness 0.15)
				)
				(justify left bottom)
				(hide yes)
			)
		)
		(property "License" "Apache-2.0"
			(at 64.77 60.96 0)
			(effects
				(font
					(size 1.27 1.27)
					(thickness 0.15)
				)
				(justify left bottom)
				(hide yes)
			)
		)
		(property "Author" "Antmicro"
			(at 67.31 60.96 0)
			(effects
				(font
					(size 1.27 1.27)
					(thickness 0.15)
				)
				(justify left bottom)
				(hide yes)
			)
		)
		(property "Voltage" "6V"
			(at 69.85 60.96 0)
			(effects
				(font
					(size 1.27 1.27)
				)
				(justify left bottom)
				(hide yes)
			)
		)
		(property "Dielectric" "template_dielectric"
			(at 72.39 60.96 0)
			(effects
				(font
					(size 1.27 1.27)
				)
				(justify left bottom)
				(hide yes)
			)
		)
		(pin "2"
		)
		(pin "1"
		)
		(instances
			(project "thunderbolt-to-10gbe-adapter"
				(path ""
					(reference "C330")
					(unit 1)
				)
			)
		)
	)
	(symbol
		(lib_id "antmicropower:GND")
		(at 97.79 76.2 0)
		(unit 1)
		(exclude_from_sim no)
		(in_bom yes)
		(on_board yes)
		(dnp no)
		(property "Reference" "#PWR0247"
			(at 106.68 78.74 0)
			(effects
				(font
					(size 1.27 1.27)
					(thickness 0.15)
				)
				(justify left bottom)
				(hide yes)
			)
		)
		(property "Value" "GND"
			(at 97.79 80.01 0)
			(effects
				(font
					(size 1.27 1.27)
					(thickness 0.15)
				)
			)
		)
		(property "Footprint" ""
			(at 106.68 83.82 0)
			(effects
				(font
					(size 1.27 1.27)
					(thickness 0.15)
				)
				(justify left bottom)
				(hide yes)
			)
		)
		(property "Datasheet" ""
			(at 106.68 88.9 0)
			(effects
				(font
					(size 1.27 1.27)
					(thickness 0.15)
				)
				(justify left bottom)
				(hide yes)
			)
		)
		(property "Description" ""
			(at 97.79 76.2 0)
			(effects
				(font
					(size 1.27 1.27)
				)
				(hide yes)
			)
		)
		(property "Author" "Antmicro"
			(at 106.68 83.82 0)
			(effects
				(font
					(size 1.27 1.27)
					(thickness 0.15)
				)
				(justify left bottom)
				(hide yes)
			)
		)
		(property "License" "Apache-2.0"
			(at 106.68 86.36 0)
			(effects
				(font
					(size 1.27 1.27)
					(thickness 0.15)
				)
				(justify left bottom)
				(hide yes)
			)
		)
		(pin "1"
		)
		(instances
			(project "OCuLink to 10GbE adapter"
				(path ""
					(reference "#PWR0134")
					(unit 1)
				)
			)
			(project "thunderbolt-to-10gbe-adapter"
				(path ""
					(reference "#PWR0247")
					(unit 1)
				)
			)
		)
	)
	(symbol
		(lib_id "antmicroCapacitors0402:C_1u_25V_0402")
		(at 142.24 73.66 90)
		(unit 1)
		(exclude_from_sim no)
		(in_bom yes)
		(on_board yes)
		(dnp no)
		(property "Reference" "C197"
			(at 144.272 69.85 90)
			(effects
				(font
					(size 1.27 1.27)
					(thickness 0.15)
				)
				(justify right)
			)
		)
		(property "Value" "C_1u_25V_0402"
			(at 152.4 53.34 0)
			(effects
				(font
					(size 1.27 1.27)
					(thickness 0.15)
				)
				(justify left bottom)
				(hide yes)
			)
		)
		(property "Footprint" "antmicro-footprints:C_0402_1005Metric"
			(at 154.94 53.34 0)
			(effects
				(font
					(size 1.27 1.27)
					(thickness 0.15)
				)
				(justify left bottom)
				(hide yes)
			)
		)
		(property "Datasheet" "https://www.murata.com/products/productdetail?partno=GRM155R61E105KE11%23"
			(at 157.48 53.34 0)
			(effects
				(font
					(size 1.27 1.27)
					(thickness 0.15)
				)
				(justify left bottom)
				(hide yes)
			)
		)
		(property "Description" "SMD Multilayer Ceramic Capacitor, 1 µF, 25 V, 0402 [1005 Metric], ± 10%, X5R, GRM Series"
			(at 142.24 73.66 0)
			(effects
				(font
					(size 1.27 1.27)
				)
				(hide yes)
			)
		)
		(property "MPN" "GRM155R61E105KE11J"
			(at 160.02 53.34 0)
			(effects
				(font
					(size 1.27 1.27)
					(thickness 0.15)
				)
				(justify left bottom)
				(hide yes)
			)
		)
		(property "Manufacturer" "Murata"
			(at 162.56 53.34 0)
			(effects
				(font
					(size 1.27 1.27)
					(thickness 0.15)
				)
				(justify left bottom)
				(hide yes)
			)
		)
		(property "License" "Apache-2.0"
			(at 165.1 53.34 0)
			(effects
				(font
					(size 1.27 1.27)
					(thickness 0.15)
				)
				(justify left bottom)
				(hide yes)
			)
		)
		(property "Author" "Antmicro"
			(at 167.64 53.34 0)
			(effects
				(font
					(size 1.27 1.27)
					(thickness 0.15)
				)
				(justify left bottom)
				(hide yes)
			)
		)
		(property "Val" "1u"
			(at 144.272 72.39 90)
			(effects
				(font
					(size 1.27 1.27)
					(thickness 0.15)
				)
				(justify right)
			)
		)
		(property "Voltage" "25V"
			(at 170.18 53.34 0)
			(effects
				(font
					(size 1.27 1.27)
				)
				(justify left bottom)
				(hide yes)
			)
		)
		(property "Dielectric" "X5R"
			(at 172.72 53.34 0)
			(effects
				(font
					(size 1.27 1.27)
				)
				(justify left bottom)
				(hide yes)
			)
		)
		(pin "2"
		)
		(pin "1"
		)
		(instances
			(project "OCuLink to 10GbE adapter"
				(path ""
					(reference "C103")
					(unit 1)
				)
			)
			(project "thunderbolt-to-10gbe-adapter"
				(path ""
					(reference "C197")
					(unit 1)
				)
			)
		)
	)
	(symbol
		(lib_id "antmicropower:GND")
		(at 388.62 93.98 0)
		(unit 1)
		(exclude_from_sim no)
		(in_bom yes)
		(on_board yes)
		(dnp no)
		(property "Reference" "#PWR0347"
			(at 397.51 96.52 0)
			(effects
				(font
					(size 1.27 1.27)
					(thickness 0.15)
				)
				(justify left bottom)
				(hide yes)
			)
		)
		(property "Value" "GND"
			(at 388.62 97.79 0)
			(effects
				(font
					(size 1.27 1.27)
					(thickness 0.15)
				)
			)
		)
		(property "Footprint" ""
			(at 397.51 101.6 0)
			(effects
				(font
					(size 1.27 1.27)
					(thickness 0.15)
				)
				(justify left bottom)
				(hide yes)
			)
		)
		(property "Datasheet" ""
			(at 397.51 106.68 0)
			(effects
				(font
					(size 1.27 1.27)
					(thickness 0.15)
				)
				(justify left bottom)
				(hide yes)
			)
		)
		(property "Description" ""
			(at 388.62 93.98 0)
			(effects
				(font
					(size 1.27 1.27)
				)
				(hide yes)
			)
		)
		(property "Author" "Antmicro"
			(at 397.51 101.6 0)
			(effects
				(font
					(size 1.27 1.27)
					(thickness 0.15)
				)
				(justify left bottom)
				(hide yes)
			)
		)
		(property "License" "Apache-2.0"
			(at 397.51 104.14 0)
			(effects
				(font
					(size 1.27 1.27)
					(thickness 0.15)
				)
				(justify left bottom)
				(hide yes)
			)
		)
		(pin "1"
		)
		(instances
			(project "OCuLink to 10GbE adapter"
				(path ""
					(reference "#PWR0173")
					(unit 1)
				)
			)
			(project "thunderbolt-to-10gbe-adapter"
				(path ""
					(reference "#PWR0347")
					(unit 1)
				)
			)
		)
	)
	(symbol
		(lib_id "antmicroCapacitors0402:C_1u_25V_0402")
		(at 308.61 73.66 90)
		(unit 1)
		(exclude_from_sim no)
		(in_bom yes)
		(on_board yes)
		(dnp no)
		(property "Reference" "C218"
			(at 310.642 69.85 90)
			(effects
				(font
					(size 1.27 1.27)
					(thickness 0.15)
				)
				(justify right)
			)
		)
		(property "Value" "C_1u_25V_0402"
			(at 318.77 53.34 0)
			(effects
				(font
					(size 1.27 1.27)
					(thickness 0.15)
				)
				(justify left bottom)
				(hide yes)
			)
		)
		(property "Footprint" "antmicro-footprints:C_0402_1005Metric"
			(at 321.31 53.34 0)
			(effects
				(font
					(size 1.27 1.27)
					(thickness 0.15)
				)
				(justify left bottom)
				(hide yes)
			)
		)
		(property "Datasheet" "https://www.murata.com/products/productdetail?partno=GRM155R61E105KE11%23"
			(at 323.85 53.34 0)
			(effects
				(font
					(size 1.27 1.27)
					(thickness 0.15)
				)
				(justify left bottom)
				(hide yes)
			)
		)
		(property "Description" "SMD Multilayer Ceramic Capacitor, 1 µF, 25 V, 0402 [1005 Metric], ± 10%, X5R, GRM Series"
			(at 308.61 73.66 0)
			(effects
				(font
					(size 1.27 1.27)
				)
				(hide yes)
			)
		)
		(property "MPN" "GRM155R61E105KE11J"
			(at 326.39 53.34 0)
			(effects
				(font
					(size 1.27 1.27)
					(thickness 0.15)
				)
				(justify left bottom)
				(hide yes)
			)
		)
		(property "Manufacturer" "Murata"
			(at 328.93 53.34 0)
			(effects
				(font
					(size 1.27 1.27)
					(thickness 0.15)
				)
				(justify left bottom)
				(hide yes)
			)
		)
		(property "License" "Apache-2.0"
			(at 331.47 53.34 0)
			(effects
				(font
					(size 1.27 1.27)
					(thickness 0.15)
				)
				(justify left bottom)
				(hide yes)
			)
		)
		(property "Author" "Antmicro"
			(at 334.01 53.34 0)
			(effects
				(font
					(size 1.27 1.27)
					(thickness 0.15)
				)
				(justify left bottom)
				(hide yes)
			)
		)
		(property "Val" "1u"
			(at 310.642 72.39 90)
			(effects
				(font
					(size 1.27 1.27)
					(thickness 0.15)
				)
				(justify right)
			)
		)
		(property "Voltage" "25V"
			(at 336.55 53.34 0)
			(effects
				(font
					(size 1.27 1.27)
				)
				(justify left bottom)
				(hide yes)
			)
		)
		(property "Dielectric" "X5R"
			(at 339.09 53.34 0)
			(effects
				(font
					(size 1.27 1.27)
				)
				(justify left bottom)
				(hide yes)
			)
		)
		(pin "2"
		)
		(pin "1"
		)
		(instances
			(project "OCuLink to 10GbE adapter"
				(path ""
					(reference "C106")
					(unit 1)
				)
			)
			(project "thunderbolt-to-10gbe-adapter"
				(path ""
					(reference "C218")
					(unit 1)
				)
			)
		)
	)
	(symbol
		(lib_id "antmicropower:GND")
		(at 270.51 152.4 0)
		(unit 1)
		(exclude_from_sim no)
		(in_bom yes)
		(on_board yes)
		(dnp no)
		(property "Reference" "#PWR0291"
			(at 279.4 154.94 0)
			(effects
				(font
					(size 1.27 1.27)
					(thickness 0.15)
				)
				(justify left bottom)
				(hide yes)
			)
		)
		(property "Value" "GND"
			(at 270.51 156.21 0)
			(effects
				(font
					(size 1.27 1.27)
					(thickness 0.15)
				)
			)
		)
		(property "Footprint" ""
			(at 279.4 160.02 0)
			(effects
				(font
					(size 1.27 1.27)
					(thickness 0.15)
				)
				(justify left bottom)
				(hide yes)
			)
		)
		(property "Datasheet" ""
			(at 279.4 165.1 0)
			(effects
				(font
					(size 1.27 1.27)
					(thickness 0.15)
				)
				(justify left bottom)
				(hide yes)
			)
		)
		(property "Description" ""
			(at 270.51 152.4 0)
			(effects
				(font
					(size 1.27 1.27)
				)
				(hide yes)
			)
		)
		(property "Author" "Antmicro"
			(at 279.4 160.02 0)
			(effects
				(font
					(size 1.27 1.27)
					(thickness 0.15)
				)
				(justify left bottom)
				(hide yes)
			)
		)
		(property "License" "Apache-2.0"
			(at 279.4 162.56 0)
			(effects
				(font
					(size 1.27 1.27)
					(thickness 0.15)
				)
				(justify left bottom)
				(hide yes)
			)
		)
		(pin "1"
		)
		(instances
			(project "OCuLink to 10GbE adapter"
				(path ""
					(reference "#PWR0206")
					(unit 1)
				)
			)
			(project "thunderbolt-to-10gbe-adapter"
				(path ""
					(reference "#PWR0291")
					(unit 1)
				)
			)
		)
	)
	(symbol
		(lib_id "antmicroCapacitors0402:C_1u_25V_0402")
		(at 142.24 207.01 90)
		(unit 1)
		(exclude_from_sim no)
		(in_bom yes)
		(on_board yes)
		(dnp no)
		(property "Reference" "C201"
			(at 144.272 203.2 90)
			(effects
				(font
					(size 1.27 1.27)
					(thickness 0.15)
				)
				(justify right)
			)
		)
		(property "Value" "C_1u_25V_0402"
			(at 152.4 186.69 0)
			(effects
				(font
					(size 1.27 1.27)
					(thickness 0.15)
				)
				(justify left bottom)
				(hide yes)
			)
		)
		(property "Footprint" "antmicro-footprints:C_0402_1005Metric"
			(at 154.94 186.69 0)
			(effects
				(font
					(size 1.27 1.27)
					(thickness 0.15)
				)
				(justify left bottom)
				(hide yes)
			)
		)
		(property "Datasheet" "https://www.murata.com/products/productdetail?partno=GRM155R61E105KE11%23"
			(at 157.48 186.69 0)
			(effects
				(font
					(size 1.27 1.27)
					(thickness 0.15)
				)
				(justify left bottom)
				(hide yes)
			)
		)
		(property "Description" "SMD Multilayer Ceramic Capacitor, 1 µF, 25 V, 0402 [1005 Metric], ± 10%, X5R, GRM Series"
			(at 142.24 207.01 0)
			(effects
				(font
					(size 1.27 1.27)
				)
				(hide yes)
			)
		)
		(property "MPN" "GRM155R61E105KE11J"
			(at 160.02 186.69 0)
			(effects
				(font
					(size 1.27 1.27)
					(thickness 0.15)
				)
				(justify left bottom)
				(hide yes)
			)
		)
		(property "Manufacturer" "Murata"
			(at 162.56 186.69 0)
			(effects
				(font
					(size 1.27 1.27)
					(thickness 0.15)
				)
				(justify left bottom)
				(hide yes)
			)
		)
		(property "License" "Apache-2.0"
			(at 165.1 186.69 0)
			(effects
				(font
					(size 1.27 1.27)
					(thickness 0.15)
				)
				(justify left bottom)
				(hide yes)
			)
		)
		(property "Author" "Antmicro"
			(at 167.64 186.69 0)
			(effects
				(font
					(size 1.27 1.27)
					(thickness 0.15)
				)
				(justify left bottom)
				(hide yes)
			)
		)
		(property "Val" "1u"
			(at 144.272 205.74 90)
			(effects
				(font
					(size 1.27 1.27)
					(thickness 0.15)
				)
				(justify right)
			)
		)
		(property "Voltage" "25V"
			(at 170.18 186.69 0)
			(effects
				(font
					(size 1.27 1.27)
				)
				(justify left bottom)
				(hide yes)
			)
		)
		(property "Dielectric" "X5R"
			(at 172.72 186.69 0)
			(effects
				(font
					(size 1.27 1.27)
				)
				(justify left bottom)
				(hide yes)
			)
		)
		(pin "2"
		)
		(pin "1"
		)
		(instances
			(project "OCuLink to 10GbE adapter"
				(path ""
					(reference "C183")
					(unit 1)
				)
			)
			(project "thunderbolt-to-10gbe-adapter"
				(path ""
					(reference "C201")
					(unit 1)
				)
			)
		)
	)
	(symbol
		(lib_id "antmicroCapacitors0402:C_1u_25V_0402")
		(at 142.24 52.07 90)
		(unit 1)
		(exclude_from_sim no)
		(in_bom yes)
		(on_board yes)
		(dnp no)
		(property "Reference" "C196"
			(at 144.272 48.26 90)
			(effects
				(font
					(size 1.27 1.27)
					(thickness 0.15)
				)
				(justify right)
			)
		)
		(property "Value" "C_1u_25V_0402"
			(at 152.4 31.75 0)
			(effects
				(font
					(size 1.27 1.27)
					(thickness 0.15)
				)
				(justify left bottom)
				(hide yes)
			)
		)
		(property "Footprint" "antmicro-footprints:C_0402_1005Metric"
			(at 154.94 31.75 0)
			(effects
				(font
					(size 1.27 1.27)
					(thickness 0.15)
				)
				(justify left bottom)
				(hide yes)
			)
		)
		(property "Datasheet" "https://www.murata.com/products/productdetail?partno=GRM155R61E105KE11%23"
			(at 157.48 31.75 0)
			(effects
				(font
					(size 1.27 1.27)
					(thickness 0.15)
				)
				(justify left bottom)
				(hide yes)
			)
		)
		(property "Description" "SMD Multilayer Ceramic Capacitor, 1 µF, 25 V, 0402 [1005 Metric], ± 10%, X5R, GRM Series"
			(at 142.24 52.07 0)
			(effects
				(font
					(size 1.27 1.27)
				)
				(hide yes)
			)
		)
		(property "MPN" "GRM155R61E105KE11J"
			(at 160.02 31.75 0)
			(effects
				(font
					(size 1.27 1.27)
					(thickness 0.15)
				)
				(justify left bottom)
				(hide yes)
			)
		)
		(property "Manufacturer" "Murata"
			(at 162.56 31.75 0)
			(effects
				(font
					(size 1.27 1.27)
					(thickness 0.15)
				)
				(justify left bottom)
				(hide yes)
			)
		)
		(property "License" "Apache-2.0"
			(at 165.1 31.75 0)
			(effects
				(font
					(size 1.27 1.27)
					(thickness 0.15)
				)
				(justify left bottom)
				(hide yes)
			)
		)
		(property "Author" "Antmicro"
			(at 167.64 31.75 0)
			(effects
				(font
					(size 1.27 1.27)
					(thickness 0.15)
				)
				(justify left bottom)
				(hide yes)
			)
		)
		(property "Val" "1u"
			(at 144.272 50.8 90)
			(effects
				(font
					(size 1.27 1.27)
					(thickness 0.15)
				)
				(justify right)
			)
		)
		(property "Voltage" "25V"
			(at 170.18 31.75 0)
			(effects
				(font
					(size 1.27 1.27)
				)
				(justify left bottom)
				(hide yes)
			)
		)
		(property "Dielectric" "X5R"
			(at 172.72 31.75 0)
			(effects
				(font
					(size 1.27 1.27)
				)
				(justify left bottom)
				(hide yes)
			)
		)
		(pin "2"
		)
		(pin "1"
		)
		(instances
			(project "OCuLink to 10GbE adapter"
				(path ""
					(reference "C85")
					(unit 1)
				)
			)
			(project "thunderbolt-to-10gbe-adapter"
				(path ""
					(reference "C196")
					(unit 1)
				)
			)
		)
	)
	(symbol
		(lib_id "antmicropower:GND")
		(at 115.57 156.21 0)
		(unit 1)
		(exclude_from_sim no)
		(in_bom yes)
		(on_board yes)
		(dnp no)
		(property "Reference" "#PWR0251"
			(at 124.46 158.75 0)
			(effects
				(font
					(size 1.27 1.27)
					(thickness 0.15)
				)
				(justify left bottom)
				(hide yes)
			)
		)
		(property "Value" "GND"
			(at 115.57 160.02 0)
			(effects
				(font
					(size 1.27 1.27)
					(thickness 0.15)
				)
			)
		)
		(property "Footprint" ""
			(at 124.46 163.83 0)
			(effects
				(font
					(size 1.27 1.27)
					(thickness 0.15)
				)
				(justify left bottom)
				(hide yes)
			)
		)
		(property "Datasheet" ""
			(at 124.46 168.91 0)
			(effects
				(font
					(size 1.27 1.27)
					(thickness 0.15)
				)
				(justify left bottom)
				(hide yes)
			)
		)
		(property "Description" ""
			(at 115.57 156.21 0)
			(effects
				(font
					(size 1.27 1.27)
				)
				(hide yes)
			)
		)
		(property "Author" "Antmicro"
			(at 124.46 163.83 0)
			(effects
				(font
					(size 1.27 1.27)
					(thickness 0.15)
				)
				(justify left bottom)
				(hide yes)
			)
		)
		(property "License" "Apache-2.0"
			(at 124.46 166.37 0)
			(effects
				(font
					(size 1.27 1.27)
					(thickness 0.15)
				)
				(justify left bottom)
				(hide yes)
			)
		)
		(pin "1"
		)
		(instances
			(project "OCuLink to 10GbE adapter"
				(path ""
					(reference "#PWR0216")
					(unit 1)
				)
			)
			(project "thunderbolt-to-10gbe-adapter"
				(path ""
					(reference "#PWR0251")
					(unit 1)
				)
			)
		)
	)
	(symbol
		(lib_id "antmicropower:GND")
		(at 353.06 54.61 0)
		(unit 1)
		(exclude_from_sim no)
		(in_bom yes)
		(on_board yes)
		(dnp no)
		(property "Reference" "#PWR0326"
			(at 361.95 57.15 0)
			(effects
				(font
					(size 1.27 1.27)
					(thickness 0.15)
				)
				(justify left bottom)
				(hide yes)
			)
		)
		(property "Value" "GND"
			(at 353.06 58.42 0)
			(effects
				(font
					(size 1.27 1.27)
					(thickness 0.15)
				)
			)
		)
		(property "Footprint" ""
			(at 361.95 62.23 0)
			(effects
				(font
					(size 1.27 1.27)
					(thickness 0.15)
				)
				(justify left bottom)
				(hide yes)
			)
		)
		(property "Datasheet" ""
			(at 361.95 67.31 0)
			(effects
				(font
					(size 1.27 1.27)
					(thickness 0.15)
				)
				(justify left bottom)
				(hide yes)
			)
		)
		(property "Description" ""
			(at 353.06 54.61 0)
			(effects
				(font
					(size 1.27 1.27)
				)
				(hide yes)
			)
		)
		(property "Author" "Antmicro"
			(at 361.95 62.23 0)
			(effects
				(font
					(size 1.27 1.27)
					(thickness 0.15)
				)
				(justify left bottom)
				(hide yes)
			)
		)
		(property "License" "Apache-2.0"
			(at 361.95 64.77 0)
			(effects
				(font
					(size 1.27 1.27)
					(thickness 0.15)
				)
				(justify left bottom)
				(hide yes)
			)
		)
		(pin "1"
		)
		(instances
			(project "OCuLink to 10GbE adapter"
				(path ""
					(reference "#PWR0127")
					(unit 1)
				)
			)
			(project "thunderbolt-to-10gbe-adapter"
				(path ""
					(reference "#PWR0326")
					(unit 1)
				)
			)
		)
	)
	(symbol
		(lib_id "antmicroCapacitors0603:C_22u_16V_0603")
		(at 388.62 91.44 90)
		(unit 1)
		(exclude_from_sim no)
		(in_bom yes)
		(on_board yes)
		(dnp no)
		(fields_autoplaced yes)
		(property "Reference" "C261"
			(at 391.16 87.6236 90)
			(effects
				(font
					(size 1.27 1.27)
					(thickness 0.15)
				)
				(justify right)
			)
		)
		(property "Value" "C_22u_16V_0603"
			(at 398.78 71.12 0)
			(effects
				(font
					(size 1.27 1.27)
					(thickness 0.15)
				)
				(justify left bottom)
				(hide yes)
			)
		)
		(property "Footprint" "antmicro-footprints:C_0603_1608Metric_EIA"
			(at 401.32 71.12 0)
			(effects
				(font
					(size 1.27 1.27)
					(thickness 0.15)
				)
				(justify left bottom)
				(hide yes)
			)
		)
		(property "Datasheet" "https://product.samsungsem.com/mlcc/CL10A226MO7JZN.do"
			(at 403.86 71.12 0)
			(effects
				(font
					(size 1.27 1.27)
					(thickness 0.15)
				)
				(justify left bottom)
				(hide yes)
			)
		)
		(property "Description" "SMD Multilayer Ceramic Capacitor"
			(at 388.62 91.44 0)
			(effects
				(font
					(size 1.27 1.27)
				)
				(hide yes)
			)
		)
		(property "MPN" "CL10A226MO7JZNC"
			(at 406.4 71.12 0)
			(effects
				(font
					(size 1.27 1.27)
					(thickness 0.15)
				)
				(justify left bottom)
				(hide yes)
			)
		)
		(property "Manufacturer" "Samsung Electro-Mechanics"
			(at 408.94 71.12 0)
			(effects
				(font
					(size 1.27 1.27)
					(thickness 0.15)
				)
				(justify left bottom)
				(hide yes)
			)
		)
		(property "License" "Apache-2.0"
			(at 411.48 71.12 0)
			(effects
				(font
					(size 1.27 1.27)
					(thickness 0.15)
				)
				(justify left bottom)
				(hide yes)
			)
		)
		(property "Author" "Antmicro"
			(at 414.02 71.12 0)
			(effects
				(font
					(size 1.27 1.27)
					(thickness 0.15)
				)
				(justify left bottom)
				(hide yes)
			)
		)
		(property "Val" "22u"
			(at 391.16 90.1636 90)
			(effects
				(font
					(size 1.27 1.27)
					(thickness 0.15)
				)
				(justify right)
			)
		)
		(property "Voltage" "16V"
			(at 416.56 71.12 0)
			(effects
				(font
					(size 1.27 1.27)
				)
				(justify left bottom)
				(hide yes)
			)
		)
		(property "Dielectric" ""
			(at 419.1 71.12 0)
			(effects
				(font
					(size 1.27 1.27)
				)
				(justify left bottom)
				(hide yes)
			)
		)
		(pin "1"
		)
		(pin "2"
		)
		(instances
			(project "OCuLink to 10GbE adapter"
				(path ""
					(reference "C126")
					(unit 1)
				)
			)
			(project "thunderbolt-to-10gbe-adapter"
				(path ""
					(reference "C261")
					(unit 1)
				)
			)
		)
	)
	(symbol
		(lib_id "antmicroCapacitors0603:C_22u_16V_0603")
		(at 370.84 91.44 90)
		(unit 1)
		(exclude_from_sim no)
		(in_bom yes)
		(on_board yes)
		(dnp no)
		(fields_autoplaced yes)
		(property "Reference" "C252"
			(at 373.38 87.6236 90)
			(effects
				(font
					(size 1.27 1.27)
					(thickness 0.15)
				)
				(justify right)
			)
		)
		(property "Value" "C_22u_16V_0603"
			(at 381 71.12 0)
			(effects
				(font
					(size 1.27 1.27)
					(thickness 0.15)
				)
				(justify left bottom)
				(hide yes)
			)
		)
		(property "Footprint" "antmicro-footprints:C_0603_1608Metric_EIA"
			(at 383.54 71.12 0)
			(effects
				(font
					(size 1.27 1.27)
					(thickness 0.15)
				)
				(justify left bottom)
				(hide yes)
			)
		)
		(property "Datasheet" "https://product.samsungsem.com/mlcc/CL10A226MO7JZN.do"
			(at 386.08 71.12 0)
			(effects
				(font
					(size 1.27 1.27)
					(thickness 0.15)
				)
				(justify left bottom)
				(hide yes)
			)
		)
		(property "Description" "SMD Multilayer Ceramic Capacitor"
			(at 370.84 91.44 0)
			(effects
				(font
					(size 1.27 1.27)
				)
				(hide yes)
			)
		)
		(property "MPN" "CL10A226MO7JZNC"
			(at 388.62 71.12 0)
			(effects
				(font
					(size 1.27 1.27)
					(thickness 0.15)
				)
				(justify left bottom)
				(hide yes)
			)
		)
		(property "Manufacturer" "Samsung Electro-Mechanics"
			(at 391.16 71.12 0)
			(effects
				(font
					(size 1.27 1.27)
					(thickness 0.15)
				)
				(justify left bottom)
				(hide yes)
			)
		)
		(property "License" "Apache-2.0"
			(at 393.7 71.12 0)
			(effects
				(font
					(size 1.27 1.27)
					(thickness 0.15)
				)
				(justify left bottom)
				(hide yes)
			)
		)
		(property "Author" "Antmicro"
			(at 396.24 71.12 0)
			(effects
				(font
					(size 1.27 1.27)
					(thickness 0.15)
				)
				(justify left bottom)
				(hide yes)
			)
		)
		(property "Val" "22u"
			(at 373.38 90.1636 90)
			(effects
				(font
					(size 1.27 1.27)
					(thickness 0.15)
				)
				(justify right)
			)
		)
		(property "Voltage" "16V"
			(at 398.78 71.12 0)
			(effects
				(font
					(size 1.27 1.27)
				)
				(justify left bottom)
				(hide yes)
			)
		)
		(property "Dielectric" ""
			(at 401.32 71.12 0)
			(effects
				(font
					(size 1.27 1.27)
				)
				(justify left bottom)
				(hide yes)
			)
		)
		(pin "1"
		)
		(pin "2"
		)
		(instances
			(project "OCuLink to 10GbE adapter"
				(path ""
					(reference "C124")
					(unit 1)
				)
			)
			(project "thunderbolt-to-10gbe-adapter"
				(path ""
					(reference "C252")
					(unit 1)
				)
			)
		)
	)
	(symbol
		(lib_id "antmicroCapacitors0402:C_1u_25V_0402")
		(at 124.46 207.01 90)
		(unit 1)
		(exclude_from_sim no)
		(in_bom yes)
		(on_board yes)
		(dnp no)
		(property "Reference" "C189"
			(at 126.492 203.2 90)
			(effects
				(font
					(size 1.27 1.27)
					(thickness 0.15)
				)
				(justify right)
			)
		)
		(property "Value" "C_1u_25V_0402"
			(at 134.62 186.69 0)
			(effects
				(font
					(size 1.27 1.27)
					(thickness 0.15)
				)
				(justify left bottom)
				(hide yes)
			)
		)
		(property "Footprint" "antmicro-footprints:C_0402_1005Metric"
			(at 137.16 186.69 0)
			(effects
				(font
					(size 1.27 1.27)
					(thickness 0.15)
				)
				(justify left bottom)
				(hide yes)
			)
		)
		(property "Datasheet" "https://www.murata.com/products/productdetail?partno=GRM155R61E105KE11%23"
			(at 139.7 186.69 0)
			(effects
				(font
					(size 1.27 1.27)
					(thickness 0.15)
				)
				(justify left bottom)
				(hide yes)
			)
		)
		(property "Description" "SMD Multilayer Ceramic Capacitor, 1 µF, 25 V, 0402 [1005 Metric], ± 10%, X5R, GRM Series"
			(at 124.46 207.01 0)
			(effects
				(font
					(size 1.27 1.27)
				)
				(hide yes)
			)
		)
		(property "MPN" "GRM155R61E105KE11J"
			(at 142.24 186.69 0)
			(effects
				(font
					(size 1.27 1.27)
					(thickness 0.15)
				)
				(justify left bottom)
				(hide yes)
			)
		)
		(property "Manufacturer" "Murata"
			(at 144.78 186.69 0)
			(effects
				(font
					(size 1.27 1.27)
					(thickness 0.15)
				)
				(justify left bottom)
				(hide yes)
			)
		)
		(property "License" "Apache-2.0"
			(at 147.32 186.69 0)
			(effects
				(font
					(size 1.27 1.27)
					(thickness 0.15)
				)
				(justify left bottom)
				(hide yes)
			)
		)
		(property "Author" "Antmicro"
			(at 149.86 186.69 0)
			(effects
				(font
					(size 1.27 1.27)
					(thickness 0.15)
				)
				(justify left bottom)
				(hide yes)
			)
		)
		(property "Val" "1u"
			(at 126.492 205.74 90)
			(effects
				(font
					(size 1.27 1.27)
					(thickness 0.15)
				)
				(justify right)
			)
		)
		(property "Voltage" "25V"
			(at 152.4 186.69 0)
			(effects
				(font
					(size 1.27 1.27)
				)
				(justify left bottom)
				(hide yes)
			)
		)
		(property "Dielectric" "X5R"
			(at 154.94 186.69 0)
			(effects
				(font
					(size 1.27 1.27)
				)
				(justify left bottom)
				(hide yes)
			)
		)
		(pin "2"
		)
		(pin "1"
		)
		(instances
			(project "OCuLink to 10GbE adapter"
				(path ""
					(reference "C181")
					(unit 1)
				)
			)
			(project "thunderbolt-to-10gbe-adapter"
				(path ""
					(reference "C189")
					(unit 1)
				)
			)
		)
	)
	(symbol
		(lib_id "antmicroCapacitors0402:C_1u_25V_0402")
		(at 151.13 127 90)
		(unit 1)
		(exclude_from_sim no)
		(in_bom yes)
		(on_board yes)
		(dnp no)
		(property "Reference" "C204"
			(at 152.908 123.19 90)
			(effects
				(font
					(size 1.27 1.27)
					(thickness 0.15)
				)
				(justify right)
			)
		)
		(property "Value" "C_1u_25V_0402"
			(at 161.29 106.68 0)
			(effects
				(font
					(size 1.27 1.27)
					(thickness 0.15)
				)
				(justify left bottom)
				(hide yes)
			)
		)
		(property "Footprint" "antmicro-footprints:C_0402_1005Metric"
			(at 163.83 106.68 0)
			(effects
				(font
					(size 1.27 1.27)
					(thickness 0.15)
				)
				(justify left bottom)
				(hide yes)
			)
		)
		(property "Datasheet" "https://www.murata.com/products/productdetail?partno=GRM155R61E105KE11%23"
			(at 166.37 106.68 0)
			(effects
				(font
					(size 1.27 1.27)
					(thickness 0.15)
				)
				(justify left bottom)
				(hide yes)
			)
		)
		(property "Description" "SMD Multilayer Ceramic Capacitor, 1 µF, 25 V, 0402 [1005 Metric], ± 10%, X5R, GRM Series"
			(at 151.13 127 0)
			(effects
				(font
					(size 1.27 1.27)
				)
				(hide yes)
			)
		)
		(property "MPN" "GRM155R61E105KE11J"
			(at 168.91 106.68 0)
			(effects
				(font
					(size 1.27 1.27)
					(thickness 0.15)
				)
				(justify left bottom)
				(hide yes)
			)
		)
		(property "Manufacturer" "Murata"
			(at 171.45 106.68 0)
			(effects
				(font
					(size 1.27 1.27)
					(thickness 0.15)
				)
				(justify left bottom)
				(hide yes)
			)
		)
		(property "License" "Apache-2.0"
			(at 173.99 106.68 0)
			(effects
				(font
					(size 1.27 1.27)
					(thickness 0.15)
				)
				(justify left bottom)
				(hide yes)
			)
		)
		(property "Author" "Antmicro"
			(at 176.53 106.68 0)
			(effects
				(font
					(size 1.27 1.27)
					(thickness 0.15)
				)
				(justify left bottom)
				(hide yes)
			)
		)
		(property "Val" "1u"
			(at 152.908 125.73 90)
			(effects
				(font
					(size 1.27 1.27)
					(thickness 0.15)
				)
				(justify right)
			)
		)
		(property "Voltage" "25V"
			(at 179.07 106.68 0)
			(effects
				(font
					(size 1.27 1.27)
				)
				(justify left bottom)
				(hide yes)
			)
		)
		(property "Dielectric" "X5R"
			(at 181.61 106.68 0)
			(effects
				(font
					(size 1.27 1.27)
				)
				(justify left bottom)
				(hide yes)
			)
		)
		(pin "2"
		)
		(pin "1"
		)
		(instances
			(project "OCuLink to 10GbE adapter"
				(path ""
					(reference "C145")
					(unit 1)
				)
			)
			(project "thunderbolt-to-10gbe-adapter"
				(path ""
					(reference "C204")
					(unit 1)
				)
			)
		)
	)
	(symbol
		(lib_id "antmicropower:PWR_FLAG")
		(at 101.6 198.12 0)
		(unit 1)
		(exclude_from_sim no)
		(in_bom yes)
		(on_board yes)
		(dnp no)
		(fields_autoplaced yes)
		(property "Reference" "#FLG027"
			(at 101.6 196.215 0)
			(effects
				(font
					(size 1.27 1.27)
				)
				(hide yes)
			)
		)
		(property "Value" "PWR_FLAG"
			(at 101.6 193.04 0)
			(effects
				(font
					(size 1.27 1.27)
				)
			)
		)
		(property "Footprint" ""
			(at 101.6 198.12 0)
			(effects
				(font
					(size 1.27 1.27)
				)
				(hide yes)
			)
		)
		(property "Datasheet" ""
			(at 101.6 198.12 0)
			(effects
				(font
					(size 1.27 1.27)
				)
				(hide yes)
			)
		)
		(property "Description" ""
			(at 101.6 200.66 0)
			(effects
				(font
					(size 1.27 1.27)
				)
				(justify left bottom)
				(hide yes)
			)
		)
		(pin "1"
		)
		(instances
			(project "OCuLink to 10GbE adapter"
				(path ""
					(reference "#FLG017")
					(unit 1)
				)
			)
			(project "thunderbolt-to-10gbe-adapter"
				(path ""
					(reference "#FLG027")
					(unit 1)
				)
			)
		)
	)
	(symbol
		(lib_id "antmicropower:GND")
		(at 151.13 54.61 0)
		(unit 1)
		(exclude_from_sim no)
		(in_bom yes)
		(on_board yes)
		(dnp no)
		(property "Reference" "#PWR0273"
			(at 160.02 57.15 0)
			(effects
				(font
					(size 1.27 1.27)
					(thickness 0.15)
				)
				(justify left bottom)
				(hide yes)
			)
		)
		(property "Value" "GND"
			(at 151.13 58.42 0)
			(effects
				(font
					(size 1.27 1.27)
					(thickness 0.15)
				)
			)
		)
		(property "Footprint" ""
			(at 160.02 62.23 0)
			(effects
				(font
					(size 1.27 1.27)
					(thickness 0.15)
				)
				(justify left bottom)
				(hide yes)
			)
		)
		(property "Datasheet" ""
			(at 160.02 67.31 0)
			(effects
				(font
					(size 1.27 1.27)
					(thickness 0.15)
				)
				(justify left bottom)
				(hide yes)
			)
		)
		(property "Description" ""
			(at 151.13 54.61 0)
			(effects
				(font
					(size 1.27 1.27)
				)
				(hide yes)
			)
		)
		(property "Author" "Antmicro"
			(at 160.02 62.23 0)
			(effects
				(font
					(size 1.27 1.27)
					(thickness 0.15)
				)
				(justify left bottom)
				(hide yes)
			)
		)
		(property "License" "Apache-2.0"
			(at 160.02 64.77 0)
			(effects
				(font
					(size 1.27 1.27)
					(thickness 0.15)
				)
				(justify left bottom)
				(hide yes)
			)
		)
		(pin "1"
		)
		(instances
			(project "OCuLink to 10GbE adapter"
				(path ""
					(reference "#PWR0120")
					(unit 1)
				)
			)
			(project "thunderbolt-to-10gbe-adapter"
				(path ""
					(reference "#PWR0273")
					(unit 1)
				)
			)
		)
	)
	(symbol
		(lib_id "antmicropower:GND")
		(at 299.72 93.98 0)
		(unit 1)
		(exclude_from_sim no)
		(in_bom yes)
		(on_board yes)
		(dnp no)
		(property "Reference" "#PWR0299"
			(at 308.61 96.52 0)
			(effects
				(font
					(size 1.27 1.27)
					(thickness 0.15)
				)
				(justify left bottom)
				(hide yes)
			)
		)
		(property "Value" "GND"
			(at 299.72 97.79 0)
			(effects
				(font
					(size 1.27 1.27)
					(thickness 0.15)
				)
			)
		)
		(property "Footprint" ""
			(at 308.61 101.6 0)
			(effects
				(font
					(size 1.27 1.27)
					(thickness 0.15)
				)
				(justify left bottom)
				(hide yes)
			)
		)
		(property "Datasheet" ""
			(at 308.61 106.68 0)
			(effects
				(font
					(size 1.27 1.27)
					(thickness 0.15)
				)
				(justify left bottom)
				(hide yes)
			)
		)
		(property "Description" ""
			(at 299.72 93.98 0)
			(effects
				(font
					(size 1.27 1.27)
				)
				(hide yes)
			)
		)
		(property "Author" "Antmicro"
			(at 308.61 101.6 0)
			(effects
				(font
					(size 1.27 1.27)
					(thickness 0.15)
				)
				(justify left bottom)
				(hide yes)
			)
		)
		(property "License" "Apache-2.0"
			(at 308.61 104.14 0)
			(effects
				(font
					(size 1.27 1.27)
					(thickness 0.15)
				)
				(justify left bottom)
				(hide yes)
			)
		)
		(pin "1"
		)
		(instances
			(project "OCuLink to 10GbE adapter"
				(path ""
					(reference "#PWR0164")
					(unit 1)
				)
			)
			(project "thunderbolt-to-10gbe-adapter"
				(path ""
					(reference "#PWR0299")
					(unit 1)
				)
			)
		)
	)
	(symbol
		(lib_id "antmicroCapacitorsmisc:C_100u_0805")
		(at 97.79 180.34 90)
		(unit 1)
		(exclude_from_sim no)
		(in_bom yes)
		(on_board yes)
		(dnp no)
		(property "Reference" "C179"
			(at 99.568 176.53 90)
			(effects
				(font
					(size 1.27 1.27)
					(thickness 0.15)
				)
				(justify right)
			)
		)
		(property "Value" "C_100u_0805"
			(at 107.95 160.02 0)
			(effects
				(font
					(size 1.27 1.27)
					(thickness 0.15)
				)
				(justify left bottom)
				(hide yes)
			)
		)
		(property "Footprint" "antmicro-footprints:C_0805_2012Metric"
			(at 110.49 160.02 0)
			(effects
				(font
					(size 1.27 1.27)
					(thickness 0.15)
				)
				(justify left bottom)
				(hide yes)
			)
		)
		(property "Datasheet" "https://www.murata.com/products/productdetail?partno=GRM21BR60J107ME15%23"
			(at 113.03 160.02 0)
			(effects
				(font
					(size 1.27 1.27)
					(thickness 0.15)
				)
				(justify left bottom)
				(hide yes)
			)
		)
		(property "Description" "SMD Multilayer Ceramic Capacitor, 100 µF, 6.3 V, 0805 [2012 Metric], ± 20%, X5R, GRM Series"
			(at 97.79 180.34 0)
			(effects
				(font
					(size 1.27 1.27)
				)
				(hide yes)
			)
		)
		(property "MPN" "GRM21BR60J107ME15L"
			(at 115.57 160.02 0)
			(effects
				(font
					(size 1.27 1.27)
					(thickness 0.15)
				)
				(justify left bottom)
				(hide yes)
			)
		)
		(property "Manufacturer" "Murata"
			(at 118.11 160.02 0)
			(effects
				(font
					(size 1.27 1.27)
					(thickness 0.15)
				)
				(justify left bottom)
				(hide yes)
			)
		)
		(property "License" "Apache-2.0"
			(at 120.65 160.02 0)
			(effects
				(font
					(size 1.27 1.27)
					(thickness 0.15)
				)
				(justify left bottom)
				(hide yes)
			)
		)
		(property "Author" "Antmicro"
			(at 123.19 160.02 0)
			(effects
				(font
					(size 1.27 1.27)
					(thickness 0.15)
				)
				(justify left bottom)
				(hide yes)
			)
		)
		(property "Val" "100u"
			(at 99.568 179.07 90)
			(effects
				(font
					(size 1.27 1.27)
					(thickness 0.15)
				)
				(justify right)
			)
		)
		(property "Voltage" ""
			(at 125.73 160.02 0)
			(effects
				(font
					(size 1.27 1.27)
				)
				(justify left bottom)
				(hide yes)
			)
		)
		(property "Dielectric" ""
			(at 128.27 160.02 0)
			(effects
				(font
					(size 1.27 1.27)
				)
				(justify left bottom)
				(hide yes)
			)
		)
		(property "Public" "False"
			(at 130.81 160.02 0)
			(effects
				(font
					(size 1.27 1.27)
				)
				(justify left bottom)
				(hide yes)
			)
		)
		(pin "1"
		)
		(pin "2"
		)
		(instances
			(project "OCuLink to 10GbE adapter"
				(path ""
					(reference "C173")
					(unit 1)
				)
			)
			(project "thunderbolt-to-10gbe-adapter"
				(path ""
					(reference "C179")
					(unit 1)
				)
			)
		)
	)
	(symbol
		(lib_id "antmicroCapacitorspol:C_Pol_100u_6V_KEMET-T490-A")
		(at 48.26 148.59 270)
		(unit 1)
		(exclude_from_sim no)
		(in_bom yes)
		(on_board yes)
		(dnp no)
		(fields_autoplaced yes)
		(property "Reference" "C77"
			(at 50.8 149.3266 90)
			(effects
				(font
					(size 1.27 1.27)
					(thickness 0.15)
				)
				(justify left)
			)
		)
		(property "Value" "C_Pol_100u_6V_KEMET-T490-A"
			(at 45.72 162.56 0)
			(effects
				(font
					(size 1.27 1.27)
					(thickness 0.15)
				)
				(justify left bottom)
				(hide yes)
			)
		)
		(property "Footprint" "antmicro-footprints:C_Pol_EIA-A"
			(at 40.64 162.56 0)
			(effects
				(font
					(size 1.27 1.27)
					(thickness 0.15)
				)
				(justify left bottom)
				(hide yes)
			)
		)
		(property "Datasheet" "https://www.kemet.com/en/us/capacitors/product/T490A107M006ATE800.html"
			(at 38.1 162.56 0)
			(effects
				(font
					(size 1.27 1.27)
					(thickness 0.15)
				)
				(justify left bottom)
				(hide yes)
			)
		)
		(property "Description" "Surface Mount Tantalum Capacitor,  Solid SMD 6V 100uF 1206 20% ESR=800mOhms"
			(at 22.86 162.56 0)
			(effects
				(font
					(size 1.27 1.27)
				)
				(justify left bottom)
				(hide yes)
			)
		)
		(property "Val" "100u"
			(at 50.8 151.8666 90)
			(effects
				(font
					(size 1.27 1.27)
					(thickness 0.15)
				)
				(justify left)
			)
		)
		(property "MPN" "T490A107M006ATE800"
			(at 35.56 162.56 0)
			(effects
				(font
					(size 1.27 1.27)
					(thickness 0.15)
				)
				(justify left bottom)
				(hide yes)
			)
		)
		(property "Manufacturer" "KEMET"
			(at 33.02 162.56 0)
			(effects
				(font
					(size 1.27 1.27)
					(thickness 0.15)
				)
				(justify left bottom)
				(hide yes)
			)
		)
		(property "License" "Apache-2.0"
			(at 30.48 162.56 0)
			(effects
				(font
					(size 1.27 1.27)
					(thickness 0.15)
				)
				(justify left bottom)
				(hide yes)
			)
		)
		(property "Author" "Antmicro"
			(at 27.94 162.56 0)
			(effects
				(font
					(size 1.27 1.27)
					(thickness 0.15)
				)
				(justify left bottom)
				(hide yes)
			)
		)
		(property "Voltage" "6V"
			(at 25.4 162.56 0)
			(effects
				(font
					(size 1.27 1.27)
				)
				(justify left bottom)
				(hide yes)
			)
		)
		(property "Dielectric" "template_dielectric"
			(at 22.86 162.56 0)
			(effects
				(font
					(size 1.27 1.27)
				)
				(justify left bottom)
				(hide yes)
			)
		)
		(pin "2"
		)
		(pin "1"
		)
		(instances
			(project "thunderbolt-to-10gbe-adapter"
				(path ""
					(reference "C77")
					(unit 1)
				)
			)
		)
	)
	(symbol
		(lib_id "antmicroCapacitors0603:C_22u_16V_0603")
		(at 353.06 130.81 90)
		(unit 1)
		(exclude_from_sim no)
		(in_bom yes)
		(on_board yes)
		(dnp no)
		(fields_autoplaced yes)
		(property "Reference" "C244"
			(at 355.6 126.9936 90)
			(effects
				(font
					(size 1.27 1.27)
					(thickness 0.15)
				)
				(justify right)
			)
		)
		(property "Value" "C_22u_16V_0603"
			(at 363.22 110.49 0)
			(effects
				(font
					(size 1.27 1.27)
					(thickness 0.15)
				)
				(justify left bottom)
				(hide yes)
			)
		)
		(property "Footprint" "antmicro-footprints:C_0603_1608Metric_EIA"
			(at 365.76 110.49 0)
			(effects
				(font
					(size 1.27 1.27)
					(thickness 0.15)
				)
				(justify left bottom)
				(hide yes)
			)
		)
		(property "Datasheet" "https://product.samsungsem.com/mlcc/CL10A226MO7JZN.do"
			(at 368.3 110.49 0)
			(effects
				(font
					(size 1.27 1.27)
					(thickness 0.15)
				)
				(justify left bottom)
				(hide yes)
			)
		)
		(property "Description" "SMD Multilayer Ceramic Capacitor"
			(at 353.06 130.81 0)
			(effects
				(font
					(size 1.27 1.27)
				)
				(hide yes)
			)
		)
		(property "MPN" "CL10A226MO7JZNC"
			(at 370.84 110.49 0)
			(effects
				(font
					(size 1.27 1.27)
					(thickness 0.15)
				)
				(justify left bottom)
				(hide yes)
			)
		)
		(property "Manufacturer" "Samsung Electro-Mechanics"
			(at 373.38 110.49 0)
			(effects
				(font
					(size 1.27 1.27)
					(thickness 0.15)
				)
				(justify left bottom)
				(hide yes)
			)
		)
		(property "License" "Apache-2.0"
			(at 375.92 110.49 0)
			(effects
				(font
					(size 1.27 1.27)
					(thickness 0.15)
				)
				(justify left bottom)
				(hide yes)
			)
		)
		(property "Author" "Antmicro"
			(at 378.46 110.49 0)
			(effects
				(font
					(size 1.27 1.27)
					(thickness 0.15)
				)
				(justify left bottom)
				(hide yes)
			)
		)
		(property "Val" "22u"
			(at 355.6 129.5336 90)
			(effects
				(font
					(size 1.27 1.27)
					(thickness 0.15)
				)
				(justify right)
			)
		)
		(property "Voltage" "16V"
			(at 381 110.49 0)
			(effects
				(font
					(size 1.27 1.27)
				)
				(justify left bottom)
				(hide yes)
			)
		)
		(property "Dielectric" ""
			(at 383.54 110.49 0)
			(effects
				(font
					(size 1.27 1.27)
				)
				(justify left bottom)
				(hide yes)
			)
		)
		(pin "1"
		)
		(pin "2"
		)
		(instances
			(project "OCuLink to 10GbE adapter"
				(path ""
					(reference "C151")
					(unit 1)
				)
			)
			(project "thunderbolt-to-10gbe-adapter"
				(path ""
					(reference "C244")
					(unit 1)
				)
			)
		)
	)
	(symbol
		(lib_id "antmicroCapacitors0402:C_1u_25V_0402")
		(at 335.28 91.44 90)
		(unit 1)
		(exclude_from_sim no)
		(in_bom yes)
		(on_board yes)
		(dnp no)
		(property "Reference" "C234"
			(at 337.312 87.63 90)
			(effects
				(font
					(size 1.27 1.27)
					(thickness 0.15)
				)
				(justify right)
			)
		)
		(property "Value" "C_1u_25V_0402"
			(at 345.44 71.12 0)
			(effects
				(font
					(size 1.27 1.27)
					(thickness 0.15)
				)
				(justify left bottom)
				(hide yes)
			)
		)
		(property "Footprint" "antmicro-footprints:C_0402_1005Metric"
			(at 347.98 71.12 0)
			(effects
				(font
					(size 1.27 1.27)
					(thickness 0.15)
				)
				(justify left bottom)
				(hide yes)
			)
		)
		(property "Datasheet" "https://www.murata.com/products/productdetail?partno=GRM155R61E105KE11%23"
			(at 350.52 71.12 0)
			(effects
				(font
					(size 1.27 1.27)
					(thickness 0.15)
				)
				(justify left bottom)
				(hide yes)
			)
		)
		(property "Description" "SMD Multilayer Ceramic Capacitor, 1 µF, 25 V, 0402 [1005 Metric], ± 10%, X5R, GRM Series"
			(at 335.28 91.44 0)
			(effects
				(font
					(size 1.27 1.27)
				)
				(hide yes)
			)
		)
		(property "MPN" "GRM155R61E105KE11J"
			(at 353.06 71.12 0)
			(effects
				(font
					(size 1.27 1.27)
					(thickness 0.15)
				)
				(justify left bottom)
				(hide yes)
			)
		)
		(property "Manufacturer" "Murata"
			(at 355.6 71.12 0)
			(effects
				(font
					(size 1.27 1.27)
					(thickness 0.15)
				)
				(justify left bottom)
				(hide yes)
			)
		)
		(property "License" "Apache-2.0"
			(at 358.14 71.12 0)
			(effects
				(font
					(size 1.27 1.27)
					(thickness 0.15)
				)
				(justify left bottom)
				(hide yes)
			)
		)
		(property "Author" "Antmicro"
			(at 360.68 71.12 0)
			(effects
				(font
					(size 1.27 1.27)
					(thickness 0.15)
				)
				(justify left bottom)
				(hide yes)
			)
		)
		(property "Val" "1u"
			(at 337.312 90.17 90)
			(effects
				(font
					(size 1.27 1.27)
					(thickness 0.15)
				)
				(justify right)
			)
		)
		(property "Voltage" "25V"
			(at 363.22 71.12 0)
			(effects
				(font
					(size 1.27 1.27)
				)
				(justify left bottom)
				(hide yes)
			)
		)
		(property "Dielectric" "X5R"
			(at 365.76 71.12 0)
			(effects
				(font
					(size 1.27 1.27)
				)
				(justify left bottom)
				(hide yes)
			)
		)
		(pin "2"
		)
		(pin "1"
		)
		(instances
			(project "OCuLink to 10GbE adapter"
				(path ""
					(reference "C121")
					(unit 1)
				)
			)
			(project "thunderbolt-to-10gbe-adapter"
				(path ""
					(reference "C234")
					(unit 1)
				)
			)
		)
	)
	(symbol
		(lib_id "antmicroCapacitors0402:C_100n_0402")
		(at 77.47 127 90)
		(unit 1)
		(exclude_from_sim no)
		(in_bom yes)
		(on_board yes)
		(dnp no)
		(property "Reference" "C162"
			(at 79.502 123.19 90)
			(effects
				(font
					(size 1.27 1.27)
					(thickness 0.15)
				)
				(justify right)
			)
		)
		(property "Value" "C_100n_0402"
			(at 100.33 111.76 0)
			(effects
				(font
					(size 1.27 1.27)
					(thickness 0.15)
				)
				(justify left bottom)
				(hide yes)
			)
		)
		(property "Footprint" "antmicro-footprints:C_0402_1005Metric"
			(at 102.87 111.76 0)
			(effects
				(font
					(size 1.27 1.27)
					(thickness 0.15)
				)
				(justify left bottom)
				(hide yes)
			)
		)
		(property "Datasheet" "https://www.murata.com/products/productdetail?partno=GRM155R61H104KE14%23"
			(at 105.41 111.76 0)
			(effects
				(font
					(size 1.27 1.27)
					(thickness 0.15)
				)
				(justify left bottom)
				(hide yes)
			)
		)
		(property "Description" "SMD Multilayer Ceramic Capacitor, 0.1 µF, 50 V, 0402 [1005 Metric], ± 10%, X5R, GRM Series"
			(at 77.47 127 0)
			(effects
				(font
					(size 1.27 1.27)
				)
				(hide yes)
			)
		)
		(property "MPN" "GRM155R61H104KE14D"
			(at 107.95 111.76 0)
			(effects
				(font
					(size 1.27 1.27)
					(thickness 0.15)
				)
				(justify left bottom)
				(hide yes)
			)
		)
		(property "Val" "100n"
			(at 79.502 125.73 90)
			(effects
				(font
					(size 1.27 1.27)
					(thickness 0.15)
				)
				(justify right)
			)
		)
		(property "Voltage" "50V"
			(at 87.63 111.76 0)
			(effects
				(font
					(size 1.27 1.27)
					(thickness 0.15)
				)
				(justify left bottom)
				(hide yes)
			)
		)
		(property "Dielectric" "X5R"
			(at 90.17 111.76 0)
			(effects
				(font
					(size 1.27 1.27)
					(thickness 0.15)
				)
				(justify left bottom)
				(hide yes)
			)
		)
		(property "Manufacturer" "Murata"
			(at 92.71 111.76 0)
			(effects
				(font
					(size 1.27 1.27)
					(thickness 0.15)
				)
				(justify left bottom)
				(hide yes)
			)
		)
		(property "License" "Apache-2.0"
			(at 95.25 111.76 0)
			(effects
				(font
					(size 1.27 1.27)
					(thickness 0.15)
				)
				(justify left bottom)
				(hide yes)
			)
		)
		(property "Author" "Antmicro"
			(at 97.79 111.76 0)
			(effects
				(font
					(size 1.27 1.27)
					(thickness 0.15)
				)
				(justify left bottom)
				(hide yes)
			)
		)
		(pin "2"
		)
		(pin "1"
		)
		(instances
			(project "OCuLink to 10GbE adapter"
				(path ""
					(reference "C138")
					(unit 1)
				)
			)
			(project "thunderbolt-to-10gbe-adapter"
				(path ""
					(reference "C162")
					(unit 1)
				)
			)
		)
	)
	(symbol
		(lib_id "antmicropower:GND")
		(at 370.84 93.98 0)
		(unit 1)
		(exclude_from_sim no)
		(in_bom yes)
		(on_board yes)
		(dnp no)
		(property "Reference" "#PWR0338"
			(at 379.73 96.52 0)
			(effects
				(font
					(size 1.27 1.27)
					(thickness 0.15)
				)
				(justify left bottom)
				(hide yes)
			)
		)
		(property "Value" "GND"
			(at 370.84 97.79 0)
			(effects
				(font
					(size 1.27 1.27)
					(thickness 0.15)
				)
			)
		)
		(property "Footprint" ""
			(at 379.73 101.6 0)
			(effects
				(font
					(size 1.27 1.27)
					(thickness 0.15)
				)
				(justify left bottom)
				(hide yes)
			)
		)
		(property "Datasheet" ""
			(at 379.73 106.68 0)
			(effects
				(font
					(size 1.27 1.27)
					(thickness 0.15)
				)
				(justify left bottom)
				(hide yes)
			)
		)
		(property "Description" ""
			(at 370.84 93.98 0)
			(effects
				(font
					(size 1.27 1.27)
				)
				(hide yes)
			)
		)
		(property "Author" "Antmicro"
			(at 379.73 101.6 0)
			(effects
				(font
					(size 1.27 1.27)
					(thickness 0.15)
				)
				(justify left bottom)
				(hide yes)
			)
		)
		(property "License" "Apache-2.0"
			(at 379.73 104.14 0)
			(effects
				(font
					(size 1.27 1.27)
					(thickness 0.15)
				)
				(justify left bottom)
				(hide yes)
			)
		)
		(pin "1"
		)
		(instances
			(project "OCuLink to 10GbE adapter"
				(path ""
					(reference "#PWR0171")
					(unit 1)
				)
			)
			(project "thunderbolt-to-10gbe-adapter"
				(path ""
					(reference "#PWR0338")
					(unit 1)
				)
			)
		)
	)
	(symbol
		(lib_id "antmicropower:GND")
		(at 76.2 156.21 0)
		(unit 1)
		(exclude_from_sim no)
		(in_bom yes)
		(on_board yes)
		(dnp no)
		(property "Reference" "#PWR0226"
			(at 85.09 158.75 0)
			(effects
				(font
					(size 1.27 1.27)
					(thickness 0.15)
				)
				(justify left bottom)
				(hide yes)
			)
		)
		(property "Value" "GND"
			(at 76.2 160.02 0)
			(effects
				(font
					(size 1.27 1.27)
					(thickness 0.15)
				)
			)
		)
		(property "Footprint" ""
			(at 85.09 163.83 0)
			(effects
				(font
					(size 1.27 1.27)
					(thickness 0.15)
				)
				(justify left bottom)
				(hide yes)
			)
		)
		(property "Datasheet" ""
			(at 85.09 168.91 0)
			(effects
				(font
					(size 1.27 1.27)
					(thickness 0.15)
				)
				(justify left bottom)
				(hide yes)
			)
		)
		(property "Description" ""
			(at 76.2 156.21 0)
			(effects
				(font
					(size 1.27 1.27)
				)
				(hide yes)
			)
		)
		(property "Author" "Antmicro"
			(at 85.09 163.83 0)
			(effects
				(font
					(size 1.27 1.27)
					(thickness 0.15)
				)
				(justify left bottom)
				(hide yes)
			)
		)
		(property "License" "Apache-2.0"
			(at 85.09 166.37 0)
			(effects
				(font
					(size 1.27 1.27)
					(thickness 0.15)
				)
				(justify left bottom)
				(hide yes)
			)
		)
		(pin "1"
		)
		(instances
			(project "OCuLink to 10GbE adapter"
				(path ""
					(reference "#PWR0212")
					(unit 1)
				)
			)
			(project "thunderbolt-to-10gbe-adapter"
				(path ""
					(reference "#PWR0226")
					(unit 1)
				)
			)
		)
	)
	(symbol
		(lib_id "antmicropower:GND")
		(at 38.1 54.61 0)
		(mirror y)
		(unit 1)
		(exclude_from_sim no)
		(in_bom yes)
		(on_board yes)
		(dnp no)
		(property "Reference" "#PWR0505"
			(at 29.21 57.15 0)
			(effects
				(font
					(size 1.27 1.27)
					(thickness 0.15)
				)
				(justify left bottom)
				(hide yes)
			)
		)
		(property "Value" "GND"
			(at 38.1 58.42 0)
			(effects
				(font
					(size 1.27 1.27)
					(thickness 0.15)
				)
			)
		)
		(property "Footprint" ""
			(at 29.21 62.23 0)
			(effects
				(font
					(size 1.27 1.27)
					(thickness 0.15)
				)
				(justify left bottom)
				(hide yes)
			)
		)
		(property "Datasheet" ""
			(at 29.21 67.31 0)
			(effects
				(font
					(size 1.27 1.27)
					(thickness 0.15)
				)
				(justify left bottom)
				(hide yes)
			)
		)
		(property "Description" ""
			(at 38.1 54.61 0)
			(effects
				(font
					(size 1.27 1.27)
				)
				(hide yes)
			)
		)
		(property "Author" "Antmicro"
			(at 29.21 62.23 0)
			(effects
				(font
					(size 1.27 1.27)
					(thickness 0.15)
				)
				(justify left bottom)
				(hide yes)
			)
		)
		(property "License" "Apache-2.0"
			(at 29.21 64.77 0)
			(effects
				(font
					(size 1.27 1.27)
					(thickness 0.15)
				)
				(justify left bottom)
				(hide yes)
			)
		)
		(pin "1"
		)
		(instances
			(project "thunderbolt-to-10gbe-adapter"
				(path ""
					(reference "#PWR0505")
					(unit 1)
				)
			)
		)
	)
	(symbol
		(lib_id "antmicroCapacitors0603:C_22u_16V_0603")
		(at 379.73 130.81 90)
		(unit 1)
		(exclude_from_sim no)
		(in_bom yes)
		(on_board yes)
		(dnp no)
		(fields_autoplaced yes)
		(property "Reference" "C258"
			(at 382.27 126.9936 90)
			(effects
				(font
					(size 1.27 1.27)
					(thickness 0.15)
				)
				(justify right)
			)
		)
		(property "Value" "C_22u_16V_0603"
			(at 389.89 110.49 0)
			(effects
				(font
					(size 1.27 1.27)
					(thickness 0.15)
				)
				(justify left bottom)
				(hide yes)
			)
		)
		(property "Footprint" "antmicro-footprints:C_0603_1608Metric_EIA"
			(at 392.43 110.49 0)
			(effects
				(font
					(size 1.27 1.27)
					(thickness 0.15)
				)
				(justify left bottom)
				(hide yes)
			)
		)
		(property "Datasheet" "https://product.samsungsem.com/mlcc/CL10A226MO7JZN.do"
			(at 394.97 110.49 0)
			(effects
				(font
					(size 1.27 1.27)
					(thickness 0.15)
				)
				(justify left bottom)
				(hide yes)
			)
		)
		(property "Description" "SMD Multilayer Ceramic Capacitor"
			(at 379.73 130.81 0)
			(effects
				(font
					(size 1.27 1.27)
				)
				(hide yes)
			)
		)
		(property "MPN" "CL10A226MO7JZNC"
			(at 397.51 110.49 0)
			(effects
				(font
					(size 1.27 1.27)
					(thickness 0.15)
				)
				(justify left bottom)
				(hide yes)
			)
		)
		(property "Manufacturer" "Samsung Electro-Mechanics"
			(at 400.05 110.49 0)
			(effects
				(font
					(size 1.27 1.27)
					(thickness 0.15)
				)
				(justify left bottom)
				(hide yes)
			)
		)
		(property "License" "Apache-2.0"
			(at 402.59 110.49 0)
			(effects
				(font
					(size 1.27 1.27)
					(thickness 0.15)
				)
				(justify left bottom)
				(hide yes)
			)
		)
		(property "Author" "Antmicro"
			(at 405.13 110.49 0)
			(effects
				(font
					(size 1.27 1.27)
					(thickness 0.15)
				)
				(justify left bottom)
				(hide yes)
			)
		)
		(property "Val" "22u"
			(at 382.27 129.5336 90)
			(effects
				(font
					(size 1.27 1.27)
					(thickness 0.15)
				)
				(justify right)
			)
		)
		(property "Voltage" "16V"
			(at 407.67 110.49 0)
			(effects
				(font
					(size 1.27 1.27)
				)
				(justify left bottom)
				(hide yes)
			)
		)
		(property "Dielectric" ""
			(at 410.21 110.49 0)
			(effects
				(font
					(size 1.27 1.27)
				)
				(justify left bottom)
				(hide yes)
			)
		)
		(pin "1"
		)
		(pin "2"
		)
		(instances
			(project "OCuLink to 10GbE adapter"
				(path ""
					(reference "C154")
					(unit 1)
				)
			)
			(project "thunderbolt-to-10gbe-adapter"
				(path ""
					(reference "C258")
					(unit 1)
				)
			)
		)
	)
	(symbol
		(lib_id "antmicroCapacitors0402:C_1u_25V_0402")
		(at 151.13 180.34 90)
		(unit 1)
		(exclude_from_sim no)
		(in_bom yes)
		(on_board yes)
		(dnp no)
		(property "Reference" "C206"
			(at 153.162 176.53 90)
			(effects
				(font
					(size 1.27 1.27)
					(thickness 0.15)
				)
				(justify right)
			)
		)
		(property "Value" "C_1u_25V_0402"
			(at 161.29 160.02 0)
			(effects
				(font
					(size 1.27 1.27)
					(thickness 0.15)
				)
				(justify left bottom)
				(hide yes)
			)
		)
		(property "Footprint" "antmicro-footprints:C_0402_1005Metric"
			(at 163.83 160.02 0)
			(effects
				(font
					(size 1.27 1.27)
					(thickness 0.15)
				)
				(justify left bottom)
				(hide yes)
			)
		)
		(property "Datasheet" "https://www.murata.com/products/productdetail?partno=GRM155R61E105KE11%23"
			(at 166.37 160.02 0)
			(effects
				(font
					(size 1.27 1.27)
					(thickness 0.15)
				)
				(justify left bottom)
				(hide yes)
			)
		)
		(property "Description" "SMD Multilayer Ceramic Capacitor, 1 µF, 25 V, 0402 [1005 Metric], ± 10%, X5R, GRM Series"
			(at 151.13 180.34 0)
			(effects
				(font
					(size 1.27 1.27)
				)
				(hide yes)
			)
		)
		(property "MPN" "GRM155R61E105KE11J"
			(at 168.91 160.02 0)
			(effects
				(font
					(size 1.27 1.27)
					(thickness 0.15)
				)
				(justify left bottom)
				(hide yes)
			)
		)
		(property "Manufacturer" "Murata"
			(at 171.45 160.02 0)
			(effects
				(font
					(size 1.27 1.27)
					(thickness 0.15)
				)
				(justify left bottom)
				(hide yes)
			)
		)
		(property "License" "Apache-2.0"
			(at 173.99 160.02 0)
			(effects
				(font
					(size 1.27 1.27)
					(thickness 0.15)
				)
				(justify left bottom)
				(hide yes)
			)
		)
		(property "Author" "Antmicro"
			(at 176.53 160.02 0)
			(effects
				(font
					(size 1.27 1.27)
					(thickness 0.15)
				)
				(justify left bottom)
				(hide yes)
			)
		)
		(property "Val" "1u"
			(at 153.162 179.07 90)
			(effects
				(font
					(size 1.27 1.27)
					(thickness 0.15)
				)
				(justify right)
			)
		)
		(property "Voltage" "25V"
			(at 179.07 160.02 0)
			(effects
				(font
					(size 1.27 1.27)
				)
				(justify left bottom)
				(hide yes)
			)
		)
		(property "Dielectric" "X5R"
			(at 181.61 160.02 0)
			(effects
				(font
					(size 1.27 1.27)
				)
				(justify left bottom)
				(hide yes)
			)
		)
		(pin "2"
		)
		(pin "1"
		)
		(instances
			(project "OCuLink to 10GbE adapter"
				(path ""
					(reference "C178")
					(unit 1)
				)
			)
			(project "thunderbolt-to-10gbe-adapter"
				(path ""
					(reference "C206")
					(unit 1)
				)
			)
		)
	)
	(symbol
		(lib_id "antmicroCapacitors0402:C_1u_25V_0402")
		(at 299.72 91.44 90)
		(unit 1)
		(exclude_from_sim no)
		(in_bom yes)
		(on_board yes)
		(dnp no)
		(property "Reference" "C213"
			(at 301.752 87.63 90)
			(effects
				(font
					(size 1.27 1.27)
					(thickness 0.15)
				)
				(justify right)
			)
		)
		(property "Value" "C_1u_25V_0402"
			(at 309.88 71.12 0)
			(effects
				(font
					(size 1.27 1.27)
					(thickness 0.15)
				)
				(justify left bottom)
				(hide yes)
			)
		)
		(property "Footprint" "antmicro-footprints:C_0402_1005Metric"
			(at 312.42 71.12 0)
			(effects
				(font
					(size 1.27 1.27)
					(thickness 0.15)
				)
				(justify left bottom)
				(hide yes)
			)
		)
		(property "Datasheet" "https://www.murata.com/products/productdetail?partno=GRM155R61E105KE11%23"
			(at 314.96 71.12 0)
			(effects
				(font
					(size 1.27 1.27)
					(thickness 0.15)
				)
				(justify left bottom)
				(hide yes)
			)
		)
		(property "Description" "SMD Multilayer Ceramic Capacitor, 1 µF, 25 V, 0402 [1005 Metric], ± 10%, X5R, GRM Series"
			(at 299.72 91.44 0)
			(effects
				(font
					(size 1.27 1.27)
				)
				(hide yes)
			)
		)
		(property "MPN" "GRM155R61E105KE11J"
			(at 317.5 71.12 0)
			(effects
				(font
					(size 1.27 1.27)
					(thickness 0.15)
				)
				(justify left bottom)
				(hide yes)
			)
		)
		(property "Manufacturer" "Murata"
			(at 320.04 71.12 0)
			(effects
				(font
					(size 1.27 1.27)
					(thickness 0.15)
				)
				(justify left bottom)
				(hide yes)
			)
		)
		(property "License" "Apache-2.0"
			(at 322.58 71.12 0)
			(effects
				(font
					(size 1.27 1.27)
					(thickness 0.15)
				)
				(justify left bottom)
				(hide yes)
			)
		)
		(property "Author" "Antmicro"
			(at 325.12 71.12 0)
			(effects
				(font
					(size 1.27 1.27)
					(thickness 0.15)
				)
				(justify left bottom)
				(hide yes)
			)
		)
		(property "Val" "1u"
			(at 301.752 90.17 90)
			(effects
				(font
					(size 1.27 1.27)
					(thickness 0.15)
				)
				(justify right)
			)
		)
		(property "Voltage" "25V"
			(at 327.66 71.12 0)
			(effects
				(font
					(size 1.27 1.27)
				)
				(justify left bottom)
				(hide yes)
			)
		)
		(property "Dielectric" "X5R"
			(at 330.2 71.12 0)
			(effects
				(font
					(size 1.27 1.27)
				)
				(justify left bottom)
				(hide yes)
			)
		)
		(pin "2"
		)
		(pin "1"
		)
		(instances
			(project "OCuLink to 10GbE adapter"
				(path ""
					(reference "C117")
					(unit 1)
				)
			)
			(project "thunderbolt-to-10gbe-adapter"
				(path ""
					(reference "C213")
					(unit 1)
				)
			)
		)
	)
	(symbol
		(lib_id "antmicropower:GND")
		(at 335.28 54.61 0)
		(unit 1)
		(exclude_from_sim no)
		(in_bom yes)
		(on_board yes)
		(dnp no)
		(property "Reference" "#PWR0318"
			(at 344.17 57.15 0)
			(effects
				(font
					(size 1.27 1.27)
					(thickness 0.15)
				)
				(justify left bottom)
				(hide yes)
			)
		)
		(property "Value" "GND"
			(at 335.28 58.42 0)
			(effects
				(font
					(size 1.27 1.27)
					(thickness 0.15)
				)
			)
		)
		(property "Footprint" ""
			(at 344.17 62.23 0)
			(effects
				(font
					(size 1.27 1.27)
					(thickness 0.15)
				)
				(justify left bottom)
				(hide yes)
			)
		)
		(property "Datasheet" ""
			(at 344.17 67.31 0)
			(effects
				(font
					(size 1.27 1.27)
					(thickness 0.15)
				)
				(justify left bottom)
				(hide yes)
			)
		)
		(property "Description" ""
			(at 335.28 54.61 0)
			(effects
				(font
					(size 1.27 1.27)
				)
				(hide yes)
			)
		)
		(property "Author" "Antmicro"
			(at 344.17 62.23 0)
			(effects
				(font
					(size 1.27 1.27)
					(thickness 0.15)
				)
				(justify left bottom)
				(hide yes)
			)
		)
		(property "License" "Apache-2.0"
			(at 344.17 64.77 0)
			(effects
				(font
					(size 1.27 1.27)
					(thickness 0.15)
				)
				(justify left bottom)
				(hide yes)
			)
		)
		(pin "1"
		)
		(instances
			(project "OCuLink to 10GbE adapter"
				(path ""
					(reference "#PWR0125")
					(unit 1)
				)
			)
			(project "thunderbolt-to-10gbe-adapter"
				(path ""
					(reference "#PWR0318")
					(unit 1)
				)
			)
		)
	)
	(symbol
		(lib_id "antmicroCapacitors0402:C_1u_25V_0402")
		(at 353.06 113.03 90)
		(unit 1)
		(exclude_from_sim no)
		(in_bom yes)
		(on_board yes)
		(dnp no)
		(property "Reference" "C243"
			(at 355.092 109.22 90)
			(effects
				(font
					(size 1.27 1.27)
					(thickness 0.15)
				)
				(justify right)
			)
		)
		(property "Value" "C_1u_25V_0402"
			(at 363.22 92.71 0)
			(effects
				(font
					(size 1.27 1.27)
					(thickness 0.15)
				)
				(justify left bottom)
				(hide yes)
			)
		)
		(property "Footprint" "antmicro-footprints:C_0402_1005Metric"
			(at 365.76 92.71 0)
			(effects
				(font
					(size 1.27 1.27)
					(thickness 0.15)
				)
				(justify left bottom)
				(hide yes)
			)
		)
		(property "Datasheet" "https://www.murata.com/products/productdetail?partno=GRM155R61E105KE11%23"
			(at 368.3 92.71 0)
			(effects
				(font
					(size 1.27 1.27)
					(thickness 0.15)
				)
				(justify left bottom)
				(hide yes)
			)
		)
		(property "Description" "SMD Multilayer Ceramic Capacitor, 1 µF, 25 V, 0402 [1005 Metric], ± 10%, X5R, GRM Series"
			(at 353.06 113.03 0)
			(effects
				(font
					(size 1.27 1.27)
				)
				(hide yes)
			)
		)
		(property "MPN" "GRM155R61E105KE11J"
			(at 370.84 92.71 0)
			(effects
				(font
					(size 1.27 1.27)
					(thickness 0.15)
				)
				(justify left bottom)
				(hide yes)
			)
		)
		(property "Manufacturer" "Murata"
			(at 373.38 92.71 0)
			(effects
				(font
					(size 1.27 1.27)
					(thickness 0.15)
				)
				(justify left bottom)
				(hide yes)
			)
		)
		(property "License" "Apache-2.0"
			(at 375.92 92.71 0)
			(effects
				(font
					(size 1.27 1.27)
					(thickness 0.15)
				)
				(justify left bottom)
				(hide yes)
			)
		)
		(property "Author" "Antmicro"
			(at 378.46 92.71 0)
			(effects
				(font
					(size 1.27 1.27)
					(thickness 0.15)
				)
				(justify left bottom)
				(hide yes)
			)
		)
		(property "Val" "1u"
			(at 355.092 111.76 90)
			(effects
				(font
					(size 1.27 1.27)
					(thickness 0.15)
				)
				(justify right)
			)
		)
		(property "Voltage" "25V"
			(at 381 92.71 0)
			(effects
				(font
					(size 1.27 1.27)
				)
				(justify left bottom)
				(hide yes)
			)
		)
		(property "Dielectric" "X5R"
			(at 383.54 92.71 0)
			(effects
				(font
					(size 1.27 1.27)
				)
				(justify left bottom)
				(hide yes)
			)
		)
		(pin "2"
		)
		(pin "1"
		)
		(instances
			(project "OCuLink to 10GbE adapter"
				(path ""
					(reference "C135")
					(unit 1)
				)
			)
			(project "thunderbolt-to-10gbe-adapter"
				(path ""
					(reference "C243")
					(unit 1)
				)
			)
		)
	)
	(symbol
		(lib_id "antmicroCapacitors0402:C_1u_25V_0402")
		(at 151.13 52.07 90)
		(unit 1)
		(exclude_from_sim no)
		(in_bom yes)
		(on_board yes)
		(dnp no)
		(property "Reference" "C202"
			(at 153.162 48.26 90)
			(effects
				(font
					(size 1.27 1.27)
					(thickness 0.15)
				)
				(justify right)
			)
		)
		(property "Value" "C_1u_25V_0402"
			(at 161.29 31.75 0)
			(effects
				(font
					(size 1.27 1.27)
					(thickness 0.15)
				)
				(justify left bottom)
				(hide yes)
			)
		)
		(property "Footprint" "antmicro-footprints:C_0402_1005Metric"
			(at 163.83 31.75 0)
			(effects
				(font
					(size 1.27 1.27)
					(thickness 0.15)
				)
				(justify left bottom)
				(hide yes)
			)
		)
		(property "Datasheet" "https://www.murata.com/products/productdetail?partno=GRM155R61E105KE11%23"
			(at 166.37 31.75 0)
			(effects
				(font
					(size 1.27 1.27)
					(thickness 0.15)
				)
				(justify left bottom)
				(hide yes)
			)
		)
		(property "Description" "SMD Multilayer Ceramic Capacitor, 1 µF, 25 V, 0402 [1005 Metric], ± 10%, X5R, GRM Series"
			(at 151.13 52.07 0)
			(effects
				(font
					(size 1.27 1.27)
				)
				(hide yes)
			)
		)
		(property "MPN" "GRM155R61E105KE11J"
			(at 168.91 31.75 0)
			(effects
				(font
					(size 1.27 1.27)
					(thickness 0.15)
				)
				(justify left bottom)
				(hide yes)
			)
		)
		(property "Manufacturer" "Murata"
			(at 171.45 31.75 0)
			(effects
				(font
					(size 1.27 1.27)
					(thickness 0.15)
				)
				(justify left bottom)
				(hide yes)
			)
		)
		(property "License" "Apache-2.0"
			(at 173.99 31.75 0)
			(effects
				(font
					(size 1.27 1.27)
					(thickness 0.15)
				)
				(justify left bottom)
				(hide yes)
			)
		)
		(property "Author" "Antmicro"
			(at 176.53 31.75 0)
			(effects
				(font
					(size 1.27 1.27)
					(thickness 0.15)
				)
				(justify left bottom)
				(hide yes)
			)
		)
		(property "Val" "1u"
			(at 153.162 50.8 90)
			(effects
				(font
					(size 1.27 1.27)
					(thickness 0.15)
				)
				(justify right)
			)
		)
		(property "Voltage" "25V"
			(at 179.07 31.75 0)
			(effects
				(font
					(size 1.27 1.27)
				)
				(justify left bottom)
				(hide yes)
			)
		)
		(property "Dielectric" "X5R"
			(at 181.61 31.75 0)
			(effects
				(font
					(size 1.27 1.27)
				)
				(justify left bottom)
				(hide yes)
			)
		)
		(pin "2"
		)
		(pin "1"
		)
		(instances
			(project "OCuLink to 10GbE adapter"
				(path ""
					(reference "C86")
					(unit 1)
				)
			)
			(project "thunderbolt-to-10gbe-adapter"
				(path ""
					(reference "C202")
					(unit 1)
				)
			)
		)
	)
	(symbol
		(lib_id "antmicroFixedInductors:L_4u7_1.55A_Bourns-SRP2512A")
		(at 80.01 199.39 0)
		(unit 1)
		(exclude_from_sim no)
		(in_bom yes)
		(on_board yes)
		(dnp no)
		(fields_autoplaced yes)
		(property "Reference" "L9"
			(at 82.55 194.31 0)
			(effects
				(font
					(size 1.27 1.27)
					(thickness 0.15)
				)
			)
		)
		(property "Value" "L_4u7_1.55A_Bourns-SRP2512A"
			(at 95.25 204.47 0)
			(effects
				(font
					(size 1.27 1.27)
					(thickness 0.15)
				)
				(justify left bottom)
				(hide yes)
			)
		)
		(property "Footprint" "antmicro-footprints:L_Bourns-SRP2512A"
			(at 95.25 207.01 0)
			(effects
				(font
					(size 1.27 1.27)
					(thickness 0.15)
				)
				(justify left bottom)
				(hide yes)
			)
		)
		(property "Datasheet" "https://www.bourns.com/docs/Product-Datasheets/srp2512a.pdf"
			(at 95.25 209.55 0)
			(effects
				(font
					(size 1.27 1.27)
					(thickness 0.15)
				)
				(justify left bottom)
				(hide yes)
			)
		)
		(property "Description" "4.7 µH Shielded Drum Core, Wirewound Inductor 1.55 A 235mOhm Max 1008 (2520 Metric)"
			(at 95.25 229.87 0)
			(effects
				(font
					(size 1.27 1.27)
				)
				(justify left bottom)
				(hide yes)
			)
		)
		(property "Val" "4u7/1.55A"
			(at 82.55 196.85 0)
			(effects
				(font
					(size 1.27 1.27)
					(thickness 0.15)
				)
			)
		)
		(property "Manufacturer" "Bourns"
			(at 95.25 212.09 0)
			(effects
				(font
					(size 1.27 1.27)
					(thickness 0.15)
				)
				(justify left bottom)
				(hide yes)
			)
		)
		(property "MPN" "SRP2512A-4R7M"
			(at 95.25 214.63 0)
			(effects
				(font
					(size 1.27 1.27)
					(thickness 0.15)
				)
				(justify left bottom)
				(hide yes)
			)
		)
		(property "ISat" "1.9 A"
			(at 95.25 217.17 0)
			(effects
				(font
					(size 1.27 1.27)
				)
				(justify left bottom)
				(hide yes)
			)
		)
		(property "IMax" "1.55 A"
			(at 95.25 219.71 0)
			(effects
				(font
					(size 1.27 1.27)
				)
				(justify left bottom)
				(hide yes)
			)
		)
		(property "Size" "2.5x2.0"
			(at 95.25 222.25 0)
			(effects
				(font
					(size 1.27 1.27)
				)
				(justify left bottom)
				(hide yes)
			)
		)
		(property "Author" "Antmicro"
			(at 95.25 224.79 0)
			(effects
				(font
					(size 1.27 1.27)
					(thickness 0.15)
				)
				(justify left bottom)
				(hide yes)
			)
		)
		(property "License" "Apache-2.0"
			(at 95.25 227.33 0)
			(effects
				(font
					(size 1.27 1.27)
					(thickness 0.15)
				)
				(justify left bottom)
				(hide yes)
			)
		)
		(pin "2"
		)
		(pin "1"
		)
		(instances
			(project "oculink-to-10gbe-adapter"
				(path ""
					(reference "L9")
					(unit 1)
				)
			)
			(project "thunderbolt-to-10gbe-adapter"
				(path ""
					(reference "L9")
					(unit 1)
				)
			)
		)
	)
	(symbol
		(lib_id "antmicroCapacitors0603:C_10u_10V_X7R_0603")
		(at 299.72 130.81 90)
		(unit 1)
		(exclude_from_sim no)
		(in_bom yes)
		(on_board yes)
		(dnp no)
		(property "Reference" "C215"
			(at 301.752 127 90)
			(effects
				(font
					(size 1.27 1.27)
					(thickness 0.15)
				)
				(justify right)
			)
		)
		(property "Value" "C_10u_10V_X7R_0603"
			(at 309.88 115.57 0)
			(effects
				(font
					(size 1.27 1.27)
					(thickness 0.15)
				)
				(justify left bottom)
				(hide yes)
			)
		)
		(property "Footprint" "antmicro-footprints:C_0603_1608Metric"
			(at 312.42 115.57 0)
			(effects
				(font
					(size 1.27 1.27)
					(thickness 0.15)
				)
				(justify left bottom)
				(hide yes)
			)
		)
		(property "Datasheet" "https://www.murata.com/products/productdetail?partno=GRM188Z71A106KA73%23"
			(at 314.96 115.57 0)
			(effects
				(font
					(size 1.27 1.27)
					(thickness 0.15)
				)
				(justify left bottom)
				(hide yes)
			)
		)
		(property "Description" "SMD Multilayer Ceramic Capacitor,  10µF, 10V, 0603, ±10%, X7R"
			(at 299.72 130.81 0)
			(effects
				(font
					(size 1.27 1.27)
				)
				(hide yes)
			)
		)
		(property "MPN" "GRM188Z71A106KA73D"
			(at 317.5 115.57 0)
			(effects
				(font
					(size 1.27 1.27)
					(thickness 0.15)
				)
				(justify left bottom)
				(hide yes)
			)
		)
		(property "Val" "10u"
			(at 301.752 129.54 90)
			(effects
				(font
					(size 1.27 1.27)
					(thickness 0.15)
				)
				(justify right)
			)
		)
		(property "Voltage" "10V"
			(at 320.04 115.57 0)
			(effects
				(font
					(size 1.27 1.27)
					(thickness 0.15)
				)
				(justify left bottom)
				(hide yes)
			)
		)
		(property "Dielectric" "X7R"
			(at 322.58 115.57 0)
			(effects
				(font
					(size 1.27 1.27)
					(thickness 0.15)
				)
				(justify left bottom)
				(hide yes)
			)
		)
		(property "Manufacturer" "Murata"
			(at 325.12 115.57 0)
			(effects
				(font
					(size 1.27 1.27)
					(thickness 0.15)
				)
				(justify left bottom)
				(hide yes)
			)
		)
		(property "License" "Apache-2.0"
			(at 327.66 115.57 0)
			(effects
				(font
					(size 1.27 1.27)
					(thickness 0.15)
				)
				(justify left bottom)
				(hide yes)
			)
		)
		(property "Author" "Antmicro"
			(at 330.2 115.57 0)
			(effects
				(font
					(size 1.27 1.27)
					(thickness 0.15)
				)
				(justify left bottom)
				(hide yes)
			)
		)
		(pin "1"
		)
		(pin "2"
		)
		(instances
			(project ""
				(path ""
					(reference "C146")
					(unit 1)
				)
			)
			(project "thunderbolt-to-10gbe-adapter"
				(path ""
					(reference "C215")
					(unit 1)
				)
			)
		)
	)
	(symbol
		(lib_id "antmicropower:GND")
		(at 55.88 54.61 0)
		(mirror y)
		(unit 1)
		(exclude_from_sim no)
		(in_bom yes)
		(on_board yes)
		(dnp no)
		(property "Reference" "#PWR0503"
			(at 46.99 57.15 0)
			(effects
				(font
					(size 1.27 1.27)
					(thickness 0.15)
				)
				(justify left bottom)
				(hide yes)
			)
		)
		(property "Value" "GND"
			(at 55.88 58.42 0)
			(effects
				(font
					(size 1.27 1.27)
					(thickness 0.15)
				)
			)
		)
		(property "Footprint" ""
			(at 46.99 62.23 0)
			(effects
				(font
					(size 1.27 1.27)
					(thickness 0.15)
				)
				(justify left bottom)
				(hide yes)
			)
		)
		(property "Datasheet" ""
			(at 46.99 67.31 0)
			(effects
				(font
					(size 1.27 1.27)
					(thickness 0.15)
				)
				(justify left bottom)
				(hide yes)
			)
		)
		(property "Description" ""
			(at 55.88 54.61 0)
			(effects
				(font
					(size 1.27 1.27)
				)
				(hide yes)
			)
		)
		(property "Author" "Antmicro"
			(at 46.99 62.23 0)
			(effects
				(font
					(size 1.27 1.27)
					(thickness 0.15)
				)
				(justify left bottom)
				(hide yes)
			)
		)
		(property "License" "Apache-2.0"
			(at 46.99 64.77 0)
			(effects
				(font
					(size 1.27 1.27)
					(thickness 0.15)
				)
				(justify left bottom)
				(hide yes)
			)
		)
		(pin "1"
		)
		(instances
			(project "thunderbolt-to-10gbe-adapter"
				(path ""
					(reference "#PWR0503")
					(unit 1)
				)
			)
		)
	)
	(symbol
		(lib_id "antmicropower:VCC")
		(at 276.86 78.74 0)
		(unit 1)
		(exclude_from_sim no)
		(in_bom yes)
		(on_board yes)
		(dnp no)
		(property "Reference" "#PWR0292"
			(at 276.86 82.55 0)
			(effects
				(font
					(size 1.27 1.27)
				)
				(hide yes)
			)
		)
		(property "Value" "VCCD"
			(at 276.86 74.93 0)
			(effects
				(font
					(size 1.27 1.27)
				)
			)
		)
		(property "Footprint" ""
			(at 276.86 78.74 0)
			(effects
				(font
					(size 1.27 1.27)
				)
				(hide yes)
			)
		)
		(property "Datasheet" ""
			(at 276.86 78.74 0)
			(effects
				(font
					(size 1.27 1.27)
				)
				(hide yes)
			)
		)
		(property "Description" ""
			(at 276.86 78.74 0)
			(effects
				(font
					(size 1.27 1.27)
				)
				(hide yes)
			)
		)
		(pin "1"
		)
		(instances
			(project "OCuLink to 10GbE adapter"
				(path ""
					(reference "#PWR0161")
					(unit 1)
				)
			)
			(project "thunderbolt-to-10gbe-adapter"
				(path ""
					(reference "#PWR0292")
					(unit 1)
				)
			)
		)
	)
	(symbol
		(lib_id "antmicroCapacitors0402:C_1u_25V_0402")
		(at 326.39 73.66 90)
		(unit 1)
		(exclude_from_sim no)
		(in_bom yes)
		(on_board yes)
		(dnp no)
		(property "Reference" "C228"
			(at 328.422 69.85 90)
			(effects
				(font
					(size 1.27 1.27)
					(thickness 0.15)
				)
				(justify right)
			)
		)
		(property "Value" "C_1u_25V_0402"
			(at 336.55 53.34 0)
			(effects
				(font
					(size 1.27 1.27)
					(thickness 0.15)
				)
				(justify left bottom)
				(hide yes)
			)
		)
		(property "Footprint" "antmicro-footprints:C_0402_1005Metric"
			(at 339.09 53.34 0)
			(effects
				(font
					(size 1.27 1.27)
					(thickness 0.15)
				)
				(justify left bottom)
				(hide yes)
			)
		)
		(property "Datasheet" "https://www.murata.com/products/productdetail?partno=GRM155R61E105KE11%23"
			(at 341.63 53.34 0)
			(effects
				(font
					(size 1.27 1.27)
					(thickness 0.15)
				)
				(justify left bottom)
				(hide yes)
			)
		)
		(property "Description" "SMD Multilayer Ceramic Capacitor, 1 µF, 25 V, 0402 [1005 Metric], ± 10%, X5R, GRM Series"
			(at 326.39 73.66 0)
			(effects
				(font
					(size 1.27 1.27)
				)
				(hide yes)
			)
		)
		(property "MPN" "GRM155R61E105KE11J"
			(at 344.17 53.34 0)
			(effects
				(font
					(size 1.27 1.27)
					(thickness 0.15)
				)
				(justify left bottom)
				(hide yes)
			)
		)
		(property "Manufacturer" "Murata"
			(at 346.71 53.34 0)
			(effects
				(font
					(size 1.27 1.27)
					(thickness 0.15)
				)
				(justify left bottom)
				(hide yes)
			)
		)
		(property "License" "Apache-2.0"
			(at 349.25 53.34 0)
			(effects
				(font
					(size 1.27 1.27)
					(thickness 0.15)
				)
				(justify left bottom)
				(hide yes)
			)
		)
		(property "Author" "Antmicro"
			(at 351.79 53.34 0)
			(effects
				(font
					(size 1.27 1.27)
					(thickness 0.15)
				)
				(justify left bottom)
				(hide yes)
			)
		)
		(property "Val" "1u"
			(at 328.422 72.39 90)
			(effects
				(font
					(size 1.27 1.27)
					(thickness 0.15)
				)
				(justify right)
			)
		)
		(property "Voltage" "25V"
			(at 354.33 53.34 0)
			(effects
				(font
					(size 1.27 1.27)
				)
				(justify left bottom)
				(hide yes)
			)
		)
		(property "Dielectric" "X5R"
			(at 356.87 53.34 0)
			(effects
				(font
					(size 1.27 1.27)
				)
				(justify left bottom)
				(hide yes)
			)
		)
		(pin "2"
		)
		(pin "1"
		)
		(instances
			(project "OCuLink to 10GbE adapter"
				(path ""
					(reference "C108")
					(unit 1)
				)
			)
			(project "thunderbolt-to-10gbe-adapter"
				(path ""
					(reference "C228")
					(unit 1)
				)
			)
		)
	)
	(symbol
		(lib_id "antmicropower:GND")
		(at 90.17 209.55 0)
		(unit 1)
		(exclude_from_sim no)
		(in_bom yes)
		(on_board yes)
		(dnp no)
		(property "Reference" "#PWR0243"
			(at 99.06 212.09 0)
			(effects
				(font
					(size 1.27 1.27)
					(thickness 0.15)
				)
				(justify left bottom)
				(hide yes)
			)
		)
		(property "Value" "GND"
			(at 90.17 213.36 0)
			(effects
				(font
					(size 1.27 1.27)
					(thickness 0.15)
				)
			)
		)
		(property "Footprint" ""
			(at 99.06 217.17 0)
			(effects
				(font
					(size 1.27 1.27)
					(thickness 0.15)
				)
				(justify left bottom)
				(hide yes)
			)
		)
		(property "Datasheet" ""
			(at 99.06 222.25 0)
			(effects
				(font
					(size 1.27 1.27)
					(thickness 0.15)
				)
				(justify left bottom)
				(hide yes)
			)
		)
		(property "Description" ""
			(at 90.17 209.55 0)
			(effects
				(font
					(size 1.27 1.27)
				)
				(hide yes)
			)
		)
		(property "Author" "Antmicro"
			(at 99.06 217.17 0)
			(effects
				(font
					(size 1.27 1.27)
					(thickness 0.15)
				)
				(justify left bottom)
				(hide yes)
			)
		)
		(property "License" "Apache-2.0"
			(at 99.06 219.71 0)
			(effects
				(font
					(size 1.27 1.27)
					(thickness 0.15)
				)
				(justify left bottom)
				(hide yes)
			)
		)
		(pin "1"
		)
		(instances
			(project "OCuLink to 10GbE adapter"
				(path ""
					(reference "#PWR0233")
					(unit 1)
				)
			)
			(project "thunderbolt-to-10gbe-adapter"
				(path ""
					(reference "#PWR0243")
					(unit 1)
				)
			)
		)
	)
	(symbol
		(lib_id "antmicroCapacitors0402:C_1u_25V_0402")
		(at 133.35 127 90)
		(unit 1)
		(exclude_from_sim no)
		(in_bom yes)
		(on_board yes)
		(dnp no)
		(property "Reference" "C192"
			(at 135.128 123.19 90)
			(effects
				(font
					(size 1.27 1.27)
					(thickness 0.15)
				)
				(justify right)
			)
		)
		(property "Value" "C_1u_25V_0402"
			(at 143.51 106.68 0)
			(effects
				(font
					(size 1.27 1.27)
					(thickness 0.15)
				)
				(justify left bottom)
				(hide yes)
			)
		)
		(property "Footprint" "antmicro-footprints:C_0402_1005Metric"
			(at 146.05 106.68 0)
			(effects
				(font
					(size 1.27 1.27)
					(thickness 0.15)
				)
				(justify left bottom)
				(hide yes)
			)
		)
		(property "Datasheet" "https://www.murata.com/products/productdetail?partno=GRM155R61E105KE11%23"
			(at 148.59 106.68 0)
			(effects
				(font
					(size 1.27 1.27)
					(thickness 0.15)
				)
				(justify left bottom)
				(hide yes)
			)
		)
		(property "Description" "SMD Multilayer Ceramic Capacitor, 1 µF, 25 V, 0402 [1005 Metric], ± 10%, X5R, GRM Series"
			(at 133.35 127 0)
			(effects
				(font
					(size 1.27 1.27)
				)
				(hide yes)
			)
		)
		(property "MPN" "GRM155R61E105KE11J"
			(at 151.13 106.68 0)
			(effects
				(font
					(size 1.27 1.27)
					(thickness 0.15)
				)
				(justify left bottom)
				(hide yes)
			)
		)
		(property "Manufacturer" "Murata"
			(at 153.67 106.68 0)
			(effects
				(font
					(size 1.27 1.27)
					(thickness 0.15)
				)
				(justify left bottom)
				(hide yes)
			)
		)
		(property "License" "Apache-2.0"
			(at 156.21 106.68 0)
			(effects
				(font
					(size 1.27 1.27)
					(thickness 0.15)
				)
				(justify left bottom)
				(hide yes)
			)
		)
		(property "Author" "Antmicro"
			(at 158.75 106.68 0)
			(effects
				(font
					(size 1.27 1.27)
					(thickness 0.15)
				)
				(justify left bottom)
				(hide yes)
			)
		)
		(property "Val" "1u"
			(at 135.128 125.73 90)
			(effects
				(font
					(size 1.27 1.27)
					(thickness 0.15)
				)
				(justify right)
			)
		)
		(property "Voltage" "25V"
			(at 161.29 106.68 0)
			(effects
				(font
					(size 1.27 1.27)
				)
				(justify left bottom)
				(hide yes)
			)
		)
		(property "Dielectric" "X5R"
			(at 163.83 106.68 0)
			(effects
				(font
					(size 1.27 1.27)
				)
				(justify left bottom)
				(hide yes)
			)
		)
		(pin "2"
		)
		(pin "1"
		)
		(instances
			(project "OCuLink to 10GbE adapter"
				(path ""
					(reference "C143")
					(unit 1)
				)
			)
			(project "thunderbolt-to-10gbe-adapter"
				(path ""
					(reference "C192")
					(unit 1)
				)
			)
		)
	)
	(symbol
		(lib_id "antmicroCapacitors0603:C_22u_16V_0603")
		(at 353.06 91.44 90)
		(unit 1)
		(exclude_from_sim no)
		(in_bom yes)
		(on_board yes)
		(dnp no)
		(fields_autoplaced yes)
		(property "Reference" "C242"
			(at 355.6 87.6236 90)
			(effects
				(font
					(size 1.27 1.27)
					(thickness 0.15)
				)
				(justify right)
			)
		)
		(property "Value" "C_22u_16V_0603"
			(at 363.22 71.12 0)
			(effects
				(font
					(size 1.27 1.27)
					(thickness 0.15)
				)
				(justify left bottom)
				(hide yes)
			)
		)
		(property "Footprint" "antmicro-footprints:C_0603_1608Metric_EIA"
			(at 365.76 71.12 0)
			(effects
				(font
					(size 1.27 1.27)
					(thickness 0.15)
				)
				(justify left bottom)
				(hide yes)
			)
		)
		(property "Datasheet" "https://product.samsungsem.com/mlcc/CL10A226MO7JZN.do"
			(at 368.3 71.12 0)
			(effects
				(font
					(size 1.27 1.27)
					(thickness 0.15)
				)
				(justify left bottom)
				(hide yes)
			)
		)
		(property "Description" "SMD Multilayer Ceramic Capacitor"
			(at 353.06 91.44 0)
			(effects
				(font
					(size 1.27 1.27)
				)
				(hide yes)
			)
		)
		(property "MPN" "CL10A226MO7JZNC"
			(at 370.84 71.12 0)
			(effects
				(font
					(size 1.27 1.27)
					(thickness 0.15)
				)
				(justify left bottom)
				(hide yes)
			)
		)
		(property "Manufacturer" "Samsung Electro-Mechanics"
			(at 373.38 71.12 0)
			(effects
				(font
					(size 1.27 1.27)
					(thickness 0.15)
				)
				(justify left bottom)
				(hide yes)
			)
		)
		(property "License" "Apache-2.0"
			(at 375.92 71.12 0)
			(effects
				(font
					(size 1.27 1.27)
					(thickness 0.15)
				)
				(justify left bottom)
				(hide yes)
			)
		)
		(property "Author" "Antmicro"
			(at 378.46 71.12 0)
			(effects
				(font
					(size 1.27 1.27)
					(thickness 0.15)
				)
				(justify left bottom)
				(hide yes)
			)
		)
		(property "Val" "22u"
			(at 355.6 90.1636 90)
			(effects
				(font
					(size 1.27 1.27)
					(thickness 0.15)
				)
				(justify right)
			)
		)
		(property "Voltage" "16V"
			(at 381 71.12 0)
			(effects
				(font
					(size 1.27 1.27)
				)
				(justify left bottom)
				(hide yes)
			)
		)
		(property "Dielectric" ""
			(at 383.54 71.12 0)
			(effects
				(font
					(size 1.27 1.27)
				)
				(justify left bottom)
				(hide yes)
			)
		)
		(pin "1"
		)
		(pin "2"
		)
		(instances
			(project "OCuLink to 10GbE adapter"
				(path ""
					(reference "C122")
					(unit 1)
				)
			)
			(project "thunderbolt-to-10gbe-adapter"
				(path ""
					(reference "C242")
					(unit 1)
				)
			)
		)
	)
	(symbol
		(lib_id "antmicropower:GND")
		(at 86.36 156.21 0)
		(unit 1)
		(exclude_from_sim no)
		(in_bom yes)
		(on_board yes)
		(dnp no)
		(property "Reference" "#PWR0234"
			(at 95.25 158.75 0)
			(effects
				(font
					(size 1.27 1.27)
					(thickness 0.15)
				)
				(justify left bottom)
				(hide yes)
			)
		)
		(property "Value" "GND"
			(at 86.36 160.02 0)
			(effects
				(font
					(size 1.27 1.27)
					(thickness 0.15)
				)
			)
		)
		(property "Footprint" ""
			(at 95.25 163.83 0)
			(effects
				(font
					(size 1.27 1.27)
					(thickness 0.15)
				)
				(justify left bottom)
				(hide yes)
			)
		)
		(property "Datasheet" ""
			(at 95.25 168.91 0)
			(effects
				(font
					(size 1.27 1.27)
					(thickness 0.15)
				)
				(justify left bottom)
				(hide yes)
			)
		)
		(property "Description" ""
			(at 86.36 156.21 0)
			(effects
				(font
					(size 1.27 1.27)
				)
				(hide yes)
			)
		)
		(property "Author" "Antmicro"
			(at 95.25 163.83 0)
			(effects
				(font
					(size 1.27 1.27)
					(thickness 0.15)
				)
				(justify left bottom)
				(hide yes)
			)
		)
		(property "License" "Apache-2.0"
			(at 95.25 166.37 0)
			(effects
				(font
					(size 1.27 1.27)
					(thickness 0.15)
				)
				(justify left bottom)
				(hide yes)
			)
		)
		(pin "1"
		)
		(instances
			(project "OCuLink to 10GbE adapter"
				(path ""
					(reference "#PWR0213")
					(unit 1)
				)
			)
			(project "thunderbolt-to-10gbe-adapter"
				(path ""
					(reference "#PWR0234")
					(unit 1)
				)
			)
		)
	)
	(symbol
		(lib_id "antmicropower:GND")
		(at 97.79 129.54 0)
		(unit 1)
		(exclude_from_sim no)
		(in_bom yes)
		(on_board yes)
		(dnp no)
		(property "Reference" "#PWR0248"
			(at 106.68 132.08 0)
			(effects
				(font
					(size 1.27 1.27)
					(thickness 0.15)
				)
				(justify left bottom)
				(hide yes)
			)
		)
		(property "Value" "GND"
			(at 97.79 133.35 0)
			(effects
				(font
					(size 1.27 1.27)
					(thickness 0.15)
				)
			)
		)
		(property "Footprint" ""
			(at 106.68 137.16 0)
			(effects
				(font
					(size 1.27 1.27)
					(thickness 0.15)
				)
				(justify left bottom)
				(hide yes)
			)
		)
		(property "Datasheet" ""
			(at 106.68 142.24 0)
			(effects
				(font
					(size 1.27 1.27)
					(thickness 0.15)
				)
				(justify left bottom)
				(hide yes)
			)
		)
		(property "Description" ""
			(at 97.79 129.54 0)
			(effects
				(font
					(size 1.27 1.27)
				)
				(hide yes)
			)
		)
		(property "Author" "Antmicro"
			(at 106.68 137.16 0)
			(effects
				(font
					(size 1.27 1.27)
					(thickness 0.15)
				)
				(justify left bottom)
				(hide yes)
			)
		)
		(property "License" "Apache-2.0"
			(at 106.68 139.7 0)
			(effects
				(font
					(size 1.27 1.27)
					(thickness 0.15)
				)
				(justify left bottom)
				(hide yes)
			)
		)
		(pin "1"
		)
		(instances
			(project "OCuLink to 10GbE adapter"
				(path ""
					(reference "#PWR0189")
					(unit 1)
				)
			)
			(project "thunderbolt-to-10gbe-adapter"
				(path ""
					(reference "#PWR0248")
					(unit 1)
				)
			)
		)
	)
	(symbol
		(lib_id "antmicroCapacitors0402:C_1u_25V_0402")
		(at 326.39 113.03 90)
		(unit 1)
		(exclude_from_sim no)
		(in_bom yes)
		(on_board yes)
		(dnp no)
		(property "Reference" "C230"
			(at 328.422 109.22 90)
			(effects
				(font
					(size 1.27 1.27)
					(thickness 0.15)
				)
				(justify right)
			)
		)
		(property "Value" "C_1u_25V_0402"
			(at 336.55 92.71 0)
			(effects
				(font
					(size 1.27 1.27)
					(thickness 0.15)
				)
				(justify left bottom)
				(hide yes)
			)
		)
		(property "Footprint" "antmicro-footprints:C_0402_1005Metric"
			(at 339.09 92.71 0)
			(effects
				(font
					(size 1.27 1.27)
					(thickness 0.15)
				)
				(justify left bottom)
				(hide yes)
			)
		)
		(property "Datasheet" "https://www.murata.com/products/productdetail?partno=GRM155R61E105KE11%23"
			(at 341.63 92.71 0)
			(effects
				(font
					(size 1.27 1.27)
					(thickness 0.15)
				)
				(justify left bottom)
				(hide yes)
			)
		)
		(property "Description" "SMD Multilayer Ceramic Capacitor, 1 µF, 25 V, 0402 [1005 Metric], ± 10%, X5R, GRM Series"
			(at 326.39 113.03 0)
			(effects
				(font
					(size 1.27 1.27)
				)
				(hide yes)
			)
		)
		(property "MPN" "GRM155R61E105KE11J"
			(at 344.17 92.71 0)
			(effects
				(font
					(size 1.27 1.27)
					(thickness 0.15)
				)
				(justify left bottom)
				(hide yes)
			)
		)
		(property "Manufacturer" "Murata"
			(at 346.71 92.71 0)
			(effects
				(font
					(size 1.27 1.27)
					(thickness 0.15)
				)
				(justify left bottom)
				(hide yes)
			)
		)
		(property "License" "Apache-2.0"
			(at 349.25 92.71 0)
			(effects
				(font
					(size 1.27 1.27)
					(thickness 0.15)
				)
				(justify left bottom)
				(hide yes)
			)
		)
		(property "Author" "Antmicro"
			(at 351.79 92.71 0)
			(effects
				(font
					(size 1.27 1.27)
					(thickness 0.15)
				)
				(justify left bottom)
				(hide yes)
			)
		)
		(property "Val" "1u"
			(at 328.422 111.76 90)
			(effects
				(font
					(size 1.27 1.27)
					(thickness 0.15)
				)
				(justify right)
			)
		)
		(property "Voltage" "25V"
			(at 354.33 92.71 0)
			(effects
				(font
					(size 1.27 1.27)
				)
				(justify left bottom)
				(hide yes)
			)
		)
		(property "Dielectric" "X5R"
			(at 356.87 92.71 0)
			(effects
				(font
					(size 1.27 1.27)
				)
				(justify left bottom)
				(hide yes)
			)
		)
		(pin "2"
		)
		(pin "1"
		)
		(instances
			(project "OCuLink to 10GbE adapter"
				(path ""
					(reference "C132")
					(unit 1)
				)
			)
			(project "thunderbolt-to-10gbe-adapter"
				(path ""
					(reference "C230")
					(unit 1)
				)
			)
		)
	)
	(symbol
		(lib_id "antmicroCapacitors0603:C_22u_16V_0603")
		(at 397.51 91.44 90)
		(unit 1)
		(exclude_from_sim no)
		(in_bom yes)
		(on_board yes)
		(dnp no)
		(fields_autoplaced yes)
		(property "Reference" "C265"
			(at 400.05 87.6236 90)
			(effects
				(font
					(size 1.27 1.27)
					(thickness 0.15)
				)
				(justify right)
			)
		)
		(property "Value" "C_22u_16V_0603"
			(at 407.67 71.12 0)
			(effects
				(font
					(size 1.27 1.27)
					(thickness 0.15)
				)
				(justify left bottom)
				(hide yes)
			)
		)
		(property "Footprint" "antmicro-footprints:C_0603_1608Metric_EIA"
			(at 410.21 71.12 0)
			(effects
				(font
					(size 1.27 1.27)
					(thickness 0.15)
				)
				(justify left bottom)
				(hide yes)
			)
		)
		(property "Datasheet" "https://product.samsungsem.com/mlcc/CL10A226MO7JZN.do"
			(at 412.75 71.12 0)
			(effects
				(font
					(size 1.27 1.27)
					(thickness 0.15)
				)
				(justify left bottom)
				(hide yes)
			)
		)
		(property "Description" "SMD Multilayer Ceramic Capacitor"
			(at 397.51 91.44 0)
			(effects
				(font
					(size 1.27 1.27)
				)
				(hide yes)
			)
		)
		(property "MPN" "CL10A226MO7JZNC"
			(at 415.29 71.12 0)
			(effects
				(font
					(size 1.27 1.27)
					(thickness 0.15)
				)
				(justify left bottom)
				(hide yes)
			)
		)
		(property "Manufacturer" "Samsung Electro-Mechanics"
			(at 417.83 71.12 0)
			(effects
				(font
					(size 1.27 1.27)
					(thickness 0.15)
				)
				(justify left bottom)
				(hide yes)
			)
		)
		(property "License" "Apache-2.0"
			(at 420.37 71.12 0)
			(effects
				(font
					(size 1.27 1.27)
					(thickness 0.15)
				)
				(justify left bottom)
				(hide yes)
			)
		)
		(property "Author" "Antmicro"
			(at 422.91 71.12 0)
			(effects
				(font
					(size 1.27 1.27)
					(thickness 0.15)
				)
				(justify left bottom)
				(hide yes)
			)
		)
		(property "Val" "22u"
			(at 400.05 90.1636 90)
			(effects
				(font
					(size 1.27 1.27)
					(thickness 0.15)
				)
				(justify right)
			)
		)
		(property "Voltage" "16V"
			(at 425.45 71.12 0)
			(effects
				(font
					(size 1.27 1.27)
				)
				(justify left bottom)
				(hide yes)
			)
		)
		(property "Dielectric" ""
			(at 427.99 71.12 0)
			(effects
				(font
					(size 1.27 1.27)
				)
				(justify left bottom)
				(hide yes)
			)
		)
		(pin "1"
		)
		(pin "2"
		)
		(instances
			(project ""
				(path ""
					(reference "C127")
					(unit 1)
				)
			)
			(project "thunderbolt-to-10gbe-adapter"
				(path ""
					(reference "C265")
					(unit 1)
				)
			)
		)
	)
	(symbol
		(lib_id "antmicropower:GND")
		(at 142.24 182.88 0)
		(unit 1)
		(exclude_from_sim no)
		(in_bom yes)
		(on_board yes)
		(dnp no)
		(property "Reference" "#PWR0271"
			(at 151.13 185.42 0)
			(effects
				(font
					(size 1.27 1.27)
					(thickness 0.15)
				)
				(justify left bottom)
				(hide yes)
			)
		)
		(property "Value" "GND"
			(at 142.24 186.69 0)
			(effects
				(font
					(size 1.27 1.27)
					(thickness 0.15)
				)
			)
		)
		(property "Footprint" ""
			(at 151.13 190.5 0)
			(effects
				(font
					(size 1.27 1.27)
					(thickness 0.15)
				)
				(justify left bottom)
				(hide yes)
			)
		)
		(property "Datasheet" ""
			(at 151.13 195.58 0)
			(effects
				(font
					(size 1.27 1.27)
					(thickness 0.15)
				)
				(justify left bottom)
				(hide yes)
			)
		)
		(property "Description" ""
			(at 142.24 182.88 0)
			(effects
				(font
					(size 1.27 1.27)
				)
				(hide yes)
			)
		)
		(property "Author" "Antmicro"
			(at 151.13 190.5 0)
			(effects
				(font
					(size 1.27 1.27)
					(thickness 0.15)
				)
				(justify left bottom)
				(hide yes)
			)
		)
		(property "License" "Apache-2.0"
			(at 151.13 193.04 0)
			(effects
				(font
					(size 1.27 1.27)
					(thickness 0.15)
				)
				(justify left bottom)
				(hide yes)
			)
		)
		(pin "1"
		)
		(instances
			(project "OCuLink to 10GbE adapter"
				(path ""
					(reference "#PWR0229")
					(unit 1)
				)
			)
			(project "thunderbolt-to-10gbe-adapter"
				(path ""
					(reference "#PWR0271")
					(unit 1)
				)
			)
		)
	)
	(symbol
		(lib_id "antmicroCapacitors0603:C_10u_10V_X7R_0603")
		(at 106.68 180.34 90)
		(unit 1)
		(exclude_from_sim no)
		(in_bom yes)
		(on_board yes)
		(dnp no)
		(property "Reference" "C181"
			(at 108.458 176.53 90)
			(effects
				(font
					(size 1.27 1.27)
					(thickness 0.15)
				)
				(justify right)
			)
		)
		(property "Value" "C_10u_10V_X7R_0603"
			(at 116.84 165.1 0)
			(effects
				(font
					(size 1.27 1.27)
					(thickness 0.15)
				)
				(justify left bottom)
				(hide yes)
			)
		)
		(property "Footprint" "antmicro-footprints:C_0603_1608Metric"
			(at 119.38 165.1 0)
			(effects
				(font
					(size 1.27 1.27)
					(thickness 0.15)
				)
				(justify left bottom)
				(hide yes)
			)
		)
		(property "Datasheet" "https://www.murata.com/products/productdetail?partno=GRM188Z71A106KA73%23"
			(at 121.92 165.1 0)
			(effects
				(font
					(size 1.27 1.27)
					(thickness 0.15)
				)
				(justify left bottom)
				(hide yes)
			)
		)
		(property "Description" "SMD Multilayer Ceramic Capacitor,  10µF, 10V, 0603, ±10%, X7R"
			(at 106.68 180.34 0)
			(effects
				(font
					(size 1.27 1.27)
				)
				(hide yes)
			)
		)
		(property "MPN" "GRM188Z71A106KA73D"
			(at 124.46 165.1 0)
			(effects
				(font
					(size 1.27 1.27)
					(thickness 0.15)
				)
				(justify left bottom)
				(hide yes)
			)
		)
		(property "Val" "10u"
			(at 108.458 179.07 90)
			(effects
				(font
					(size 1.27 1.27)
					(thickness 0.15)
				)
				(justify right)
			)
		)
		(property "Voltage" "10V"
			(at 127 165.1 0)
			(effects
				(font
					(size 1.27 1.27)
					(thickness 0.15)
				)
				(justify left bottom)
				(hide yes)
			)
		)
		(property "Dielectric" "X7R"
			(at 129.54 165.1 0)
			(effects
				(font
					(size 1.27 1.27)
					(thickness 0.15)
				)
				(justify left bottom)
				(hide yes)
			)
		)
		(property "Manufacturer" "Murata"
			(at 132.08 165.1 0)
			(effects
				(font
					(size 1.27 1.27)
					(thickness 0.15)
				)
				(justify left bottom)
				(hide yes)
			)
		)
		(property "License" "Apache-2.0"
			(at 134.62 165.1 0)
			(effects
				(font
					(size 1.27 1.27)
					(thickness 0.15)
				)
				(justify left bottom)
				(hide yes)
			)
		)
		(property "Author" "Antmicro"
			(at 137.16 165.1 0)
			(effects
				(font
					(size 1.27 1.27)
					(thickness 0.15)
				)
				(justify left bottom)
				(hide yes)
			)
		)
		(pin "1"
		)
		(pin "2"
		)
		(instances
			(project "OCuLink to 10GbE adapter"
				(path ""
					(reference "C174")
					(unit 1)
				)
			)
			(project "thunderbolt-to-10gbe-adapter"
				(path ""
					(reference "C181")
					(unit 1)
				)
			)
		)
	)
	(symbol
		(lib_id "antmicropower:PWR_FLAG")
		(at 110.49 144.78 0)
		(unit 1)
		(exclude_from_sim no)
		(in_bom yes)
		(on_board yes)
		(dnp no)
		(fields_autoplaced yes)
		(property "Reference" "#FLG025"
			(at 110.49 142.875 0)
			(effects
				(font
					(size 1.27 1.27)
				)
				(hide yes)
			)
		)
		(property "Value" "PWR_FLAG"
			(at 110.49 139.7 0)
			(effects
				(font
					(size 1.27 1.27)
				)
			)
		)
		(property "Footprint" ""
			(at 110.49 144.78 0)
			(effects
				(font
					(size 1.27 1.27)
				)
				(hide yes)
			)
		)
		(property "Datasheet" ""
			(at 110.49 144.78 0)
			(effects
				(font
					(size 1.27 1.27)
				)
				(hide yes)
			)
		)
		(property "Description" ""
			(at 110.49 147.32 0)
			(effects
				(font
					(size 1.27 1.27)
				)
				(justify left bottom)
				(hide yes)
			)
		)
		(pin "1"
		)
		(instances
			(project "OCuLink to 10GbE adapter"
				(path ""
					(reference "#FLG015")
					(unit 1)
				)
			)
			(project "thunderbolt-to-10gbe-adapter"
				(path ""
					(reference "#FLG025")
					(unit 1)
				)
			)
		)
	)
	(symbol
		(lib_id "antmicropower:GND")
		(at 397.51 76.2 0)
		(unit 1)
		(exclude_from_sim no)
		(in_bom yes)
		(on_board yes)
		(dnp no)
		(property "Reference" "#PWR0350"
			(at 406.4 78.74 0)
			(effects
				(font
					(size 1.27 1.27)
					(thickness 0.15)
				)
				(justify left bottom)
				(hide yes)
			)
		)
		(property "Value" "GND"
			(at 397.51 80.01 0)
			(effects
				(font
					(size 1.27 1.27)
					(thickness 0.15)
				)
			)
		)
		(property "Footprint" ""
			(at 406.4 83.82 0)
			(effects
				(font
					(size 1.27 1.27)
					(thickness 0.15)
				)
				(justify left bottom)
				(hide yes)
			)
		)
		(property "Datasheet" ""
			(at 406.4 88.9 0)
			(effects
				(font
					(size 1.27 1.27)
					(thickness 0.15)
				)
				(justify left bottom)
				(hide yes)
			)
		)
		(property "Description" ""
			(at 397.51 76.2 0)
			(effects
				(font
					(size 1.27 1.27)
				)
				(hide yes)
			)
		)
		(property "Author" "Antmicro"
			(at 406.4 83.82 0)
			(effects
				(font
					(size 1.27 1.27)
					(thickness 0.15)
				)
				(justify left bottom)
				(hide yes)
			)
		)
		(property "License" "Apache-2.0"
			(at 406.4 86.36 0)
			(effects
				(font
					(size 1.27 1.27)
					(thickness 0.15)
				)
				(justify left bottom)
				(hide yes)
			)
		)
		(pin "1"
		)
		(instances
			(project "OCuLink to 10GbE adapter"
				(path ""
					(reference "#PWR0150")
					(unit 1)
				)
			)
			(project "thunderbolt-to-10gbe-adapter"
				(path ""
					(reference "#PWR0350")
					(unit 1)
				)
			)
		)
	)
	(symbol
		(lib_id "antmicropower:GND")
		(at 64.77 54.61 0)
		(mirror y)
		(unit 1)
		(exclude_from_sim no)
		(in_bom yes)
		(on_board yes)
		(dnp no)
		(property "Reference" "#PWR0502"
			(at 55.88 57.15 0)
			(effects
				(font
					(size 1.27 1.27)
					(thickness 0.15)
				)
				(justify left bottom)
				(hide yes)
			)
		)
		(property "Value" "GND"
			(at 64.77 58.42 0)
			(effects
				(font
					(size 1.27 1.27)
					(thickness 0.15)
				)
			)
		)
		(property "Footprint" ""
			(at 55.88 62.23 0)
			(effects
				(font
					(size 1.27 1.27)
					(thickness 0.15)
				)
				(justify left bottom)
				(hide yes)
			)
		)
		(property "Datasheet" ""
			(at 55.88 67.31 0)
			(effects
				(font
					(size 1.27 1.27)
					(thickness 0.15)
				)
				(justify left bottom)
				(hide yes)
			)
		)
		(property "Description" ""
			(at 64.77 54.61 0)
			(effects
				(font
					(size 1.27 1.27)
				)
				(hide yes)
			)
		)
		(property "Author" "Antmicro"
			(at 55.88 62.23 0)
			(effects
				(font
					(size 1.27 1.27)
					(thickness 0.15)
				)
				(justify left bottom)
				(hide yes)
			)
		)
		(property "License" "Apache-2.0"
			(at 55.88 64.77 0)
			(effects
				(font
					(size 1.27 1.27)
					(thickness 0.15)
				)
				(justify left bottom)
				(hide yes)
			)
		)
		(pin "1"
		)
		(instances
			(project "thunderbolt-to-10gbe-adapter"
				(path ""
					(reference "#PWR0502")
					(unit 1)
				)
			)
		)
	)
	(symbol
		(lib_id "antmicroCapacitors0402:C_1u_25V_0402")
		(at 88.9 100.33 90)
		(unit 1)
		(exclude_from_sim no)
		(in_bom yes)
		(on_board yes)
		(dnp no)
		(property "Reference" "C168"
			(at 90.932 96.52 90)
			(effects
				(font
					(size 1.27 1.27)
					(thickness 0.15)
				)
				(justify right)
			)
		)
		(property "Value" "C_1u_25V_0402"
			(at 99.06 80.01 0)
			(effects
				(font
					(size 1.27 1.27)
					(thickness 0.15)
				)
				(justify left bottom)
				(hide yes)
			)
		)
		(property "Footprint" "antmicro-footprints:C_0402_1005Metric"
			(at 101.6 80.01 0)
			(effects
				(font
					(size 1.27 1.27)
					(thickness 0.15)
				)
				(justify left bottom)
				(hide yes)
			)
		)
		(property "Datasheet" "https://www.murata.com/products/productdetail?partno=GRM155R61E105KE11%23"
			(at 104.14 80.01 0)
			(effects
				(font
					(size 1.27 1.27)
					(thickness 0.15)
				)
				(justify left bottom)
				(hide yes)
			)
		)
		(property "Description" "SMD Multilayer Ceramic Capacitor, 1 µF, 25 V, 0402 [1005 Metric], ± 10%, X5R, GRM Series"
			(at 88.9 100.33 0)
			(effects
				(font
					(size 1.27 1.27)
				)
				(hide yes)
			)
		)
		(property "MPN" "GRM155R61E105KE11J"
			(at 106.68 80.01 0)
			(effects
				(font
					(size 1.27 1.27)
					(thickness 0.15)
				)
				(justify left bottom)
				(hide yes)
			)
		)
		(property "Manufacturer" "Murata"
			(at 109.22 80.01 0)
			(effects
				(font
					(size 1.27 1.27)
					(thickness 0.15)
				)
				(justify left bottom)
				(hide yes)
			)
		)
		(property "License" "Apache-2.0"
			(at 111.76 80.01 0)
			(effects
				(font
					(size 1.27 1.27)
					(thickness 0.15)
				)
				(justify left bottom)
				(hide yes)
			)
		)
		(property "Author" "Antmicro"
			(at 114.3 80.01 0)
			(effects
				(font
					(size 1.27 1.27)
					(thickness 0.15)
				)
				(justify left bottom)
				(hide yes)
			)
		)
		(property "Val" "1u"
			(at 90.932 99.06 90)
			(effects
				(font
					(size 1.27 1.27)
					(thickness 0.15)
				)
				(justify right)
			)
		)
		(property "Voltage" "25V"
			(at 116.84 80.01 0)
			(effects
				(font
					(size 1.27 1.27)
				)
				(justify left bottom)
				(hide yes)
			)
		)
		(property "Dielectric" "X5R"
			(at 119.38 80.01 0)
			(effects
				(font
					(size 1.27 1.27)
				)
				(justify left bottom)
				(hide yes)
			)
		)
		(pin "2"
		)
		(pin "1"
		)
		(instances
			(project "OCuLink to 10GbE adapter"
				(path ""
					(reference "C129")
					(unit 1)
				)
			)
			(project "thunderbolt-to-10gbe-adapter"
				(path ""
					(reference "C168")
					(unit 1)
				)
			)
		)
	)
	(symbol
		(lib_id "antmicroCapacitors0402:C_1u_25V_0402")
		(at 344.17 52.07 90)
		(unit 1)
		(exclude_from_sim no)
		(in_bom yes)
		(on_board yes)
		(dnp no)
		(property "Reference" "C236"
			(at 346.202 48.26 90)
			(effects
				(font
					(size 1.27 1.27)
					(thickness 0.15)
				)
				(justify right)
			)
		)
		(property "Value" "C_1u_25V_0402"
			(at 354.33 31.75 0)
			(effects
				(font
					(size 1.27 1.27)
					(thickness 0.15)
				)
				(justify left bottom)
				(hide yes)
			)
		)
		(property "Footprint" "antmicro-footprints:C_0402_1005Metric"
			(at 356.87 31.75 0)
			(effects
				(font
					(size 1.27 1.27)
					(thickness 0.15)
				)
				(justify left bottom)
				(hide yes)
			)
		)
		(property "Datasheet" "https://www.murata.com/products/productdetail?partno=GRM155R61E105KE11%23"
			(at 359.41 31.75 0)
			(effects
				(font
					(size 1.27 1.27)
					(thickness 0.15)
				)
				(justify left bottom)
				(hide yes)
			)
		)
		(property "Description" "SMD Multilayer Ceramic Capacitor, 1 µF, 25 V, 0402 [1005 Metric], ± 10%, X5R, GRM Series"
			(at 344.17 52.07 0)
			(effects
				(font
					(size 1.27 1.27)
				)
				(hide yes)
			)
		)
		(property "MPN" "GRM155R61E105KE11J"
			(at 361.95 31.75 0)
			(effects
				(font
					(size 1.27 1.27)
					(thickness 0.15)
				)
				(justify left bottom)
				(hide yes)
			)
		)
		(property "Manufacturer" "Murata"
			(at 364.49 31.75 0)
			(effects
				(font
					(size 1.27 1.27)
					(thickness 0.15)
				)
				(justify left bottom)
				(hide yes)
			)
		)
		(property "License" "Apache-2.0"
			(at 367.03 31.75 0)
			(effects
				(font
					(size 1.27 1.27)
					(thickness 0.15)
				)
				(justify left bottom)
				(hide yes)
			)
		)
		(property "Author" "Antmicro"
			(at 369.57 31.75 0)
			(effects
				(font
					(size 1.27 1.27)
					(thickness 0.15)
				)
				(justify left bottom)
				(hide yes)
			)
		)
		(property "Val" "1u"
			(at 346.202 50.8 90)
			(effects
				(font
					(size 1.27 1.27)
					(thickness 0.15)
				)
				(justify right)
			)
		)
		(property "Voltage" "25V"
			(at 372.11 31.75 0)
			(effects
				(font
					(size 1.27 1.27)
				)
				(justify left bottom)
				(hide yes)
			)
		)
		(property "Dielectric" "X5R"
			(at 374.65 31.75 0)
			(effects
				(font
					(size 1.27 1.27)
				)
				(justify left bottom)
				(hide yes)
			)
		)
		(pin "2"
		)
		(pin "1"
		)
		(instances
			(project "OCuLink to 10GbE adapter"
				(path ""
					(reference "C92")
					(unit 1)
				)
			)
			(project "thunderbolt-to-10gbe-adapter"
				(path ""
					(reference "C236")
					(unit 1)
				)
			)
		)
	)
	(symbol
		(lib_id "antmicropower:GND")
		(at 326.39 76.2 0)
		(unit 1)
		(exclude_from_sim no)
		(in_bom yes)
		(on_board yes)
		(dnp no)
		(property "Reference" "#PWR0314"
			(at 335.28 78.74 0)
			(effects
				(font
					(size 1.27 1.27)
					(thickness 0.15)
				)
				(justify left bottom)
				(hide yes)
			)
		)
		(property "Value" "GND"
			(at 326.39 80.01 0)
			(effects
				(font
					(size 1.27 1.27)
					(thickness 0.15)
				)
			)
		)
		(property "Footprint" ""
			(at 335.28 83.82 0)
			(effects
				(font
					(size 1.27 1.27)
					(thickness 0.15)
				)
				(justify left bottom)
				(hide yes)
			)
		)
		(property "Datasheet" ""
			(at 335.28 88.9 0)
			(effects
				(font
					(size 1.27 1.27)
					(thickness 0.15)
				)
				(justify left bottom)
				(hide yes)
			)
		)
		(property "Description" ""
			(at 326.39 76.2 0)
			(effects
				(font
					(size 1.27 1.27)
				)
				(hide yes)
			)
		)
		(property "Author" "Antmicro"
			(at 335.28 83.82 0)
			(effects
				(font
					(size 1.27 1.27)
					(thickness 0.15)
				)
				(justify left bottom)
				(hide yes)
			)
		)
		(property "License" "Apache-2.0"
			(at 335.28 86.36 0)
			(effects
				(font
					(size 1.27 1.27)
					(thickness 0.15)
				)
				(justify left bottom)
				(hide yes)
			)
		)
		(pin "1"
		)
		(instances
			(project "OCuLink to 10GbE adapter"
				(path ""
					(reference "#PWR0142")
					(unit 1)
				)
			)
			(project "thunderbolt-to-10gbe-adapter"
				(path ""
					(reference "#PWR0314")
					(unit 1)
				)
			)
		)
	)
	(symbol
		(lib_id "antmicroFerriteBeadsandChips:FB_33Z_3A_Murata-BLM18PG_0603")
		(at 90.17 146.05 0)
		(unit 1)
		(exclude_from_sim no)
		(in_bom yes)
		(on_board yes)
		(dnp no)
		(fields_autoplaced yes)
		(property "Reference" "FB6"
			(at 92.6719 139.7 0)
			(effects
				(font
					(size 1.27 1.27)
					(thickness 0.15)
				)
			)
		)
		(property "Value" "FB_33Z_3A_Murata-BLM18PG_0603"
			(at 104.14 148.59 0)
			(effects
				(font
					(size 1.27 1.27)
					(thickness 0.15)
				)
				(justify left bottom)
				(hide yes)
			)
		)
		(property "Footprint" "antmicro-footprints:FB_0603_1608Metric"
			(at 104.14 153.67 0)
			(effects
				(font
					(size 1.27 1.27)
					(thickness 0.15)
				)
				(justify left bottom)
				(hide yes)
			)
		)
		(property "Datasheet" "https://www.murata.com/products/productdata/8796737273886/QNFA9101.pdf?1649080818000"
			(at 104.14 156.21 0)
			(effects
				(font
					(size 1.27 1.27)
					(thickness 0.15)
				)
				(justify left bottom)
				(hide yes)
			)
		)
		(property "Description" "Ferrite Bead, 0603 [1608 Metric], 33 ohm, 3 A, BLM18PG, 0.025 ohm, ± 25%, DC power line"
			(at 90.17 146.05 0)
			(effects
				(font
					(size 1.27 1.27)
				)
				(hide yes)
			)
		)
		(property "Val" "33Z/3A"
			(at 92.6719 142.24 0)
			(effects
				(font
					(size 1.27 1.27)
				)
			)
		)
		(property "MPN" "BLM18PG330SH1D"
			(at 104.14 158.75 0)
			(effects
				(font
					(size 1.27 1.27)
					(thickness 0.15)
				)
				(justify left bottom)
				(hide yes)
			)
		)
		(property "Manufacturer" "Murata"
			(at 104.14 161.29 0)
			(effects
				(font
					(size 1.27 1.27)
					(thickness 0.15)
				)
				(justify left bottom)
				(hide yes)
			)
		)
		(property "Current" ""
			(at 110.49 168.91 0)
			(effects
				(font
					(size 1.27 1.27)
					(thickness 0.15)
				)
				(justify left bottom)
				(hide yes)
			)
		)
		(property "Author" "Antmicro"
			(at 104.14 163.83 0)
			(effects
				(font
					(size 1.27 1.27)
					(thickness 0.15)
				)
				(justify left bottom)
				(hide yes)
			)
		)
		(property "License" "Apache-2.0"
			(at 104.14 166.37 0)
			(effects
				(font
					(size 1.27 1.27)
					(thickness 0.15)
				)
				(justify left bottom)
				(hide yes)
			)
		)
		(pin "2"
		)
		(pin "1"
		)
		(instances
			(project "OCuLink to 10GbE adapter"
				(path ""
					(reference "FB5")
					(unit 1)
				)
			)
			(project "thunderbolt-to-10gbe-adapter"
				(path ""
					(reference "FB6")
					(unit 1)
				)
			)
		)
	)
	(symbol
		(lib_id "antmicropower:GND")
		(at 133.35 156.21 0)
		(unit 1)
		(exclude_from_sim no)
		(in_bom yes)
		(on_board yes)
		(dnp no)
		(property "Reference" "#PWR0264"
			(at 142.24 158.75 0)
			(effects
				(font
					(size 1.27 1.27)
					(thickness 0.15)
				)
				(justify left bottom)
				(hide yes)
			)
		)
		(property "Value" "GND"
			(at 133.35 160.02 0)
			(effects
				(font
					(size 1.27 1.27)
					(thickness 0.15)
				)
			)
		)
		(property "Footprint" ""
			(at 142.24 163.83 0)
			(effects
				(font
					(size 1.27 1.27)
					(thickness 0.15)
				)
				(justify left bottom)
				(hide yes)
			)
		)
		(property "Datasheet" ""
			(at 142.24 168.91 0)
			(effects
				(font
					(size 1.27 1.27)
					(thickness 0.15)
				)
				(justify left bottom)
				(hide yes)
			)
		)
		(property "Description" ""
			(at 133.35 156.21 0)
			(effects
				(font
					(size 1.27 1.27)
				)
				(hide yes)
			)
		)
		(property "Author" "Antmicro"
			(at 142.24 163.83 0)
			(effects
				(font
					(size 1.27 1.27)
					(thickness 0.15)
				)
				(justify left bottom)
				(hide yes)
			)
		)
		(property "License" "Apache-2.0"
			(at 142.24 166.37 0)
			(effects
				(font
					(size 1.27 1.27)
					(thickness 0.15)
				)
				(justify left bottom)
				(hide yes)
			)
		)
		(pin "1"
		)
		(instances
			(project "OCuLink to 10GbE adapter"
				(path ""
					(reference "#PWR0218")
					(unit 1)
				)
			)
			(project "thunderbolt-to-10gbe-adapter"
				(path ""
					(reference "#PWR0264")
					(unit 1)
				)
			)
		)
	)
	(symbol
		(lib_id "antmicropower:GND")
		(at 151.13 156.21 0)
		(unit 1)
		(exclude_from_sim no)
		(in_bom yes)
		(on_board yes)
		(dnp no)
		(property "Reference" "#PWR0276"
			(at 160.02 158.75 0)
			(effects
				(font
					(size 1.27 1.27)
					(thickness 0.15)
				)
				(justify left bottom)
				(hide yes)
			)
		)
		(property "Value" "GND"
			(at 151.13 160.02 0)
			(effects
				(font
					(size 1.27 1.27)
					(thickness 0.15)
				)
			)
		)
		(property "Footprint" ""
			(at 160.02 163.83 0)
			(effects
				(font
					(size 1.27 1.27)
					(thickness 0.15)
				)
				(justify left bottom)
				(hide yes)
			)
		)
		(property "Datasheet" ""
			(at 160.02 168.91 0)
			(effects
				(font
					(size 1.27 1.27)
					(thickness 0.15)
				)
				(justify left bottom)
				(hide yes)
			)
		)
		(property "Description" ""
			(at 151.13 156.21 0)
			(effects
				(font
					(size 1.27 1.27)
				)
				(hide yes)
			)
		)
		(property "Author" "Antmicro"
			(at 160.02 163.83 0)
			(effects
				(font
					(size 1.27 1.27)
					(thickness 0.15)
				)
				(justify left bottom)
				(hide yes)
			)
		)
		(property "License" "Apache-2.0"
			(at 160.02 166.37 0)
			(effects
				(font
					(size 1.27 1.27)
					(thickness 0.15)
				)
				(justify left bottom)
				(hide yes)
			)
		)
		(pin "1"
		)
		(instances
			(project "OCuLink to 10GbE adapter"
				(path ""
					(reference "#PWR0220")
					(unit 1)
				)
			)
			(project "thunderbolt-to-10gbe-adapter"
				(path ""
					(reference "#PWR0276")
					(unit 1)
				)
			)
		)
	)
	(symbol
		(lib_id "antmicropower:GND")
		(at 299.72 115.57 0)
		(unit 1)
		(exclude_from_sim no)
		(in_bom yes)
		(on_board yes)
		(dnp no)
		(property "Reference" "#PWR0300"
			(at 308.61 118.11 0)
			(effects
				(font
					(size 1.27 1.27)
					(thickness 0.15)
				)
				(justify left bottom)
				(hide yes)
			)
		)
		(property "Value" "GND"
			(at 299.72 119.38 0)
			(effects
				(font
					(size 1.27 1.27)
					(thickness 0.15)
				)
			)
		)
		(property "Footprint" ""
			(at 308.61 123.19 0)
			(effects
				(font
					(size 1.27 1.27)
					(thickness 0.15)
				)
				(justify left bottom)
				(hide yes)
			)
		)
		(property "Datasheet" ""
			(at 308.61 128.27 0)
			(effects
				(font
					(size 1.27 1.27)
					(thickness 0.15)
				)
				(justify left bottom)
				(hide yes)
			)
		)
		(property "Description" ""
			(at 299.72 115.57 0)
			(effects
				(font
					(size 1.27 1.27)
				)
				(hide yes)
			)
		)
		(property "Author" "Antmicro"
			(at 308.61 123.19 0)
			(effects
				(font
					(size 1.27 1.27)
					(thickness 0.15)
				)
				(justify left bottom)
				(hide yes)
			)
		)
		(property "License" "Apache-2.0"
			(at 308.61 125.73 0)
			(effects
				(font
					(size 1.27 1.27)
					(thickness 0.15)
				)
				(justify left bottom)
				(hide yes)
			)
		)
		(pin "1"
		)
		(instances
			(project "OCuLink to 10GbE adapter"
				(path ""
					(reference "#PWR0178")
					(unit 1)
				)
			)
			(project "thunderbolt-to-10gbe-adapter"
				(path ""
					(reference "#PWR0300")
					(unit 1)
				)
			)
		)
	)
	(symbol
		(lib_id "antmicroCapacitorspol:C_Pol_100u_6V_KEMET-T490-A")
		(at 38.1 46.99 90)
		(mirror x)
		(unit 1)
		(exclude_from_sim no)
		(in_bom yes)
		(on_board yes)
		(dnp no)
		(fields_autoplaced yes)
		(property "Reference" "C331"
			(at 35.56 47.7266 90)
			(effects
				(font
					(size 1.27 1.27)
					(thickness 0.15)
				)
				(justify left)
			)
		)
		(property "Value" "C_Pol_100u_6V_KEMET-T490-A"
			(at 40.64 60.96 0)
			(effects
				(font
					(size 1.27 1.27)
					(thickness 0.15)
				)
				(justify left bottom)
				(hide yes)
			)
		)
		(property "Footprint" "antmicro-footprints:C_Pol_EIA-A"
			(at 45.72 60.96 0)
			(effects
				(font
					(size 1.27 1.27)
					(thickness 0.15)
				)
				(justify left bottom)
				(hide yes)
			)
		)
		(property "Datasheet" "https://www.kemet.com/en/us/capacitors/product/T490A107M006ATE800.html"
			(at 48.26 60.96 0)
			(effects
				(font
					(size 1.27 1.27)
					(thickness 0.15)
				)
				(justify left bottom)
				(hide yes)
			)
		)
		(property "Description" "Surface Mount Tantalum Capacitor,  Solid SMD 6V 100uF 1206 20% ESR=800mOhms"
			(at 63.5 60.96 0)
			(effects
				(font
					(size 1.27 1.27)
				)
				(justify left bottom)
				(hide yes)
			)
		)
		(property "Val" "100u"
			(at 35.56 50.2666 90)
			(effects
				(font
					(size 1.27 1.27)
					(thickness 0.15)
				)
				(justify left)
			)
		)
		(property "MPN" "T490A107M006ATE800"
			(at 50.8 60.96 0)
			(effects
				(font
					(size 1.27 1.27)
					(thickness 0.15)
				)
				(justify left bottom)
				(hide yes)
			)
		)
		(property "Manufacturer" "KEMET"
			(at 53.34 60.96 0)
			(effects
				(font
					(size 1.27 1.27)
					(thickness 0.15)
				)
				(justify left bottom)
				(hide yes)
			)
		)
		(property "License" "Apache-2.0"
			(at 55.88 60.96 0)
			(effects
				(font
					(size 1.27 1.27)
					(thickness 0.15)
				)
				(justify left bottom)
				(hide yes)
			)
		)
		(property "Author" "Antmicro"
			(at 58.42 60.96 0)
			(effects
				(font
					(size 1.27 1.27)
					(thickness 0.15)
				)
				(justify left bottom)
				(hide yes)
			)
		)
		(property "Voltage" "6V"
			(at 60.96 60.96 0)
			(effects
				(font
					(size 1.27 1.27)
				)
				(justify left bottom)
				(hide yes)
			)
		)
		(property "Dielectric" "template_dielectric"
			(at 63.5 60.96 0)
			(effects
				(font
					(size 1.27 1.27)
				)
				(justify left bottom)
				(hide yes)
			)
		)
		(pin "2"
		)
		(pin "1"
		)
		(instances
			(project "thunderbolt-to-10gbe-adapter"
				(path ""
					(reference "C331")
					(unit 1)
				)
			)
		)
	)
	(symbol
		(lib_id "antmicropower:VDD")
		(at 171.45 116.84 0)
		(unit 1)
		(exclude_from_sim no)
		(in_bom yes)
		(on_board yes)
		(dnp no)
		(property "Reference" "#PWR0280"
			(at 171.45 120.65 0)
			(effects
				(font
					(size 1.27 1.27)
				)
				(hide yes)
			)
		)
		(property "Value" "PLL_VDD"
			(at 171.45 113.03 0)
			(effects
				(font
					(size 1.27 1.27)
				)
			)
		)
		(property "Footprint" ""
			(at 171.45 116.84 0)
			(effects
				(font
					(size 1.27 1.27)
				)
				(hide yes)
			)
		)
		(property "Datasheet" ""
			(at 171.45 116.84 0)
			(effects
				(font
					(size 1.27 1.27)
				)
				(hide yes)
			)
		)
		(property "Description" ""
			(at 171.45 116.84 0)
			(effects
				(font
					(size 1.27 1.27)
				)
				(hide yes)
			)
		)
		(pin "1"
		)
		(instances
			(project "OCuLink to 10GbE adapter"
				(path ""
					(reference "#PWR0151")
					(unit 1)
				)
			)
			(project "thunderbolt-to-10gbe-adapter"
				(path ""
					(reference "#PWR0280")
					(unit 1)
				)
			)
		)
	)
	(symbol
		(lib_id "antmicropower:GND")
		(at 97.79 182.88 0)
		(unit 1)
		(exclude_from_sim no)
		(in_bom yes)
		(on_board yes)
		(dnp no)
		(property "Reference" "#PWR0250"
			(at 106.68 185.42 0)
			(effects
				(font
					(size 1.27 1.27)
					(thickness 0.15)
				)
				(justify left bottom)
				(hide yes)
			)
		)
		(property "Value" "GND"
			(at 97.79 186.69 0)
			(effects
				(font
					(size 1.27 1.27)
					(thickness 0.15)
				)
			)
		)
		(property "Footprint" ""
			(at 106.68 190.5 0)
			(effects
				(font
					(size 1.27 1.27)
					(thickness 0.15)
				)
				(justify left bottom)
				(hide yes)
			)
		)
		(property "Datasheet" ""
			(at 106.68 195.58 0)
			(effects
				(font
					(size 1.27 1.27)
					(thickness 0.15)
				)
				(justify left bottom)
				(hide yes)
			)
		)
		(property "Description" ""
			(at 97.79 182.88 0)
			(effects
				(font
					(size 1.27 1.27)
				)
				(hide yes)
			)
		)
		(property "Author" "Antmicro"
			(at 106.68 190.5 0)
			(effects
				(font
					(size 1.27 1.27)
					(thickness 0.15)
				)
				(justify left bottom)
				(hide yes)
			)
		)
		(property "License" "Apache-2.0"
			(at 106.68 193.04 0)
			(effects
				(font
					(size 1.27 1.27)
					(thickness 0.15)
				)
				(justify left bottom)
				(hide yes)
			)
		)
		(pin "1"
		)
		(instances
			(project "OCuLink to 10GbE adapter"
				(path ""
					(reference "#PWR0225")
					(unit 1)
				)
			)
			(project "thunderbolt-to-10gbe-adapter"
				(path ""
					(reference "#PWR0250")
					(unit 1)
				)
			)
		)
	)
	(symbol
		(lib_id "antmicroCapacitors0402:C_100n_0402")
		(at 299.72 113.03 90)
		(unit 1)
		(exclude_from_sim no)
		(in_bom yes)
		(on_board yes)
		(dnp no)
		(property "Reference" "C214"
			(at 301.752 109.22 90)
			(effects
				(font
					(size 1.27 1.27)
					(thickness 0.15)
				)
				(justify right)
			)
		)
		(property "Value" "C_100n_0402"
			(at 322.58 97.79 0)
			(effects
				(font
					(size 1.27 1.27)
					(thickness 0.15)
				)
				(justify left bottom)
				(hide yes)
			)
		)
		(property "Footprint" "antmicro-footprints:C_0402_1005Metric"
			(at 325.12 97.79 0)
			(effects
				(font
					(size 1.27 1.27)
					(thickness 0.15)
				)
				(justify left bottom)
				(hide yes)
			)
		)
		(property "Datasheet" "https://www.murata.com/products/productdetail?partno=GRM155R61H104KE14%23"
			(at 327.66 97.79 0)
			(effects
				(font
					(size 1.27 1.27)
					(thickness 0.15)
				)
				(justify left bottom)
				(hide yes)
			)
		)
		(property "Description" "SMD Multilayer Ceramic Capacitor, 0.1 µF, 50 V, 0402 [1005 Metric], ± 10%, X5R, GRM Series"
			(at 299.72 113.03 0)
			(effects
				(font
					(size 1.27 1.27)
				)
				(hide yes)
			)
		)
		(property "MPN" "GRM155R61H104KE14D"
			(at 330.2 97.79 0)
			(effects
				(font
					(size 1.27 1.27)
					(thickness 0.15)
				)
				(justify left bottom)
				(hide yes)
			)
		)
		(property "Val" "100n"
			(at 301.752 111.76 90)
			(effects
				(font
					(size 1.27 1.27)
					(thickness 0.15)
				)
				(justify right)
			)
		)
		(property "Voltage" "50V"
			(at 309.88 97.79 0)
			(effects
				(font
					(size 1.27 1.27)
					(thickness 0.15)
				)
				(justify left bottom)
				(hide yes)
			)
		)
		(property "Dielectric" "X5R"
			(at 312.42 97.79 0)
			(effects
				(font
					(size 1.27 1.27)
					(thickness 0.15)
				)
				(justify left bottom)
				(hide yes)
			)
		)
		(property "Manufacturer" "Murata"
			(at 314.96 97.79 0)
			(effects
				(font
					(size 1.27 1.27)
					(thickness 0.15)
				)
				(justify left bottom)
				(hide yes)
			)
		)
		(property "License" "Apache-2.0"
			(at 317.5 97.79 0)
			(effects
				(font
					(size 1.27 1.27)
					(thickness 0.15)
				)
				(justify left bottom)
				(hide yes)
			)
		)
		(property "Author" "Antmicro"
			(at 320.04 97.79 0)
			(effects
				(font
					(size 1.27 1.27)
					(thickness 0.15)
				)
				(justify left bottom)
				(hide yes)
			)
		)
		(pin "1"
		)
		(pin "2"
		)
		(instances
			(project ""
				(path ""
					(reference "C130")
					(unit 1)
				)
			)
			(project "thunderbolt-to-10gbe-adapter"
				(path ""
					(reference "C214")
					(unit 1)
				)
			)
		)
	)
	(symbol
		(lib_id "antmicroCapacitors0402:C_1u_25V_0402")
		(at 133.35 180.34 90)
		(unit 1)
		(exclude_from_sim no)
		(in_bom yes)
		(on_board yes)
		(dnp no)
		(property "Reference" "C194"
			(at 135.382 176.53 90)
			(effects
				(font
					(size 1.27 1.27)
					(thickness 0.15)
				)
				(justify right)
			)
		)
		(property "Value" "C_1u_25V_0402"
			(at 143.51 160.02 0)
			(effects
				(font
					(size 1.27 1.27)
					(thickness 0.15)
				)
				(justify left bottom)
				(hide yes)
			)
		)
		(property "Footprint" "antmicro-footprints:C_0402_1005Metric"
			(at 146.05 160.02 0)
			(effects
				(font
					(size 1.27 1.27)
					(thickness 0.15)
				)
				(justify left bottom)
				(hide yes)
			)
		)
		(property "Datasheet" "https://www.murata.com/products/productdetail?partno=GRM155R61E105KE11%23"
			(at 148.59 160.02 0)
			(effects
				(font
					(size 1.27 1.27)
					(thickness 0.15)
				)
				(justify left bottom)
				(hide yes)
			)
		)
		(property "Description" "SMD Multilayer Ceramic Capacitor, 1 µF, 25 V, 0402 [1005 Metric], ± 10%, X5R, GRM Series"
			(at 133.35 180.34 0)
			(effects
				(font
					(size 1.27 1.27)
				)
				(hide yes)
			)
		)
		(property "MPN" "GRM155R61E105KE11J"
			(at 151.13 160.02 0)
			(effects
				(font
					(size 1.27 1.27)
					(thickness 0.15)
				)
				(justify left bottom)
				(hide yes)
			)
		)
		(property "Manufacturer" "Murata"
			(at 153.67 160.02 0)
			(effects
				(font
					(size 1.27 1.27)
					(thickness 0.15)
				)
				(justify left bottom)
				(hide yes)
			)
		)
		(property "License" "Apache-2.0"
			(at 156.21 160.02 0)
			(effects
				(font
					(size 1.27 1.27)
					(thickness 0.15)
				)
				(justify left bottom)
				(hide yes)
			)
		)
		(property "Author" "Antmicro"
			(at 158.75 160.02 0)
			(effects
				(font
					(size 1.27 1.27)
					(thickness 0.15)
				)
				(justify left bottom)
				(hide yes)
			)
		)
		(property "Val" "1u"
			(at 135.382 179.07 90)
			(effects
				(font
					(size 1.27 1.27)
					(thickness 0.15)
				)
				(justify right)
			)
		)
		(property "Voltage" "25V"
			(at 161.29 160.02 0)
			(effects
				(font
					(size 1.27 1.27)
				)
				(justify left bottom)
				(hide yes)
			)
		)
		(property "Dielectric" "X5R"
			(at 163.83 160.02 0)
			(effects
				(font
					(size 1.27 1.27)
				)
				(justify left bottom)
				(hide yes)
			)
		)
		(pin "2"
		)
		(pin "1"
		)
		(instances
			(project "OCuLink to 10GbE adapter"
				(path ""
					(reference "C176")
					(unit 1)
				)
			)
			(project "thunderbolt-to-10gbe-adapter"
				(path ""
					(reference "C194")
					(unit 1)
				)
			)
		)
	)
	(symbol
		(lib_id "antmicropower:GND")
		(at 326.39 133.35 0)
		(unit 1)
		(exclude_from_sim no)
		(in_bom yes)
		(on_board yes)
		(dnp no)
		(property "Reference" "#PWR0317"
			(at 335.28 135.89 0)
			(effects
				(font
					(size 1.27 1.27)
					(thickness 0.15)
				)
				(justify left bottom)
				(hide yes)
			)
		)
		(property "Value" "GND"
			(at 326.39 137.16 0)
			(effects
				(font
					(size 1.27 1.27)
					(thickness 0.15)
				)
			)
		)
		(property "Footprint" ""
			(at 335.28 140.97 0)
			(effects
				(font
					(size 1.27 1.27)
					(thickness 0.15)
				)
				(justify left bottom)
				(hide yes)
			)
		)
		(property "Datasheet" ""
			(at 335.28 146.05 0)
			(effects
				(font
					(size 1.27 1.27)
					(thickness 0.15)
				)
				(justify left bottom)
				(hide yes)
			)
		)
		(property "Description" ""
			(at 326.39 133.35 0)
			(effects
				(font
					(size 1.27 1.27)
				)
				(hide yes)
			)
		)
		(property "Author" "Antmicro"
			(at 335.28 140.97 0)
			(effects
				(font
					(size 1.27 1.27)
					(thickness 0.15)
				)
				(justify left bottom)
				(hide yes)
			)
		)
		(property "License" "Apache-2.0"
			(at 335.28 143.51 0)
			(effects
				(font
					(size 1.27 1.27)
					(thickness 0.15)
				)
				(justify left bottom)
				(hide yes)
			)
		)
		(pin "1"
		)
		(instances
			(project "OCuLink to 10GbE adapter"
				(path ""
					(reference "#PWR0198")
					(unit 1)
				)
			)
			(project "thunderbolt-to-10gbe-adapter"
				(path ""
					(reference "#PWR0317")
					(unit 1)
				)
			)
		)
	)
	(symbol
		(lib_id "antmicropower:GND")
		(at 124.46 156.21 0)
		(unit 1)
		(exclude_from_sim no)
		(in_bom yes)
		(on_board yes)
		(dnp no)
		(property "Reference" "#PWR0258"
			(at 133.35 158.75 0)
			(effects
				(font
					(size 1.27 1.27)
					(thickness 0.15)
				)
				(justify left bottom)
				(hide yes)
			)
		)
		(property "Value" "GND"
			(at 124.46 160.02 0)
			(effects
				(font
					(size 1.27 1.27)
					(thickness 0.15)
				)
			)
		)
		(property "Footprint" ""
			(at 133.35 163.83 0)
			(effects
				(font
					(size 1.27 1.27)
					(thickness 0.15)
				)
				(justify left bottom)
				(hide yes)
			)
		)
		(property "Datasheet" ""
			(at 133.35 168.91 0)
			(effects
				(font
					(size 1.27 1.27)
					(thickness 0.15)
				)
				(justify left bottom)
				(hide yes)
			)
		)
		(property "Description" ""
			(at 124.46 156.21 0)
			(effects
				(font
					(size 1.27 1.27)
				)
				(hide yes)
			)
		)
		(property "Author" "Antmicro"
			(at 133.35 163.83 0)
			(effects
				(font
					(size 1.27 1.27)
					(thickness 0.15)
				)
				(justify left bottom)
				(hide yes)
			)
		)
		(property "License" "Apache-2.0"
			(at 133.35 166.37 0)
			(effects
				(font
					(size 1.27 1.27)
					(thickness 0.15)
				)
				(justify left bottom)
				(hide yes)
			)
		)
		(pin "1"
		)
		(instances
			(project "OCuLink to 10GbE adapter"
				(path ""
					(reference "#PWR0217")
					(unit 1)
				)
			)
			(project "thunderbolt-to-10gbe-adapter"
				(path ""
					(reference "#PWR0258")
					(unit 1)
				)
			)
		)
	)
	(symbol
		(lib_id "antmicroCapacitors0402:C_1u_25V_0402")
		(at 335.28 113.03 90)
		(unit 1)
		(exclude_from_sim no)
		(in_bom yes)
		(on_board yes)
		(dnp no)
		(property "Reference" "C235"
			(at 337.312 109.22 90)
			(effects
				(font
					(size 1.27 1.27)
					(thickness 0.15)
				)
				(justify right)
			)
		)
		(property "Value" "C_1u_25V_0402"
			(at 345.44 92.71 0)
			(effects
				(font
					(size 1.27 1.27)
					(thickness 0.15)
				)
				(justify left bottom)
				(hide yes)
			)
		)
		(property "Footprint" "antmicro-footprints:C_0402_1005Metric"
			(at 347.98 92.71 0)
			(effects
				(font
					(size 1.27 1.27)
					(thickness 0.15)
				)
				(justify left bottom)
				(hide yes)
			)
		)
		(property "Datasheet" "https://www.murata.com/products/productdetail?partno=GRM155R61E105KE11%23"
			(at 350.52 92.71 0)
			(effects
				(font
					(size 1.27 1.27)
					(thickness 0.15)
				)
				(justify left bottom)
				(hide yes)
			)
		)
		(property "Description" "SMD Multilayer Ceramic Capacitor, 1 µF, 25 V, 0402 [1005 Metric], ± 10%, X5R, GRM Series"
			(at 335.28 113.03 0)
			(effects
				(font
					(size 1.27 1.27)
				)
				(hide yes)
			)
		)
		(property "MPN" "GRM155R61E105KE11J"
			(at 353.06 92.71 0)
			(effects
				(font
					(size 1.27 1.27)
					(thickness 0.15)
				)
				(justify left bottom)
				(hide yes)
			)
		)
		(property "Manufacturer" "Murata"
			(at 355.6 92.71 0)
			(effects
				(font
					(size 1.27 1.27)
					(thickness 0.15)
				)
				(justify left bottom)
				(hide yes)
			)
		)
		(property "License" "Apache-2.0"
			(at 358.14 92.71 0)
			(effects
				(font
					(size 1.27 1.27)
					(thickness 0.15)
				)
				(justify left bottom)
				(hide yes)
			)
		)
		(property "Author" "Antmicro"
			(at 360.68 92.71 0)
			(effects
				(font
					(size 1.27 1.27)
					(thickness 0.15)
				)
				(justify left bottom)
				(hide yes)
			)
		)
		(property "Val" "1u"
			(at 337.312 111.76 90)
			(effects
				(font
					(size 1.27 1.27)
					(thickness 0.15)
				)
				(justify right)
			)
		)
		(property "Voltage" "25V"
			(at 363.22 92.71 0)
			(effects
				(font
					(size 1.27 1.27)
				)
				(justify left bottom)
				(hide yes)
			)
		)
		(property "Dielectric" "X5R"
			(at 365.76 92.71 0)
			(effects
				(font
					(size 1.27 1.27)
				)
				(justify left bottom)
				(hide yes)
			)
		)
		(pin "2"
		)
		(pin "1"
		)
		(instances
			(project "OCuLink to 10GbE adapter"
				(path ""
					(reference "C133")
					(unit 1)
				)
			)
			(project "thunderbolt-to-10gbe-adapter"
				(path ""
					(reference "C235")
					(unit 1)
				)
			)
		)
	)
	(symbol
		(lib_id "antmicropower:GND")
		(at 353.06 115.57 0)
		(unit 1)
		(exclude_from_sim no)
		(in_bom yes)
		(on_board yes)
		(dnp no)
		(property "Reference" "#PWR0329"
			(at 361.95 118.11 0)
			(effects
				(font
					(size 1.27 1.27)
					(thickness 0.15)
				)
				(justify left bottom)
				(hide yes)
			)
		)
		(property "Value" "GND"
			(at 353.06 119.38 0)
			(effects
				(font
					(size 1.27 1.27)
					(thickness 0.15)
				)
			)
		)
		(property "Footprint" ""
			(at 361.95 123.19 0)
			(effects
				(font
					(size 1.27 1.27)
					(thickness 0.15)
				)
				(justify left bottom)
				(hide yes)
			)
		)
		(property "Datasheet" ""
			(at 361.95 128.27 0)
			(effects
				(font
					(size 1.27 1.27)
					(thickness 0.15)
				)
				(justify left bottom)
				(hide yes)
			)
		)
		(property "Description" ""
			(at 353.06 115.57 0)
			(effects
				(font
					(size 1.27 1.27)
				)
				(hide yes)
			)
		)
		(property "Author" "Antmicro"
			(at 361.95 123.19 0)
			(effects
				(font
					(size 1.27 1.27)
					(thickness 0.15)
				)
				(justify left bottom)
				(hide yes)
			)
		)
		(property "License" "Apache-2.0"
			(at 361.95 125.73 0)
			(effects
				(font
					(size 1.27 1.27)
					(thickness 0.15)
				)
				(justify left bottom)
				(hide yes)
			)
		)
		(pin "1"
		)
		(instances
			(project "OCuLink to 10GbE adapter"
				(path ""
					(reference "#PWR0183")
					(unit 1)
				)
			)
			(project "thunderbolt-to-10gbe-adapter"
				(path ""
					(reference "#PWR0329")
					(unit 1)
				)
			)
		)
	)
	(symbol
		(lib_id "antmicroCapacitors0603:C_10u_10V_X7R_0603")
		(at 317.5 130.81 90)
		(unit 1)
		(exclude_from_sim no)
		(in_bom yes)
		(on_board yes)
		(dnp no)
		(property "Reference" "C226"
			(at 319.532 127 90)
			(effects
				(font
					(size 1.27 1.27)
					(thickness 0.15)
				)
				(justify right)
			)
		)
		(property "Value" "C_10u_10V_X7R_0603"
			(at 327.66 115.57 0)
			(effects
				(font
					(size 1.27 1.27)
					(thickness 0.15)
				)
				(justify left bottom)
				(hide yes)
			)
		)
		(property "Footprint" "antmicro-footprints:C_0603_1608Metric"
			(at 330.2 115.57 0)
			(effects
				(font
					(size 1.27 1.27)
					(thickness 0.15)
				)
				(justify left bottom)
				(hide yes)
			)
		)
		(property "Datasheet" "https://www.murata.com/products/productdetail?partno=GRM188Z71A106KA73%23"
			(at 332.74 115.57 0)
			(effects
				(font
					(size 1.27 1.27)
					(thickness 0.15)
				)
				(justify left bottom)
				(hide yes)
			)
		)
		(property "Description" "SMD Multilayer Ceramic Capacitor,  10µF, 10V, 0603, ±10%, X7R"
			(at 317.5 130.81 0)
			(effects
				(font
					(size 1.27 1.27)
				)
				(hide yes)
			)
		)
		(property "MPN" "GRM188Z71A106KA73D"
			(at 335.28 115.57 0)
			(effects
				(font
					(size 1.27 1.27)
					(thickness 0.15)
				)
				(justify left bottom)
				(hide yes)
			)
		)
		(property "Val" "10u"
			(at 319.532 129.54 90)
			(effects
				(font
					(size 1.27 1.27)
					(thickness 0.15)
				)
				(justify right)
			)
		)
		(property "Voltage" "10V"
			(at 337.82 115.57 0)
			(effects
				(font
					(size 1.27 1.27)
					(thickness 0.15)
				)
				(justify left bottom)
				(hide yes)
			)
		)
		(property "Dielectric" "X7R"
			(at 340.36 115.57 0)
			(effects
				(font
					(size 1.27 1.27)
					(thickness 0.15)
				)
				(justify left bottom)
				(hide yes)
			)
		)
		(property "Manufacturer" "Murata"
			(at 342.9 115.57 0)
			(effects
				(font
					(size 1.27 1.27)
					(thickness 0.15)
				)
				(justify left bottom)
				(hide yes)
			)
		)
		(property "License" "Apache-2.0"
			(at 345.44 115.57 0)
			(effects
				(font
					(size 1.27 1.27)
					(thickness 0.15)
				)
				(justify left bottom)
				(hide yes)
			)
		)
		(property "Author" "Antmicro"
			(at 347.98 115.57 0)
			(effects
				(font
					(size 1.27 1.27)
					(thickness 0.15)
				)
				(justify left bottom)
				(hide yes)
			)
		)
		(pin "1"
		)
		(pin "2"
		)
		(instances
			(project "OCuLink to 10GbE adapter"
				(path ""
					(reference "C148")
					(unit 1)
				)
			)
			(project "thunderbolt-to-10gbe-adapter"
				(path ""
					(reference "C226")
					(unit 1)
				)
			)
		)
	)
	(symbol
		(lib_id "antmicroCapacitors0402:C_1u_25V_0402")
		(at 397.51 52.07 90)
		(unit 1)
		(exclude_from_sim no)
		(in_bom yes)
		(on_board yes)
		(dnp no)
		(property "Reference" "C263"
			(at 399.542 48.26 90)
			(effects
				(font
					(size 1.27 1.27)
					(thickness 0.15)
				)
				(justify right)
			)
		)
		(property "Value" "C_1u_25V_0402"
			(at 407.67 31.75 0)
			(effects
				(font
					(size 1.27 1.27)
					(thickness 0.15)
				)
				(justify left bottom)
				(hide yes)
			)
		)
		(property "Footprint" "antmicro-footprints:C_0402_1005Metric"
			(at 410.21 31.75 0)
			(effects
				(font
					(size 1.27 1.27)
					(thickness 0.15)
				)
				(justify left bottom)
				(hide yes)
			)
		)
		(property "Datasheet" "https://www.murata.com/products/productdetail?partno=GRM155R61E105KE11%23"
			(at 412.75 31.75 0)
			(effects
				(font
					(size 1.27 1.27)
					(thickness 0.15)
				)
				(justify left bottom)
				(hide yes)
			)
		)
		(property "Description" "SMD Multilayer Ceramic Capacitor, 1 µF, 25 V, 0402 [1005 Metric], ± 10%, X5R, GRM Series"
			(at 397.51 52.07 0)
			(effects
				(font
					(size 1.27 1.27)
				)
				(hide yes)
			)
		)
		(property "MPN" "GRM155R61E105KE11J"
			(at 415.29 31.75 0)
			(effects
				(font
					(size 1.27 1.27)
					(thickness 0.15)
				)
				(justify left bottom)
				(hide yes)
			)
		)
		(property "Manufacturer" "Murata"
			(at 417.83 31.75 0)
			(effects
				(font
					(size 1.27 1.27)
					(thickness 0.15)
				)
				(justify left bottom)
				(hide yes)
			)
		)
		(property "License" "Apache-2.0"
			(at 420.37 31.75 0)
			(effects
				(font
					(size 1.27 1.27)
					(thickness 0.15)
				)
				(justify left bottom)
				(hide yes)
			)
		)
		(property "Author" "Antmicro"
			(at 422.91 31.75 0)
			(effects
				(font
					(size 1.27 1.27)
					(thickness 0.15)
				)
				(justify left bottom)
				(hide yes)
			)
		)
		(property "Val" "1u"
			(at 399.542 50.8 90)
			(effects
				(font
					(size 1.27 1.27)
					(thickness 0.15)
				)
				(justify right)
			)
		)
		(property "Voltage" "25V"
			(at 425.45 31.75 0)
			(effects
				(font
					(size 1.27 1.27)
				)
				(justify left bottom)
				(hide yes)
			)
		)
		(property "Dielectric" "X5R"
			(at 427.99 31.75 0)
			(effects
				(font
					(size 1.27 1.27)
				)
				(justify left bottom)
				(hide yes)
			)
		)
		(pin "2"
		)
		(pin "1"
		)
		(instances
			(project "OCuLink to 10GbE adapter"
				(path ""
					(reference "C98")
					(unit 1)
				)
			)
			(project "thunderbolt-to-10gbe-adapter"
				(path ""
					(reference "C263")
					(unit 1)
				)
			)
		)
	)
	(symbol
		(lib_id "antmicropower:GND")
		(at 124.46 76.2 0)
		(unit 1)
		(exclude_from_sim no)
		(in_bom yes)
		(on_board yes)
		(dnp no)
		(property "Reference" "#PWR0256"
			(at 133.35 78.74 0)
			(effects
				(font
					(size 1.27 1.27)
					(thickness 0.15)
				)
				(justify left bottom)
				(hide yes)
			)
		)
		(property "Value" "GND"
			(at 124.46 80.01 0)
			(effects
				(font
					(size 1.27 1.27)
					(thickness 0.15)
				)
			)
		)
		(property "Footprint" ""
			(at 133.35 83.82 0)
			(effects
				(font
					(size 1.27 1.27)
					(thickness 0.15)
				)
				(justify left bottom)
				(hide yes)
			)
		)
		(property "Datasheet" ""
			(at 133.35 88.9 0)
			(effects
				(font
					(size 1.27 1.27)
					(thickness 0.15)
				)
				(justify left bottom)
				(hide yes)
			)
		)
		(property "Description" ""
			(at 124.46 76.2 0)
			(effects
				(font
					(size 1.27 1.27)
				)
				(hide yes)
			)
		)
		(property "Author" "Antmicro"
			(at 133.35 83.82 0)
			(effects
				(font
					(size 1.27 1.27)
					(thickness 0.15)
				)
				(justify left bottom)
				(hide yes)
			)
		)
		(property "License" "Apache-2.0"
			(at 133.35 86.36 0)
			(effects
				(font
					(size 1.27 1.27)
					(thickness 0.15)
				)
				(justify left bottom)
				(hide yes)
			)
		)
		(pin "1"
		)
		(instances
			(project "OCuLink to 10GbE adapter"
				(path ""
					(reference "#PWR0135")
					(unit 1)
				)
			)
			(project "thunderbolt-to-10gbe-adapter"
				(path ""
					(reference "#PWR0256")
					(unit 1)
				)
			)
		)
	)
	(symbol
		(lib_id "antmicropower:VDD")
		(at 198.12 116.84 0)
		(unit 1)
		(exclude_from_sim no)
		(in_bom yes)
		(on_board yes)
		(dnp no)
		(property "Reference" "#PWR0283"
			(at 198.12 120.65 0)
			(effects
				(font
					(size 1.27 1.27)
				)
				(hide yes)
			)
		)
		(property "Value" "P1_AVDDL"
			(at 198.12 113.03 0)
			(effects
				(font
					(size 1.27 1.27)
				)
			)
		)
		(property "Footprint" ""
			(at 198.12 116.84 0)
			(effects
				(font
					(size 1.27 1.27)
				)
				(hide yes)
			)
		)
		(property "Datasheet" ""
			(at 198.12 116.84 0)
			(effects
				(font
					(size 1.27 1.27)
				)
				(hide yes)
			)
		)
		(property "Description" ""
			(at 198.12 116.84 0)
			(effects
				(font
					(size 1.27 1.27)
				)
				(hide yes)
			)
		)
		(pin "1"
		)
		(instances
			(project "OCuLink to 10GbE adapter"
				(path ""
					(reference "#PWR0154")
					(unit 1)
				)
			)
			(project "thunderbolt-to-10gbe-adapter"
				(path ""
					(reference "#PWR0283")
					(unit 1)
				)
			)
		)
	)
	(symbol
		(lib_id "antmicroCapacitors0603:C_47u_0603")
		(at 90.17 207.01 90)
		(unit 1)
		(exclude_from_sim no)
		(in_bom yes)
		(on_board yes)
		(dnp no)
		(property "Reference" "C172"
			(at 92.202 203.2 90)
			(effects
				(font
					(size 1.27 1.27)
					(thickness 0.15)
				)
				(justify right)
			)
		)
		(property "Value" "C_47u_0603"
			(at 100.33 186.69 0)
			(effects
				(font
					(size 1.27 1.27)
					(thickness 0.15)
				)
				(justify left bottom)
				(hide yes)
			)
		)
		(property "Footprint" "antmicro-footprints:C_0603_1608Metric"
			(at 102.87 186.69 0)
			(effects
				(font
					(size 1.27 1.27)
					(thickness 0.15)
				)
				(justify left bottom)
				(hide yes)
			)
		)
		(property "Datasheet" "https://www.murata.com/products/productdetail?partno=GRM188R60J476ME15%23"
			(at 105.41 186.69 0)
			(effects
				(font
					(size 1.27 1.27)
					(thickness 0.15)
				)
				(justify left bottom)
				(hide yes)
			)
		)
		(property "Description" "SMD Multilayer Ceramic Capacitor, 47 µF, 6.3 V, 0603 [1608 Metric], ± 20%, X5R, GRM Series"
			(at 123.19 186.69 0)
			(effects
				(font
					(size 1.27 1.27)
				)
				(justify left bottom)
				(hide yes)
			)
		)
		(property "MPN" "GRM188R60J476ME15D"
			(at 107.95 186.69 0)
			(effects
				(font
					(size 1.27 1.27)
					(thickness 0.15)
				)
				(justify left bottom)
				(hide yes)
			)
		)
		(property "Manufacturer" "Murata"
			(at 110.49 186.69 0)
			(effects
				(font
					(size 1.27 1.27)
					(thickness 0.15)
				)
				(justify left bottom)
				(hide yes)
			)
		)
		(property "License" "Apache-2.0"
			(at 113.03 186.69 0)
			(effects
				(font
					(size 1.27 1.27)
					(thickness 0.15)
				)
				(justify left bottom)
				(hide yes)
			)
		)
		(property "Author" "Antmicro"
			(at 115.57 186.69 0)
			(effects
				(font
					(size 1.27 1.27)
					(thickness 0.15)
				)
				(justify left bottom)
				(hide yes)
			)
		)
		(property "Val" "47u"
			(at 92.202 205.74 90)
			(effects
				(font
					(size 1.27 1.27)
					(thickness 0.15)
				)
				(justify right)
			)
		)
		(property "Voltage" ""
			(at 118.11 186.69 0)
			(effects
				(font
					(size 1.27 1.27)
				)
				(justify left bottom)
				(hide yes)
			)
		)
		(property "Dielectric" ""
			(at 120.65 186.69 0)
			(effects
				(font
					(size 1.27 1.27)
				)
				(justify left bottom)
				(hide yes)
			)
		)
		(pin "1"
		)
		(pin "2"
		)
		(instances
			(project ""
				(path ""
					(reference "C180")
					(unit 1)
				)
			)
			(project "thunderbolt-to-10gbe-adapter"
				(path ""
					(reference "C172")
					(unit 1)
				)
			)
		)
	)
	(symbol
		(lib_id "antmicropower:GND")
		(at 90.17 54.61 0)
		(unit 1)
		(exclude_from_sim no)
		(in_bom yes)
		(on_board yes)
		(dnp no)
		(property "Reference" "#PWR0237"
			(at 99.06 57.15 0)
			(effects
				(font
					(size 1.27 1.27)
					(thickness 0.15)
				)
				(justify left bottom)
				(hide yes)
			)
		)
		(property "Value" "GND"
			(at 90.17 58.42 0)
			(effects
				(font
					(size 1.27 1.27)
					(thickness 0.15)
				)
			)
		)
		(property "Footprint" ""
			(at 99.06 62.23 0)
			(effects
				(font
					(size 1.27 1.27)
					(thickness 0.15)
				)
				(justify left bottom)
				(hide yes)
			)
		)
		(property "Datasheet" ""
			(at 99.06 67.31 0)
			(effects
				(font
					(size 1.27 1.27)
					(thickness 0.15)
				)
				(justify left bottom)
				(hide yes)
			)
		)
		(property "Description" ""
			(at 90.17 54.61 0)
			(effects
				(font
					(size 1.27 1.27)
				)
				(hide yes)
			)
		)
		(property "Author" "Antmicro"
			(at 99.06 62.23 0)
			(effects
				(font
					(size 1.27 1.27)
					(thickness 0.15)
				)
				(justify left bottom)
				(hide yes)
			)
		)
		(property "License" "Apache-2.0"
			(at 99.06 64.77 0)
			(effects
				(font
					(size 1.27 1.27)
					(thickness 0.15)
				)
				(justify left bottom)
				(hide yes)
			)
		)
		(pin "1"
		)
		(instances
			(project "OCuLink to 10GbE adapter"
				(path ""
					(reference "#PWR0114")
					(unit 1)
				)
			)
			(project "thunderbolt-to-10gbe-adapter"
				(path ""
					(reference "#PWR0237")
					(unit 1)
				)
			)
		)
	)
	(symbol
		(lib_id "antmicroCapacitors0402:C_1u_25V_0402")
		(at 397.51 73.66 90)
		(unit 1)
		(exclude_from_sim no)
		(in_bom yes)
		(on_board yes)
		(dnp no)
		(property "Reference" "C264"
			(at 399.542 69.85 90)
			(effects
				(font
					(size 1.27 1.27)
					(thickness 0.15)
				)
				(justify right)
			)
		)
		(property "Value" "C_1u_25V_0402"
			(at 407.67 53.34 0)
			(effects
				(font
					(size 1.27 1.27)
					(thickness 0.15)
				)
				(justify left bottom)
				(hide yes)
			)
		)
		(property "Footprint" "antmicro-footprints:C_0402_1005Metric"
			(at 410.21 53.34 0)
			(effects
				(font
					(size 1.27 1.27)
					(thickness 0.15)
				)
				(justify left bottom)
				(hide yes)
			)
		)
		(property "Datasheet" "https://www.murata.com/products/productdetail?partno=GRM155R61E105KE11%23"
			(at 412.75 53.34 0)
			(effects
				(font
					(size 1.27 1.27)
					(thickness 0.15)
				)
				(justify left bottom)
				(hide yes)
			)
		)
		(property "Description" "SMD Multilayer Ceramic Capacitor, 1 µF, 25 V, 0402 [1005 Metric], ± 10%, X5R, GRM Series"
			(at 397.51 73.66 0)
			(effects
				(font
					(size 1.27 1.27)
				)
				(hide yes)
			)
		)
		(property "MPN" "GRM155R61E105KE11J"
			(at 415.29 53.34 0)
			(effects
				(font
					(size 1.27 1.27)
					(thickness 0.15)
				)
				(justify left bottom)
				(hide yes)
			)
		)
		(property "Manufacturer" "Murata"
			(at 417.83 53.34 0)
			(effects
				(font
					(size 1.27 1.27)
					(thickness 0.15)
				)
				(justify left bottom)
				(hide yes)
			)
		)
		(property "License" "Apache-2.0"
			(at 420.37 53.34 0)
			(effects
				(font
					(size 1.27 1.27)
					(thickness 0.15)
				)
				(justify left bottom)
				(hide yes)
			)
		)
		(property "Author" "Antmicro"
			(at 422.91 53.34 0)
			(effects
				(font
					(size 1.27 1.27)
					(thickness 0.15)
				)
				(justify left bottom)
				(hide yes)
			)
		)
		(property "Val" "1u"
			(at 399.542 72.39 90)
			(effects
				(font
					(size 1.27 1.27)
					(thickness 0.15)
				)
				(justify right)
			)
		)
		(property "Voltage" "25V"
			(at 425.45 53.34 0)
			(effects
				(font
					(size 1.27 1.27)
				)
				(justify left bottom)
				(hide yes)
			)
		)
		(property "Dielectric" "X5R"
			(at 427.99 53.34 0)
			(effects
				(font
					(size 1.27 1.27)
				)
				(justify left bottom)
				(hide yes)
			)
		)
		(pin "2"
		)
		(pin "1"
		)
		(instances
			(project "OCuLink to 10GbE adapter"
				(path ""
					(reference "C116")
					(unit 1)
				)
			)
			(project "thunderbolt-to-10gbe-adapter"
				(path ""
					(reference "C264")
					(unit 1)
				)
			)
		)
	)
	(symbol
		(lib_id "antmicroCapacitors0402:C_1u_25V_0402")
		(at 317.5 73.66 90)
		(unit 1)
		(exclude_from_sim no)
		(in_bom yes)
		(on_board yes)
		(dnp no)
		(property "Reference" "C223"
			(at 319.532 69.85 90)
			(effects
				(font
					(size 1.27 1.27)
					(thickness 0.15)
				)
				(justify right)
			)
		)
		(property "Value" "C_1u_25V_0402"
			(at 327.66 53.34 0)
			(effects
				(font
					(size 1.27 1.27)
					(thickness 0.15)
				)
				(justify left bottom)
				(hide yes)
			)
		)
		(property "Footprint" "antmicro-footprints:C_0402_1005Metric"
			(at 330.2 53.34 0)
			(effects
				(font
					(size 1.27 1.27)
					(thickness 0.15)
				)
				(justify left bottom)
				(hide yes)
			)
		)
		(property "Datasheet" "https://www.murata.com/products/productdetail?partno=GRM155R61E105KE11%23"
			(at 332.74 53.34 0)
			(effects
				(font
					(size 1.27 1.27)
					(thickness 0.15)
				)
				(justify left bottom)
				(hide yes)
			)
		)
		(property "Description" "SMD Multilayer Ceramic Capacitor, 1 µF, 25 V, 0402 [1005 Metric], ± 10%, X5R, GRM Series"
			(at 317.5 73.66 0)
			(effects
				(font
					(size 1.27 1.27)
				)
				(hide yes)
			)
		)
		(property "MPN" "GRM155R61E105KE11J"
			(at 335.28 53.34 0)
			(effects
				(font
					(size 1.27 1.27)
					(thickness 0.15)
				)
				(justify left bottom)
				(hide yes)
			)
		)
		(property "Manufacturer" "Murata"
			(at 337.82 53.34 0)
			(effects
				(font
					(size 1.27 1.27)
					(thickness 0.15)
				)
				(justify left bottom)
				(hide yes)
			)
		)
		(property "License" "Apache-2.0"
			(at 340.36 53.34 0)
			(effects
				(font
					(size 1.27 1.27)
					(thickness 0.15)
				)
				(justify left bottom)
				(hide yes)
			)
		)
		(property "Author" "Antmicro"
			(at 342.9 53.34 0)
			(effects
				(font
					(size 1.27 1.27)
					(thickness 0.15)
				)
				(justify left bottom)
				(hide yes)
			)
		)
		(property "Val" "1u"
			(at 319.532 72.39 90)
			(effects
				(font
					(size 1.27 1.27)
					(thickness 0.15)
				)
				(justify right)
			)
		)
		(property "Voltage" "25V"
			(at 345.44 53.34 0)
			(effects
				(font
					(size 1.27 1.27)
				)
				(justify left bottom)
				(hide yes)
			)
		)
		(property "Dielectric" "X5R"
			(at 347.98 53.34 0)
			(effects
				(font
					(size 1.27 1.27)
				)
				(justify left bottom)
				(hide yes)
			)
		)
		(pin "2"
		)
		(pin "1"
		)
		(instances
			(project "OCuLink to 10GbE adapter"
				(path ""
					(reference "C107")
					(unit 1)
				)
			)
			(project "thunderbolt-to-10gbe-adapter"
				(path ""
					(reference "C223")
					(unit 1)
				)
			)
		)
	)
	(symbol
		(lib_id "antmicropower:GND")
		(at 81.28 54.61 0)
		(unit 1)
		(exclude_from_sim no)
		(in_bom yes)
		(on_board yes)
		(dnp no)
		(property "Reference" "#PWR0236"
			(at 90.17 57.15 0)
			(effects
				(font
					(size 1.27 1.27)
					(thickness 0.15)
				)
				(justify left bottom)
				(hide yes)
			)
		)
		(property "Value" "GND"
			(at 81.28 58.42 0)
			(effects
				(font
					(size 1.27 1.27)
					(thickness 0.15)
				)
			)
		)
		(property "Footprint" ""
			(at 90.17 62.23 0)
			(effects
				(font
					(size 1.27 1.27)
					(thickness 0.15)
				)
				(justify left bottom)
				(hide yes)
			)
		)
		(property "Datasheet" ""
			(at 90.17 67.31 0)
			(effects
				(font
					(size 1.27 1.27)
					(thickness 0.15)
				)
				(justify left bottom)
				(hide yes)
			)
		)
		(property "Description" ""
			(at 81.28 54.61 0)
			(effects
				(font
					(size 1.27 1.27)
				)
				(hide yes)
			)
		)
		(property "Author" "Antmicro"
			(at 90.17 62.23 0)
			(effects
				(font
					(size 1.27 1.27)
					(thickness 0.15)
				)
				(justify left bottom)
				(hide yes)
			)
		)
		(property "License" "Apache-2.0"
			(at 90.17 64.77 0)
			(effects
				(font
					(size 1.27 1.27)
					(thickness 0.15)
				)
				(justify left bottom)
				(hide yes)
			)
		)
		(pin "1"
		)
		(instances
			(project "OCuLink to 10GbE adapter"
				(path ""
					(reference "#PWR0113")
					(unit 1)
				)
			)
			(project "thunderbolt-to-10gbe-adapter"
				(path ""
					(reference "#PWR0236")
					(unit 1)
				)
			)
		)
	)
	(symbol
		(lib_id "antmicroCapacitors0402:C_1u_25V_0402")
		(at 379.73 52.07 90)
		(unit 1)
		(exclude_from_sim no)
		(in_bom yes)
		(on_board yes)
		(dnp no)
		(property "Reference" "C255"
			(at 381.762 48.26 90)
			(effects
				(font
					(size 1.27 1.27)
					(thickness 0.15)
				)
				(justify right)
			)
		)
		(property "Value" "C_1u_25V_0402"
			(at 389.89 31.75 0)
			(effects
				(font
					(size 1.27 1.27)
					(thickness 0.15)
				)
				(justify left bottom)
				(hide yes)
			)
		)
		(property "Footprint" "antmicro-footprints:C_0402_1005Metric"
			(at 392.43 31.75 0)
			(effects
				(font
					(size 1.27 1.27)
					(thickness 0.15)
				)
				(justify left bottom)
				(hide yes)
			)
		)
		(property "Datasheet" "https://www.murata.com/products/productdetail?partno=GRM155R61E105KE11%23"
			(at 394.97 31.75 0)
			(effects
				(font
					(size 1.27 1.27)
					(thickness 0.15)
				)
				(justify left bottom)
				(hide yes)
			)
		)
		(property "Description" "SMD Multilayer Ceramic Capacitor, 1 µF, 25 V, 0402 [1005 Metric], ± 10%, X5R, GRM Series"
			(at 379.73 52.07 0)
			(effects
				(font
					(size 1.27 1.27)
				)
				(hide yes)
			)
		)
		(property "MPN" "GRM155R61E105KE11J"
			(at 397.51 31.75 0)
			(effects
				(font
					(size 1.27 1.27)
					(thickness 0.15)
				)
				(justify left bottom)
				(hide yes)
			)
		)
		(property "Manufacturer" "Murata"
			(at 400.05 31.75 0)
			(effects
				(font
					(size 1.27 1.27)
					(thickness 0.15)
				)
				(justify left bottom)
				(hide yes)
			)
		)
		(property "License" "Apache-2.0"
			(at 402.59 31.75 0)
			(effects
				(font
					(size 1.27 1.27)
					(thickness 0.15)
				)
				(justify left bottom)
				(hide yes)
			)
		)
		(property "Author" "Antmicro"
			(at 405.13 31.75 0)
			(effects
				(font
					(size 1.27 1.27)
					(thickness 0.15)
				)
				(justify left bottom)
				(hide yes)
			)
		)
		(property "Val" "1u"
			(at 381.762 50.8 90)
			(effects
				(font
					(size 1.27 1.27)
					(thickness 0.15)
				)
				(justify right)
			)
		)
		(property "Voltage" "25V"
			(at 407.67 31.75 0)
			(effects
				(font
					(size 1.27 1.27)
				)
				(justify left bottom)
				(hide yes)
			)
		)
		(property "Dielectric" "X5R"
			(at 410.21 31.75 0)
			(effects
				(font
					(size 1.27 1.27)
				)
				(justify left bottom)
				(hide yes)
			)
		)
		(pin "2"
		)
		(pin "1"
		)
		(instances
			(project "OCuLink to 10GbE adapter"
				(path ""
					(reference "C96")
					(unit 1)
				)
			)
			(project "thunderbolt-to-10gbe-adapter"
				(path ""
					(reference "C255")
					(unit 1)
				)
			)
		)
	)
	(symbol
		(lib_id "antmicropower:+3V3")
		(at 283.21 78.74 0)
		(unit 1)
		(exclude_from_sim no)
		(in_bom yes)
		(on_board yes)
		(dnp no)
		(property "Reference" "#PWR0293"
			(at 298.45 78.74 0)
			(effects
				(font
					(size 1.27 1.27)
					(thickness 0.15)
				)
				(justify left bottom)
				(hide yes)
			)
		)
		(property "Value" "+3V3"
			(at 283.21 74.93 0)
			(effects
				(font
					(size 1.27 1.27)
					(thickness 0.15)
				)
			)
		)
		(property "Footprint" ""
			(at 298.45 86.36 0)
			(effects
				(font
					(size 1.27 1.27)
					(thickness 0.15)
				)
				(justify left bottom)
				(hide yes)
			)
		)
		(property "Datasheet" ""
			(at 298.45 88.9 0)
			(effects
				(font
					(size 1.27 1.27)
					(thickness 0.15)
				)
				(justify left bottom)
				(hide yes)
			)
		)
		(property "Description" ""
			(at 283.21 78.74 0)
			(effects
				(font
					(size 1.27 1.27)
				)
				(hide yes)
			)
		)
		(property "Author" "Antmicro"
			(at 298.45 81.28 0)
			(effects
				(font
					(size 1.27 1.27)
					(thickness 0.15)
				)
				(justify left bottom)
				(hide yes)
			)
		)
		(property "License" "Apache-2.0"
			(at 298.45 83.82 0)
			(effects
				(font
					(size 1.27 1.27)
					(thickness 0.15)
				)
				(justify left bottom)
				(hide yes)
			)
		)
		(pin "1"
		)
		(instances
			(project "OCuLink to 10GbE adapter"
				(path ""
					(reference "#PWR0162")
					(unit 1)
				)
			)
			(project "thunderbolt-to-10gbe-adapter"
				(path ""
					(reference "#PWR0293")
					(unit 1)
				)
			)
		)
	)
	(symbol
		(lib_id "antmicropower:GND")
		(at 124.46 54.61 0)
		(unit 1)
		(exclude_from_sim no)
		(in_bom yes)
		(on_board yes)
		(dnp no)
		(property "Reference" "#PWR0255"
			(at 133.35 57.15 0)
			(effects
				(font
					(size 1.27 1.27)
					(thickness 0.15)
				)
				(justify left bottom)
				(hide yes)
			)
		)
		(property "Value" "GND"
			(at 124.46 58.42 0)
			(effects
				(font
					(size 1.27 1.27)
					(thickness 0.15)
				)
			)
		)
		(property "Footprint" ""
			(at 133.35 62.23 0)
			(effects
				(font
					(size 1.27 1.27)
					(thickness 0.15)
				)
				(justify left bottom)
				(hide yes)
			)
		)
		(property "Datasheet" ""
			(at 133.35 67.31 0)
			(effects
				(font
					(size 1.27 1.27)
					(thickness 0.15)
				)
				(justify left bottom)
				(hide yes)
			)
		)
		(property "Description" ""
			(at 124.46 54.61 0)
			(effects
				(font
					(size 1.27 1.27)
				)
				(hide yes)
			)
		)
		(property "Author" "Antmicro"
			(at 133.35 62.23 0)
			(effects
				(font
					(size 1.27 1.27)
					(thickness 0.15)
				)
				(justify left bottom)
				(hide yes)
			)
		)
		(property "License" "Apache-2.0"
			(at 133.35 64.77 0)
			(effects
				(font
					(size 1.27 1.27)
					(thickness 0.15)
				)
				(justify left bottom)
				(hide yes)
			)
		)
		(pin "1"
		)
		(instances
			(project "OCuLink to 10GbE adapter"
				(path ""
					(reference "#PWR0117")
					(unit 1)
				)
			)
			(project "thunderbolt-to-10gbe-adapter"
				(path ""
					(reference "#PWR0255")
					(unit 1)
				)
			)
		)
	)
	(symbol
		(lib_id "antmicropower:GND")
		(at 57.15 156.21 0)
		(unit 1)
		(exclude_from_sim no)
		(in_bom yes)
		(on_board yes)
		(dnp no)
		(property "Reference" "#PWR0221"
			(at 66.04 158.75 0)
			(effects
				(font
					(size 1.27 1.27)
					(thickness 0.15)
				)
				(justify left bottom)
				(hide yes)
			)
		)
		(property "Value" "GND"
			(at 57.15 160.02 0)
			(effects
				(font
					(size 1.27 1.27)
					(thickness 0.15)
				)
			)
		)
		(property "Footprint" ""
			(at 66.04 163.83 0)
			(effects
				(font
					(size 1.27 1.27)
					(thickness 0.15)
				)
				(justify left bottom)
				(hide yes)
			)
		)
		(property "Datasheet" ""
			(at 66.04 168.91 0)
			(effects
				(font
					(size 1.27 1.27)
					(thickness 0.15)
				)
				(justify left bottom)
				(hide yes)
			)
		)
		(property "Description" ""
			(at 57.15 156.21 0)
			(effects
				(font
					(size 1.27 1.27)
				)
				(hide yes)
			)
		)
		(property "Author" "Antmicro"
			(at 66.04 163.83 0)
			(effects
				(font
					(size 1.27 1.27)
					(thickness 0.15)
				)
				(justify left bottom)
				(hide yes)
			)
		)
		(property "License" "Apache-2.0"
			(at 66.04 166.37 0)
			(effects
				(font
					(size 1.27 1.27)
					(thickness 0.15)
				)
				(justify left bottom)
				(hide yes)
			)
		)
		(pin "1"
		)
		(instances
			(project "thunderbolt-to-10gbe-adapter"
				(path ""
					(reference "#PWR0221")
					(unit 1)
				)
			)
		)
	)
	(symbol
		(lib_id "antmicropower:GND")
		(at 133.35 129.54 0)
		(unit 1)
		(exclude_from_sim no)
		(in_bom yes)
		(on_board yes)
		(dnp no)
		(property "Reference" "#PWR0263"
			(at 142.24 132.08 0)
			(effects
				(font
					(size 1.27 1.27)
					(thickness 0.15)
				)
				(justify left bottom)
				(hide yes)
			)
		)
		(property "Value" "GND"
			(at 133.35 133.35 0)
			(effects
				(font
					(size 1.27 1.27)
					(thickness 0.15)
				)
			)
		)
		(property "Footprint" ""
			(at 142.24 137.16 0)
			(effects
				(font
					(size 1.27 1.27)
					(thickness 0.15)
				)
				(justify left bottom)
				(hide yes)
			)
		)
		(property "Datasheet" ""
			(at 142.24 142.24 0)
			(effects
				(font
					(size 1.27 1.27)
					(thickness 0.15)
				)
				(justify left bottom)
				(hide yes)
			)
		)
		(property "Description" ""
			(at 133.35 129.54 0)
			(effects
				(font
					(size 1.27 1.27)
				)
				(hide yes)
			)
		)
		(property "Author" "Antmicro"
			(at 142.24 137.16 0)
			(effects
				(font
					(size 1.27 1.27)
					(thickness 0.15)
				)
				(justify left bottom)
				(hide yes)
			)
		)
		(property "License" "Apache-2.0"
			(at 142.24 139.7 0)
			(effects
				(font
					(size 1.27 1.27)
					(thickness 0.15)
				)
				(justify left bottom)
				(hide yes)
			)
		)
		(pin "1"
		)
		(instances
			(project "OCuLink to 10GbE adapter"
				(path ""
					(reference "#PWR0192")
					(unit 1)
				)
			)
			(project "thunderbolt-to-10gbe-adapter"
				(path ""
					(reference "#PWR0263")
					(unit 1)
				)
			)
		)
	)
	(symbol
		(lib_id "antmicropower:GND")
		(at 88.9 182.88 0)
		(unit 1)
		(exclude_from_sim no)
		(in_bom yes)
		(on_board yes)
		(dnp no)
		(property "Reference" "#PWR0242"
			(at 97.79 185.42 0)
			(effects
				(font
					(size 1.27 1.27)
					(thickness 0.15)
				)
				(justify left bottom)
				(hide yes)
			)
		)
		(property "Value" "GND"
			(at 88.9 186.69 0)
			(effects
				(font
					(size 1.27 1.27)
					(thickness 0.15)
				)
			)
		)
		(property "Footprint" ""
			(at 97.79 190.5 0)
			(effects
				(font
					(size 1.27 1.27)
					(thickness 0.15)
				)
				(justify left bottom)
				(hide yes)
			)
		)
		(property "Datasheet" ""
			(at 97.79 195.58 0)
			(effects
				(font
					(size 1.27 1.27)
					(thickness 0.15)
				)
				(justify left bottom)
				(hide yes)
			)
		)
		(property "Description" ""
			(at 88.9 182.88 0)
			(effects
				(font
					(size 1.27 1.27)
				)
				(hide yes)
			)
		)
		(property "Author" "Antmicro"
			(at 97.79 190.5 0)
			(effects
				(font
					(size 1.27 1.27)
					(thickness 0.15)
				)
				(justify left bottom)
				(hide yes)
			)
		)
		(property "License" "Apache-2.0"
			(at 97.79 193.04 0)
			(effects
				(font
					(size 1.27 1.27)
					(thickness 0.15)
				)
				(justify left bottom)
				(hide yes)
			)
		)
		(pin "1"
		)
		(instances
			(project "OCuLink to 10GbE adapter"
				(path ""
					(reference "#PWR0224")
					(unit 1)
				)
			)
			(project "thunderbolt-to-10gbe-adapter"
				(path ""
					(reference "#PWR0242")
					(unit 1)
				)
			)
		)
	)
	(symbol
		(lib_id "antmicroCapacitorspol:C_Pol_100u_6V_KEMET-T490-A")
		(at 66.04 148.59 270)
		(unit 1)
		(exclude_from_sim no)
		(in_bom yes)
		(on_board yes)
		(dnp no)
		(fields_autoplaced yes)
		(property "Reference" "C332"
			(at 68.58 149.3266 90)
			(effects
				(font
					(size 1.27 1.27)
					(thickness 0.15)
				)
				(justify left)
			)
		)
		(property "Value" "C_Pol_100u_6V_KEMET-T490-A"
			(at 63.5 162.56 0)
			(effects
				(font
					(size 1.27 1.27)
					(thickness 0.15)
				)
				(justify left bottom)
				(hide yes)
			)
		)
		(property "Footprint" "antmicro-footprints:C_Pol_EIA-A"
			(at 58.42 162.56 0)
			(effects
				(font
					(size 1.27 1.27)
					(thickness 0.15)
				)
				(justify left bottom)
				(hide yes)
			)
		)
		(property "Datasheet" "https://www.kemet.com/en/us/capacitors/product/T490A107M006ATE800.html"
			(at 55.88 162.56 0)
			(effects
				(font
					(size 1.27 1.27)
					(thickness 0.15)
				)
				(justify left bottom)
				(hide yes)
			)
		)
		(property "Description" "Surface Mount Tantalum Capacitor,  Solid SMD 6V 100uF 1206 20% ESR=800mOhms"
			(at 40.64 162.56 0)
			(effects
				(font
					(size 1.27 1.27)
				)
				(justify left bottom)
				(hide yes)
			)
		)
		(property "Val" "100u"
			(at 68.58 151.8666 90)
			(effects
				(font
					(size 1.27 1.27)
					(thickness 0.15)
				)
				(justify left)
			)
		)
		(property "MPN" "T490A107M006ATE800"
			(at 53.34 162.56 0)
			(effects
				(font
					(size 1.27 1.27)
					(thickness 0.15)
				)
				(justify left bottom)
				(hide yes)
			)
		)
		(property "Manufacturer" "KEMET"
			(at 50.8 162.56 0)
			(effects
				(font
					(size 1.27 1.27)
					(thickness 0.15)
				)
				(justify left bottom)
				(hide yes)
			)
		)
		(property "License" "Apache-2.0"
			(at 48.26 162.56 0)
			(effects
				(font
					(size 1.27 1.27)
					(thickness 0.15)
				)
				(justify left bottom)
				(hide yes)
			)
		)
		(property "Author" "Antmicro"
			(at 45.72 162.56 0)
			(effects
				(font
					(size 1.27 1.27)
					(thickness 0.15)
				)
				(justify left bottom)
				(hide yes)
			)
		)
		(property "Voltage" "6V"
			(at 43.18 162.56 0)
			(effects
				(font
					(size 1.27 1.27)
				)
				(justify left bottom)
				(hide yes)
			)
		)
		(property "Dielectric" "template_dielectric"
			(at 40.64 162.56 0)
			(effects
				(font
					(size 1.27 1.27)
				)
				(justify left bottom)
				(hide yes)
			)
		)
		(pin "2"
		)
		(pin "1"
		)
		(instances
			(project "thunderbolt-to-10gbe-adapter"
				(path ""
					(reference "C332")
					(unit 1)
				)
			)
		)
	)
	(symbol
		(lib_id "antmicroCapacitors0402:C_1u_25V_0402")
		(at 124.46 127 90)
		(unit 1)
		(exclude_from_sim no)
		(in_bom yes)
		(on_board yes)
		(dnp no)
		(property "Reference" "C186"
			(at 126.238 123.19 90)
			(effects
				(font
					(size 1.27 1.27)
					(thickness 0.15)
				)
				(justify right)
			)
		)
		(property "Value" "C_1u_25V_0402"
			(at 134.62 106.68 0)
			(effects
				(font
					(size 1.27 1.27)
					(thickness 0.15)
				)
				(justify left bottom)
				(hide yes)
			)
		)
		(property "Footprint" "antmicro-footprints:C_0402_1005Metric"
			(at 137.16 106.68 0)
			(effects
				(font
					(size 1.27 1.27)
					(thickness 0.15)
				)
				(justify left bottom)
				(hide yes)
			)
		)
		(property "Datasheet" "https://www.murata.com/products/productdetail?partno=GRM155R61E105KE11%23"
			(at 139.7 106.68 0)
			(effects
				(font
					(size 1.27 1.27)
					(thickness 0.15)
				)
				(justify left bottom)
				(hide yes)
			)
		)
		(property "Description" "SMD Multilayer Ceramic Capacitor, 1 µF, 25 V, 0402 [1005 Metric], ± 10%, X5R, GRM Series"
			(at 124.46 127 0)
			(effects
				(font
					(size 1.27 1.27)
				)
				(hide yes)
			)
		)
		(property "MPN" "GRM155R61E105KE11J"
			(at 142.24 106.68 0)
			(effects
				(font
					(size 1.27 1.27)
					(thickness 0.15)
				)
				(justify left bottom)
				(hide yes)
			)
		)
		(property "Manufacturer" "Murata"
			(at 144.78 106.68 0)
			(effects
				(font
					(size 1.27 1.27)
					(thickness 0.15)
				)
				(justify left bottom)
				(hide yes)
			)
		)
		(property "License" "Apache-2.0"
			(at 147.32 106.68 0)
			(effects
				(font
					(size 1.27 1.27)
					(thickness 0.15)
				)
				(justify left bottom)
				(hide yes)
			)
		)
		(property "Author" "Antmicro"
			(at 149.86 106.68 0)
			(effects
				(font
					(size 1.27 1.27)
					(thickness 0.15)
				)
				(justify left bottom)
				(hide yes)
			)
		)
		(property "Val" "1u"
			(at 126.238 125.73 90)
			(effects
				(font
					(size 1.27 1.27)
					(thickness 0.15)
				)
				(justify right)
			)
		)
		(property "Voltage" "25V"
			(at 152.4 106.68 0)
			(effects
				(font
					(size 1.27 1.27)
				)
				(justify left bottom)
				(hide yes)
			)
		)
		(property "Dielectric" "X5R"
			(at 154.94 106.68 0)
			(effects
				(font
					(size 1.27 1.27)
				)
				(justify left bottom)
				(hide yes)
			)
		)
		(pin "2"
		)
		(pin "1"
		)
		(instances
			(project "OCuLink to 10GbE adapter"
				(path ""
					(reference "C142")
					(unit 1)
				)
			)
			(project "thunderbolt-to-10gbe-adapter"
				(path ""
					(reference "C186")
					(unit 1)
				)
			)
		)
	)
	(symbol
		(lib_id "antmicropower:GND")
		(at 142.24 54.61 0)
		(unit 1)
		(exclude_from_sim no)
		(in_bom yes)
		(on_board yes)
		(dnp no)
		(property "Reference" "#PWR0267"
			(at 151.13 57.15 0)
			(effects
				(font
					(size 1.27 1.27)
					(thickness 0.15)
				)
				(justify left bottom)
				(hide yes)
			)
		)
		(property "Value" "GND"
			(at 142.24 58.42 0)
			(effects
				(font
					(size 1.27 1.27)
					(thickness 0.15)
				)
			)
		)
		(property "Footprint" ""
			(at 151.13 62.23 0)
			(effects
				(font
					(size 1.27 1.27)
					(thickness 0.15)
				)
				(justify left bottom)
				(hide yes)
			)
		)
		(property "Datasheet" ""
			(at 151.13 67.31 0)
			(effects
				(font
					(size 1.27 1.27)
					(thickness 0.15)
				)
				(justify left bottom)
				(hide yes)
			)
		)
		(property "Description" ""
			(at 142.24 54.61 0)
			(effects
				(font
					(size 1.27 1.27)
				)
				(hide yes)
			)
		)
		(property "Author" "Antmicro"
			(at 151.13 62.23 0)
			(effects
				(font
					(size 1.27 1.27)
					(thickness 0.15)
				)
				(justify left bottom)
				(hide yes)
			)
		)
		(property "License" "Apache-2.0"
			(at 151.13 64.77 0)
			(effects
				(font
					(size 1.27 1.27)
					(thickness 0.15)
				)
				(justify left bottom)
				(hide yes)
			)
		)
		(pin "1"
		)
		(instances
			(project "OCuLink to 10GbE adapter"
				(path ""
					(reference "#PWR0119")
					(unit 1)
				)
			)
			(project "thunderbolt-to-10gbe-adapter"
				(path ""
					(reference "#PWR0267")
					(unit 1)
				)
			)
		)
	)
	(symbol
		(lib_id "antmicroCapacitors0402:C_1u_25V_0402")
		(at 344.17 113.03 90)
		(unit 1)
		(exclude_from_sim no)
		(in_bom yes)
		(on_board yes)
		(dnp no)
		(property "Reference" "C238"
			(at 346.202 109.22 90)
			(effects
				(font
					(size 1.27 1.27)
					(thickness 0.15)
				)
				(justify right)
			)
		)
		(property "Value" "C_1u_25V_0402"
			(at 354.33 92.71 0)
			(effects
				(font
					(size 1.27 1.27)
					(thickness 0.15)
				)
				(justify left bottom)
				(hide yes)
			)
		)
		(property "Footprint" "antmicro-footprints:C_0402_1005Metric"
			(at 356.87 92.71 0)
			(effects
				(font
					(size 1.27 1.27)
					(thickness 0.15)
				)
				(justify left bottom)
				(hide yes)
			)
		)
		(property "Datasheet" "https://www.murata.com/products/productdetail?partno=GRM155R61E105KE11%23"
			(at 359.41 92.71 0)
			(effects
				(font
					(size 1.27 1.27)
					(thickness 0.15)
				)
				(justify left bottom)
				(hide yes)
			)
		)
		(property "Description" "SMD Multilayer Ceramic Capacitor, 1 µF, 25 V, 0402 [1005 Metric], ± 10%, X5R, GRM Series"
			(at 344.17 113.03 0)
			(effects
				(font
					(size 1.27 1.27)
				)
				(hide yes)
			)
		)
		(property "MPN" "GRM155R61E105KE11J"
			(at 361.95 92.71 0)
			(effects
				(font
					(size 1.27 1.27)
					(thickness 0.15)
				)
				(justify left bottom)
				(hide yes)
			)
		)
		(property "Manufacturer" "Murata"
			(at 364.49 92.71 0)
			(effects
				(font
					(size 1.27 1.27)
					(thickness 0.15)
				)
				(justify left bottom)
				(hide yes)
			)
		)
		(property "License" "Apache-2.0"
			(at 367.03 92.71 0)
			(effects
				(font
					(size 1.27 1.27)
					(thickness 0.15)
				)
				(justify left bottom)
				(hide yes)
			)
		)
		(property "Author" "Antmicro"
			(at 369.57 92.71 0)
			(effects
				(font
					(size 1.27 1.27)
					(thickness 0.15)
				)
				(justify left bottom)
				(hide yes)
			)
		)
		(property "Val" "1u"
			(at 346.202 111.76 90)
			(effects
				(font
					(size 1.27 1.27)
					(thickness 0.15)
				)
				(justify right)
			)
		)
		(property "Voltage" "25V"
			(at 372.11 92.71 0)
			(effects
				(font
					(size 1.27 1.27)
				)
				(justify left bottom)
				(hide yes)
			)
		)
		(property "Dielectric" "X5R"
			(at 374.65 92.71 0)
			(effects
				(font
					(size 1.27 1.27)
				)
				(justify left bottom)
				(hide yes)
			)
		)
		(pin "2"
		)
		(pin "1"
		)
		(instances
			(project "OCuLink to 10GbE adapter"
				(path ""
					(reference "C134")
					(unit 1)
				)
			)
			(project "thunderbolt-to-10gbe-adapter"
				(path ""
					(reference "C238")
					(unit 1)
				)
			)
		)
	)
	(symbol
		(lib_id "antmicroCapacitors0402:C_1u_25V_0402")
		(at 299.72 52.07 90)
		(unit 1)
		(exclude_from_sim no)
		(in_bom yes)
		(on_board yes)
		(dnp no)
		(property "Reference" "C211"
			(at 301.752 48.26 90)
			(effects
				(font
					(size 1.27 1.27)
					(thickness 0.15)
				)
				(justify right)
			)
		)
		(property "Value" "C_1u_25V_0402"
			(at 309.88 31.75 0)
			(effects
				(font
					(size 1.27 1.27)
					(thickness 0.15)
				)
				(justify left bottom)
				(hide yes)
			)
		)
		(property "Footprint" "antmicro-footprints:C_0402_1005Metric"
			(at 312.42 31.75 0)
			(effects
				(font
					(size 1.27 1.27)
					(thickness 0.15)
				)
				(justify left bottom)
				(hide yes)
			)
		)
		(property "Datasheet" "https://www.murata.com/products/productdetail?partno=GRM155R61E105KE11%23"
			(at 314.96 31.75 0)
			(effects
				(font
					(size 1.27 1.27)
					(thickness 0.15)
				)
				(justify left bottom)
				(hide yes)
			)
		)
		(property "Description" "SMD Multilayer Ceramic Capacitor, 1 µF, 25 V, 0402 [1005 Metric], ± 10%, X5R, GRM Series"
			(at 299.72 52.07 0)
			(effects
				(font
					(size 1.27 1.27)
				)
				(hide yes)
			)
		)
		(property "MPN" "GRM155R61E105KE11J"
			(at 317.5 31.75 0)
			(effects
				(font
					(size 1.27 1.27)
					(thickness 0.15)
				)
				(justify left bottom)
				(hide yes)
			)
		)
		(property "Manufacturer" "Murata"
			(at 320.04 31.75 0)
			(effects
				(font
					(size 1.27 1.27)
					(thickness 0.15)
				)
				(justify left bottom)
				(hide yes)
			)
		)
		(property "License" "Apache-2.0"
			(at 322.58 31.75 0)
			(effects
				(font
					(size 1.27 1.27)
					(thickness 0.15)
				)
				(justify left bottom)
				(hide yes)
			)
		)
		(property "Author" "Antmicro"
			(at 325.12 31.75 0)
			(effects
				(font
					(size 1.27 1.27)
					(thickness 0.15)
				)
				(justify left bottom)
				(hide yes)
			)
		)
		(property "Val" "1u"
			(at 301.752 50.8 90)
			(effects
				(font
					(size 1.27 1.27)
					(thickness 0.15)
				)
				(justify right)
			)
		)
		(property "Voltage" "25V"
			(at 327.66 31.75 0)
			(effects
				(font
					(size 1.27 1.27)
				)
				(justify left bottom)
				(hide yes)
			)
		)
		(property "Dielectric" "X5R"
			(at 330.2 31.75 0)
			(effects
				(font
					(size 1.27 1.27)
				)
				(justify left bottom)
				(hide yes)
			)
		)
		(pin "2"
		)
		(pin "1"
		)
		(instances
			(project "OCuLink to 10GbE adapter"
				(path ""
					(reference "C87")
					(unit 1)
				)
			)
			(project "thunderbolt-to-10gbe-adapter"
				(path ""
					(reference "C211")
					(unit 1)
				)
			)
		)
	)
	(symbol
		(lib_id "antmicropower:+1V0")
		(at 26.67 143.51 0)
		(unit 1)
		(exclude_from_sim no)
		(in_bom yes)
		(on_board yes)
		(dnp no)
		(property "Reference" "#PWR0220"
			(at 26.67 147.32 0)
			(effects
				(font
					(size 1.27 1.27)
				)
				(hide yes)
			)
		)
		(property "Value" "+1V0"
			(at 26.67 139.7 0)
			(effects
				(font
					(size 1.27 1.27)
				)
			)
		)
		(property "Footprint" ""
			(at 26.67 143.51 0)
			(effects
				(font
					(size 1.27 1.27)
				)
				(hide yes)
			)
		)
		(property "Datasheet" ""
			(at 26.67 143.51 0)
			(effects
				(font
					(size 1.27 1.27)
				)
				(hide yes)
			)
		)
		(property "Description" ""
			(at 26.67 143.51 0)
			(effects
				(font
					(size 1.27 1.27)
				)
				(hide yes)
			)
		)
		(pin "1"
		)
		(instances
			(project ""
				(path ""
					(reference "#PWR0205")
					(unit 1)
				)
			)
			(project "thunderbolt-to-10gbe-adapter"
				(path ""
					(reference "#PWR0220")
					(unit 1)
				)
			)
		)
	)
	(symbol
		(lib_id "antmicroCapacitors0603:C_22u_16V_0603")
		(at 361.95 130.81 90)
		(unit 1)
		(exclude_from_sim no)
		(in_bom yes)
		(on_board yes)
		(dnp no)
		(fields_autoplaced yes)
		(property "Reference" "C249"
			(at 364.49 126.9936 90)
			(effects
				(font
					(size 1.27 1.27)
					(thickness 0.15)
				)
				(justify right)
			)
		)
		(property "Value" "C_22u_16V_0603"
			(at 372.11 110.49 0)
			(effects
				(font
					(size 1.27 1.27)
					(thickness 0.15)
				)
				(justify left bottom)
				(hide yes)
			)
		)
		(property "Footprint" "antmicro-footprints:C_0603_1608Metric_EIA"
			(at 374.65 110.49 0)
			(effects
				(font
					(size 1.27 1.27)
					(thickness 0.15)
				)
				(justify left bottom)
				(hide yes)
			)
		)
		(property "Datasheet" "https://product.samsungsem.com/mlcc/CL10A226MO7JZN.do"
			(at 377.19 110.49 0)
			(effects
				(font
					(size 1.27 1.27)
					(thickness 0.15)
				)
				(justify left bottom)
				(hide yes)
			)
		)
		(property "Description" "SMD Multilayer Ceramic Capacitor"
			(at 361.95 130.81 0)
			(effects
				(font
					(size 1.27 1.27)
				)
				(hide yes)
			)
		)
		(property "MPN" "CL10A226MO7JZNC"
			(at 379.73 110.49 0)
			(effects
				(font
					(size 1.27 1.27)
					(thickness 0.15)
				)
				(justify left bottom)
				(hide yes)
			)
		)
		(property "Manufacturer" "Samsung Electro-Mechanics"
			(at 382.27 110.49 0)
			(effects
				(font
					(size 1.27 1.27)
					(thickness 0.15)
				)
				(justify left bottom)
				(hide yes)
			)
		)
		(property "License" "Apache-2.0"
			(at 384.81 110.49 0)
			(effects
				(font
					(size 1.27 1.27)
					(thickness 0.15)
				)
				(justify left bottom)
				(hide yes)
			)
		)
		(property "Author" "Antmicro"
			(at 387.35 110.49 0)
			(effects
				(font
					(size 1.27 1.27)
					(thickness 0.15)
				)
				(justify left bottom)
				(hide yes)
			)
		)
		(property "Val" "22u"
			(at 364.49 129.5336 90)
			(effects
				(font
					(size 1.27 1.27)
					(thickness 0.15)
				)
				(justify right)
			)
		)
		(property "Voltage" "16V"
			(at 389.89 110.49 0)
			(effects
				(font
					(size 1.27 1.27)
				)
				(justify left bottom)
				(hide yes)
			)
		)
		(property "Dielectric" ""
			(at 392.43 110.49 0)
			(effects
				(font
					(size 1.27 1.27)
				)
				(justify left bottom)
				(hide yes)
			)
		)
		(pin "1"
		)
		(pin "2"
		)
		(instances
			(project "OCuLink to 10GbE adapter"
				(path ""
					(reference "C152")
					(unit 1)
				)
			)
			(project "thunderbolt-to-10gbe-adapter"
				(path ""
					(reference "C249")
					(unit 1)
				)
			)
		)
	)
	(symbol
		(lib_id "antmicroCapacitors0402:C_1u_25V_0402")
		(at 133.35 207.01 90)
		(unit 1)
		(exclude_from_sim no)
		(in_bom yes)
		(on_board yes)
		(dnp no)
		(property "Reference" "C195"
			(at 135.382 203.2 90)
			(effects
				(font
					(size 1.27 1.27)
					(thickness 0.15)
				)
				(justify right)
			)
		)
		(property "Value" "C_1u_25V_0402"
			(at 143.51 186.69 0)
			(effects
				(font
					(size 1.27 1.27)
					(thickness 0.15)
				)
				(justify left bottom)
				(hide yes)
			)
		)
		(property "Footprint" "antmicro-footprints:C_0402_1005Metric"
			(at 146.05 186.69 0)
			(effects
				(font
					(size 1.27 1.27)
					(thickness 0.15)
				)
				(justify left bottom)
				(hide yes)
			)
		)
		(property "Datasheet" "https://www.murata.com/products/productdetail?partno=GRM155R61E105KE11%23"
			(at 148.59 186.69 0)
			(effects
				(font
					(size 1.27 1.27)
					(thickness 0.15)
				)
				(justify left bottom)
				(hide yes)
			)
		)
		(property "Description" "SMD Multilayer Ceramic Capacitor, 1 µF, 25 V, 0402 [1005 Metric], ± 10%, X5R, GRM Series"
			(at 133.35 207.01 0)
			(effects
				(font
					(size 1.27 1.27)
				)
				(hide yes)
			)
		)
		(property "MPN" "GRM155R61E105KE11J"
			(at 151.13 186.69 0)
			(effects
				(font
					(size 1.27 1.27)
					(thickness 0.15)
				)
				(justify left bottom)
				(hide yes)
			)
		)
		(property "Manufacturer" "Murata"
			(at 153.67 186.69 0)
			(effects
				(font
					(size 1.27 1.27)
					(thickness 0.15)
				)
				(justify left bottom)
				(hide yes)
			)
		)
		(property "License" "Apache-2.0"
			(at 156.21 186.69 0)
			(effects
				(font
					(size 1.27 1.27)
					(thickness 0.15)
				)
				(justify left bottom)
				(hide yes)
			)
		)
		(property "Author" "Antmicro"
			(at 158.75 186.69 0)
			(effects
				(font
					(size 1.27 1.27)
					(thickness 0.15)
				)
				(justify left bottom)
				(hide yes)
			)
		)
		(property "Val" "1u"
			(at 135.382 205.74 90)
			(effects
				(font
					(size 1.27 1.27)
					(thickness 0.15)
				)
				(justify right)
			)
		)
		(property "Voltage" "25V"
			(at 161.29 186.69 0)
			(effects
				(font
					(size 1.27 1.27)
				)
				(justify left bottom)
				(hide yes)
			)
		)
		(property "Dielectric" "X5R"
			(at 163.83 186.69 0)
			(effects
				(font
					(size 1.27 1.27)
				)
				(justify left bottom)
				(hide yes)
			)
		)
		(pin "2"
		)
		(pin "1"
		)
		(instances
			(project "OCuLink to 10GbE adapter"
				(path ""
					(reference "C182")
					(unit 1)
				)
			)
			(project "thunderbolt-to-10gbe-adapter"
				(path ""
					(reference "C195")
					(unit 1)
				)
			)
		)
	)
	(symbol
		(lib_id "antmicroCapacitors0603:C_22u_16V_0603")
		(at 361.95 91.44 90)
		(unit 1)
		(exclude_from_sim no)
		(in_bom yes)
		(on_board yes)
		(dnp no)
		(fields_autoplaced yes)
		(property "Reference" "C247"
			(at 364.49 87.6236 90)
			(effects
				(font
					(size 1.27 1.27)
					(thickness 0.15)
				)
				(justify right)
			)
		)
		(property "Value" "C_22u_16V_0603"
			(at 372.11 71.12 0)
			(effects
				(font
					(size 1.27 1.27)
					(thickness 0.15)
				)
				(justify left bottom)
				(hide yes)
			)
		)
		(property "Footprint" "antmicro-footprints:C_0603_1608Metric_EIA"
			(at 374.65 71.12 0)
			(effects
				(font
					(size 1.27 1.27)
					(thickness 0.15)
				)
				(justify left bottom)
				(hide yes)
			)
		)
		(property "Datasheet" "https://product.samsungsem.com/mlcc/CL10A226MO7JZN.do"
			(at 377.19 71.12 0)
			(effects
				(font
					(size 1.27 1.27)
					(thickness 0.15)
				)
				(justify left bottom)
				(hide yes)
			)
		)
		(property "Description" "SMD Multilayer Ceramic Capacitor"
			(at 361.95 91.44 0)
			(effects
				(font
					(size 1.27 1.27)
				)
				(hide yes)
			)
		)
		(property "MPN" "CL10A226MO7JZNC"
			(at 379.73 71.12 0)
			(effects
				(font
					(size 1.27 1.27)
					(thickness 0.15)
				)
				(justify left bottom)
				(hide yes)
			)
		)
		(property "Manufacturer" "Samsung Electro-Mechanics"
			(at 382.27 71.12 0)
			(effects
				(font
					(size 1.27 1.27)
					(thickness 0.15)
				)
				(justify left bottom)
				(hide yes)
			)
		)
		(property "License" "Apache-2.0"
			(at 384.81 71.12 0)
			(effects
				(font
					(size 1.27 1.27)
					(thickness 0.15)
				)
				(justify left bottom)
				(hide yes)
			)
		)
		(property "Author" "Antmicro"
			(at 387.35 71.12 0)
			(effects
				(font
					(size 1.27 1.27)
					(thickness 0.15)
				)
				(justify left bottom)
				(hide yes)
			)
		)
		(property "Val" "22u"
			(at 364.49 90.1636 90)
			(effects
				(font
					(size 1.27 1.27)
					(thickness 0.15)
				)
				(justify right)
			)
		)
		(property "Voltage" "16V"
			(at 389.89 71.12 0)
			(effects
				(font
					(size 1.27 1.27)
				)
				(justify left bottom)
				(hide yes)
			)
		)
		(property "Dielectric" ""
			(at 392.43 71.12 0)
			(effects
				(font
					(size 1.27 1.27)
				)
				(justify left bottom)
				(hide yes)
			)
		)
		(pin "1"
		)
		(pin "2"
		)
		(instances
			(project "OCuLink to 10GbE adapter"
				(path ""
					(reference "C123")
					(unit 1)
				)
			)
			(project "thunderbolt-to-10gbe-adapter"
				(path ""
					(reference "C247")
					(unit 1)
				)
			)
		)
	)
	(symbol
		(lib_id "antmicroCapacitors0402:C_1u_25V_0402")
		(at 133.35 153.67 90)
		(unit 1)
		(exclude_from_sim no)
		(in_bom yes)
		(on_board yes)
		(dnp no)
		(property "Reference" "C193"
			(at 135.382 149.86 90)
			(effects
				(font
					(size 1.27 1.27)
					(thickness 0.15)
				)
				(justify right)
			)
		)
		(property "Value" "C_1u_25V_0402"
			(at 143.51 133.35 0)
			(effects
				(font
					(size 1.27 1.27)
					(thickness 0.15)
				)
				(justify left bottom)
				(hide yes)
			)
		)
		(property "Footprint" "antmicro-footprints:C_0402_1005Metric"
			(at 146.05 133.35 0)
			(effects
				(font
					(size 1.27 1.27)
					(thickness 0.15)
				)
				(justify left bottom)
				(hide yes)
			)
		)
		(property "Datasheet" "https://www.murata.com/products/productdetail?partno=GRM155R61E105KE11%23"
			(at 148.59 133.35 0)
			(effects
				(font
					(size 1.27 1.27)
					(thickness 0.15)
				)
				(justify left bottom)
				(hide yes)
			)
		)
		(property "Description" "SMD Multilayer Ceramic Capacitor, 1 µF, 25 V, 0402 [1005 Metric], ± 10%, X5R, GRM Series"
			(at 133.35 153.67 0)
			(effects
				(font
					(size 1.27 1.27)
				)
				(hide yes)
			)
		)
		(property "MPN" "GRM155R61E105KE11J"
			(at 151.13 133.35 0)
			(effects
				(font
					(size 1.27 1.27)
					(thickness 0.15)
				)
				(justify left bottom)
				(hide yes)
			)
		)
		(property "Manufacturer" "Murata"
			(at 153.67 133.35 0)
			(effects
				(font
					(size 1.27 1.27)
					(thickness 0.15)
				)
				(justify left bottom)
				(hide yes)
			)
		)
		(property "License" "Apache-2.0"
			(at 156.21 133.35 0)
			(effects
				(font
					(size 1.27 1.27)
					(thickness 0.15)
				)
				(justify left bottom)
				(hide yes)
			)
		)
		(property "Author" "Antmicro"
			(at 158.75 133.35 0)
			(effects
				(font
					(size 1.27 1.27)
					(thickness 0.15)
				)
				(justify left bottom)
				(hide yes)
			)
		)
		(property "Val" "1u"
			(at 135.382 152.4 90)
			(effects
				(font
					(size 1.27 1.27)
					(thickness 0.15)
				)
				(justify right)
			)
		)
		(property "Voltage" "25V"
			(at 161.29 133.35 0)
			(effects
				(font
					(size 1.27 1.27)
				)
				(justify left bottom)
				(hide yes)
			)
		)
		(property "Dielectric" "X5R"
			(at 163.83 133.35 0)
			(effects
				(font
					(size 1.27 1.27)
				)
				(justify left bottom)
				(hide yes)
			)
		)
		(pin "2"
		)
		(pin "1"
		)
		(instances
			(project "OCuLink to 10GbE adapter"
				(path ""
					(reference "C167")
					(unit 1)
				)
			)
			(project "thunderbolt-to-10gbe-adapter"
				(path ""
					(reference "C193")
					(unit 1)
				)
			)
		)
	)
	(symbol
		(lib_id "antmicropower:GND")
		(at 151.13 129.54 0)
		(unit 1)
		(exclude_from_sim no)
		(in_bom yes)
		(on_board yes)
		(dnp no)
		(property "Reference" "#PWR0275"
			(at 160.02 132.08 0)
			(effects
				(font
					(size 1.27 1.27)
					(thickness 0.15)
				)
				(justify left bottom)
				(hide yes)
			)
		)
		(property "Value" "GND"
			(at 151.13 133.35 0)
			(effects
				(font
					(size 1.27 1.27)
					(thickness 0.15)
				)
			)
		)
		(property "Footprint" ""
			(at 160.02 137.16 0)
			(effects
				(font
					(size 1.27 1.27)
					(thickness 0.15)
				)
				(justify left bottom)
				(hide yes)
			)
		)
		(property "Datasheet" ""
			(at 160.02 142.24 0)
			(effects
				(font
					(size 1.27 1.27)
					(thickness 0.15)
				)
				(justify left bottom)
				(hide yes)
			)
		)
		(property "Description" ""
			(at 151.13 129.54 0)
			(effects
				(font
					(size 1.27 1.27)
				)
				(hide yes)
			)
		)
		(property "Author" "Antmicro"
			(at 160.02 137.16 0)
			(effects
				(font
					(size 1.27 1.27)
					(thickness 0.15)
				)
				(justify left bottom)
				(hide yes)
			)
		)
		(property "License" "Apache-2.0"
			(at 160.02 139.7 0)
			(effects
				(font
					(size 1.27 1.27)
					(thickness 0.15)
				)
				(justify left bottom)
				(hide yes)
			)
		)
		(pin "1"
		)
		(instances
			(project "OCuLink to 10GbE adapter"
				(path ""
					(reference "#PWR0194")
					(unit 1)
				)
			)
			(project "thunderbolt-to-10gbe-adapter"
				(path ""
					(reference "#PWR0275")
					(unit 1)
				)
			)
		)
	)
	(symbol
		(lib_id "antmicropower:VDD")
		(at 208.28 116.84 0)
		(unit 1)
		(exclude_from_sim no)
		(in_bom yes)
		(on_board yes)
		(dnp no)
		(property "Reference" "#PWR0284"
			(at 208.28 120.65 0)
			(effects
				(font
					(size 1.27 1.27)
				)
				(hide yes)
			)
		)
		(property "Value" "P0_AVDDL"
			(at 208.28 113.03 0)
			(effects
				(font
					(size 1.27 1.27)
				)
			)
		)
		(property "Footprint" ""
			(at 208.28 116.84 0)
			(effects
				(font
					(size 1.27 1.27)
				)
				(hide yes)
			)
		)
		(property "Datasheet" ""
			(at 208.28 116.84 0)
			(effects
				(font
					(size 1.27 1.27)
				)
				(hide yes)
			)
		)
		(property "Description" ""
			(at 208.28 116.84 0)
			(effects
				(font
					(size 1.27 1.27)
				)
				(hide yes)
			)
		)
		(pin "1"
		)
		(instances
			(project "OCuLink to 10GbE adapter"
				(path ""
					(reference "#PWR0155")
					(unit 1)
				)
			)
			(project "thunderbolt-to-10gbe-adapter"
				(path ""
					(reference "#PWR0284")
					(unit 1)
				)
			)
		)
	)
	(symbol
		(lib_id "antmicroCapacitors0402:C_1u_25V_0402")
		(at 142.24 153.67 90)
		(unit 1)
		(exclude_from_sim no)
		(in_bom yes)
		(on_board yes)
		(dnp no)
		(property "Reference" "C199"
			(at 144.272 149.86 90)
			(effects
				(font
					(size 1.27 1.27)
					(thickness 0.15)
				)
				(justify right)
			)
		)
		(property "Value" "C_1u_25V_0402"
			(at 152.4 133.35 0)
			(effects
				(font
					(size 1.27 1.27)
					(thickness 0.15)
				)
				(justify left bottom)
				(hide yes)
			)
		)
		(property "Footprint" "antmicro-footprints:C_0402_1005Metric"
			(at 154.94 133.35 0)
			(effects
				(font
					(size 1.27 1.27)
					(thickness 0.15)
				)
				(justify left bottom)
				(hide yes)
			)
		)
		(property "Datasheet" "https://www.murata.com/products/productdetail?partno=GRM155R61E105KE11%23"
			(at 157.48 133.35 0)
			(effects
				(font
					(size 1.27 1.27)
					(thickness 0.15)
				)
				(justify left bottom)
				(hide yes)
			)
		)
		(property "Description" "SMD Multilayer Ceramic Capacitor, 1 µF, 25 V, 0402 [1005 Metric], ± 10%, X5R, GRM Series"
			(at 142.24 153.67 0)
			(effects
				(font
					(size 1.27 1.27)
				)
				(hide yes)
			)
		)
		(property "MPN" "GRM155R61E105KE11J"
			(at 160.02 133.35 0)
			(effects
				(font
					(size 1.27 1.27)
					(thickness 0.15)
				)
				(justify left bottom)
				(hide yes)
			)
		)
		(property "Manufacturer" "Murata"
			(at 162.56 133.35 0)
			(effects
				(font
					(size 1.27 1.27)
					(thickness 0.15)
				)
				(justify left bottom)
				(hide yes)
			)
		)
		(property "License" "Apache-2.0"
			(at 165.1 133.35 0)
			(effects
				(font
					(size 1.27 1.27)
					(thickness 0.15)
				)
				(justify left bottom)
				(hide yes)
			)
		)
		(property "Author" "Antmicro"
			(at 167.64 133.35 0)
			(effects
				(font
					(size 1.27 1.27)
					(thickness 0.15)
				)
				(justify left bottom)
				(hide yes)
			)
		)
		(property "Val" "1u"
			(at 144.272 152.4 90)
			(effects
				(font
					(size 1.27 1.27)
					(thickness 0.15)
				)
				(justify right)
			)
		)
		(property "Voltage" "25V"
			(at 170.18 133.35 0)
			(effects
				(font
					(size 1.27 1.27)
				)
				(justify left bottom)
				(hide yes)
			)
		)
		(property "Dielectric" "X5R"
			(at 172.72 133.35 0)
			(effects
				(font
					(size 1.27 1.27)
				)
				(justify left bottom)
				(hide yes)
			)
		)
		(pin "2"
		)
		(pin "1"
		)
		(instances
			(project "OCuLink to 10GbE adapter"
				(path ""
					(reference "C168")
					(unit 1)
				)
			)
			(project "thunderbolt-to-10gbe-adapter"
				(path ""
					(reference "C199")
					(unit 1)
				)
			)
		)
	)
	(symbol
		(lib_id "antmicroFerriteBeadsandChips:FB_470Z_1A_Murata-BLM18PG_0603")
		(at 81.28 92.71 0)
		(unit 1)
		(exclude_from_sim no)
		(in_bom yes)
		(on_board yes)
		(dnp no)
		(fields_autoplaced yes)
		(property "Reference" "FB4"
			(at 83.7819 86.36 0)
			(effects
				(font
					(size 1.27 1.27)
					(thickness 0.15)
				)
			)
		)
		(property "Value" "FB_470Z_1A_Murata-BLM18PG_0603"
			(at 95.25 95.25 0)
			(effects
				(font
					(size 1.27 1.27)
					(thickness 0.15)
				)
				(justify left bottom)
				(hide yes)
			)
		)
		(property "Footprint" "antmicro-footprints:FB_0603_1608Metric"
			(at 95.25 100.33 0)
			(effects
				(font
					(size 1.27 1.27)
					(thickness 0.15)
				)
				(justify left bottom)
				(hide yes)
			)
		)
		(property "Datasheet" "https://www.murata.com/en-us/products/productdata/8796738650142/ENFA0003.pdf"
			(at 95.25 102.87 0)
			(effects
				(font
					(size 1.27 1.27)
					(thickness 0.15)
				)
				(justify left bottom)
				(hide yes)
			)
		)
		(property "Description" "Ferrite Bead, 0603 [1608 Metric], 470 ohm, 1 A, BLM18P, 0.2 ohm, ± 25%, DC power line"
			(at 81.28 92.71 0)
			(effects
				(font
					(size 1.27 1.27)
				)
				(hide yes)
			)
		)
		(property "Val" "470Z/1A"
			(at 83.7819 88.9 0)
			(effects
				(font
					(size 1.27 1.27)
				)
			)
		)
		(property "MPN" "BLM18PG471SN1D"
			(at 95.25 105.41 0)
			(effects
				(font
					(size 1.27 1.27)
					(thickness 0.15)
				)
				(justify left bottom)
				(hide yes)
			)
		)
		(property "Manufacturer" "Murata"
			(at 95.25 107.95 0)
			(effects
				(font
					(size 1.27 1.27)
					(thickness 0.15)
				)
				(justify left bottom)
				(hide yes)
			)
		)
		(property "Current" ""
			(at 101.6 115.57 0)
			(effects
				(font
					(size 1.27 1.27)
					(thickness 0.15)
				)
				(justify left bottom)
				(hide yes)
			)
		)
		(property "Author" "Antmicro"
			(at 95.25 110.49 0)
			(effects
				(font
					(size 1.27 1.27)
					(thickness 0.15)
				)
				(justify left bottom)
				(hide yes)
			)
		)
		(property "License" "Apache-2.0"
			(at 95.25 113.03 0)
			(effects
				(font
					(size 1.27 1.27)
					(thickness 0.15)
				)
				(justify left bottom)
				(hide yes)
			)
		)
		(pin "2"
		)
		(pin "1"
		)
		(instances
			(project "OCuLink to 10GbE adapter"
				(path ""
					(reference "FB3")
					(unit 1)
				)
			)
			(project "thunderbolt-to-10gbe-adapter"
				(path ""
					(reference "FB4")
					(unit 1)
				)
			)
		)
	)
	(symbol
		(lib_id "antmicropower:GND")
		(at 115.57 129.54 0)
		(unit 1)
		(exclude_from_sim no)
		(in_bom yes)
		(on_board yes)
		(dnp no)
		(property "Reference" "#PWR0254"
			(at 124.46 132.08 0)
			(effects
				(font
					(size 1.27 1.27)
					(thickness 0.15)
				)
				(justify left bottom)
				(hide yes)
			)
		)
		(property "Value" "GND"
			(at 115.57 133.35 0)
			(effects
				(font
					(size 1.27 1.27)
					(thickness 0.15)
				)
			)
		)
		(property "Footprint" ""
			(at 124.46 137.16 0)
			(effects
				(font
					(size 1.27 1.27)
					(thickness 0.15)
				)
				(justify left bottom)
				(hide yes)
			)
		)
		(property "Datasheet" ""
			(at 124.46 142.24 0)
			(effects
				(font
					(size 1.27 1.27)
					(thickness 0.15)
				)
				(justify left bottom)
				(hide yes)
			)
		)
		(property "Description" ""
			(at 115.57 129.54 0)
			(effects
				(font
					(size 1.27 1.27)
				)
				(hide yes)
			)
		)
		(property "Author" "Antmicro"
			(at 124.46 137.16 0)
			(effects
				(font
					(size 1.27 1.27)
					(thickness 0.15)
				)
				(justify left bottom)
				(hide yes)
			)
		)
		(property "License" "Apache-2.0"
			(at 124.46 139.7 0)
			(effects
				(font
					(size 1.27 1.27)
					(thickness 0.15)
				)
				(justify left bottom)
				(hide yes)
			)
		)
		(pin "1"
		)
		(instances
			(project "OCuLink to 10GbE adapter"
				(path ""
					(reference "#PWR0190")
					(unit 1)
				)
			)
			(project "thunderbolt-to-10gbe-adapter"
				(path ""
					(reference "#PWR0254")
					(unit 1)
				)
			)
		)
	)
	(symbol
		(lib_id "antmicroCapacitors0603:C_22u_16V_0603")
		(at 67.31 180.34 90)
		(unit 1)
		(exclude_from_sim no)
		(in_bom yes)
		(on_board yes)
		(dnp no)
		(property "Reference" "C156"
			(at 69.342 176.53 90)
			(effects
				(font
					(size 1.27 1.27)
					(thickness 0.15)
				)
				(justify right)
			)
		)
		(property "Value" "C_22u_16V_0603"
			(at 77.47 160.02 0)
			(effects
				(font
					(size 1.27 1.27)
					(thickness 0.15)
				)
				(justify left bottom)
				(hide yes)
			)
		)
		(property "Footprint" "antmicro-footprints:C_0603_1608Metric_EIA"
			(at 80.01 160.02 0)
			(effects
				(font
					(size 1.27 1.27)
					(thickness 0.15)
				)
				(justify left bottom)
				(hide yes)
			)
		)
		(property "Datasheet" "https://product.samsungsem.com/mlcc/CL10A226MO7JZN.do"
			(at 82.55 160.02 0)
			(effects
				(font
					(size 1.27 1.27)
					(thickness 0.15)
				)
				(justify left bottom)
				(hide yes)
			)
		)
		(property "Description" "SMD Multilayer Ceramic Capacitor"
			(at 67.31 180.34 0)
			(effects
				(font
					(size 1.27 1.27)
				)
				(hide yes)
			)
		)
		(property "MPN" "CL10A226MO7JZNC"
			(at 85.09 160.02 0)
			(effects
				(font
					(size 1.27 1.27)
					(thickness 0.15)
				)
				(justify left bottom)
				(hide yes)
			)
		)
		(property "Manufacturer" "Samsung Electro-Mechanics"
			(at 87.63 160.02 0)
			(effects
				(font
					(size 1.27 1.27)
					(thickness 0.15)
				)
				(justify left bottom)
				(hide yes)
			)
		)
		(property "License" "Apache-2.0"
			(at 90.17 160.02 0)
			(effects
				(font
					(size 1.27 1.27)
					(thickness 0.15)
				)
				(justify left bottom)
				(hide yes)
			)
		)
		(property "Author" "Antmicro"
			(at 92.71 160.02 0)
			(effects
				(font
					(size 1.27 1.27)
					(thickness 0.15)
				)
				(justify left bottom)
				(hide yes)
			)
		)
		(property "Val" "22u"
			(at 69.342 179.07 90)
			(effects
				(font
					(size 1.27 1.27)
					(thickness 0.15)
				)
				(justify right)
			)
		)
		(property "Voltage" "16V"
			(at 95.25 160.02 0)
			(effects
				(font
					(size 1.27 1.27)
				)
				(justify left bottom)
				(hide yes)
			)
		)
		(property "Dielectric" ""
			(at 97.79 160.02 0)
			(effects
				(font
					(size 1.27 1.27)
				)
				(justify left bottom)
				(hide yes)
			)
		)
		(pin "1"
		)
		(pin "2"
		)
		(instances
			(project "OCuLink to 10GbE adapter"
				(path ""
					(reference "C170")
					(unit 1)
				)
			)
			(project "thunderbolt-to-10gbe-adapter"
				(path ""
					(reference "C156")
					(unit 1)
				)
			)
		)
	)
	(symbol
		(lib_id "antmicropower:GND")
		(at 335.28 93.98 0)
		(unit 1)
		(exclude_from_sim no)
		(in_bom yes)
		(on_board yes)
		(dnp no)
		(property "Reference" "#PWR0320"
			(at 344.17 96.52 0)
			(effects
				(font
					(size 1.27 1.27)
					(thickness 0.15)
				)
				(justify left bottom)
				(hide yes)
			)
		)
		(property "Value" "GND"
			(at 335.28 97.79 0)
			(effects
				(font
					(size 1.27 1.27)
					(thickness 0.15)
				)
			)
		)
		(property "Footprint" ""
			(at 344.17 101.6 0)
			(effects
				(font
					(size 1.27 1.27)
					(thickness 0.15)
				)
				(justify left bottom)
				(hide yes)
			)
		)
		(property "Datasheet" ""
			(at 344.17 106.68 0)
			(effects
				(font
					(size 1.27 1.27)
					(thickness 0.15)
				)
				(justify left bottom)
				(hide yes)
			)
		)
		(property "Description" ""
			(at 335.28 93.98 0)
			(effects
				(font
					(size 1.27 1.27)
				)
				(hide yes)
			)
		)
		(property "Author" "Antmicro"
			(at 344.17 101.6 0)
			(effects
				(font
					(size 1.27 1.27)
					(thickness 0.15)
				)
				(justify left bottom)
				(hide yes)
			)
		)
		(property "License" "Apache-2.0"
			(at 344.17 104.14 0)
			(effects
				(font
					(size 1.27 1.27)
					(thickness 0.15)
				)
				(justify left bottom)
				(hide yes)
			)
		)
		(pin "1"
		)
		(instances
			(project "OCuLink to 10GbE adapter"
				(path ""
					(reference "#PWR0168")
					(unit 1)
				)
			)
			(project "thunderbolt-to-10gbe-adapter"
				(path ""
					(reference "#PWR0320")
					(unit 1)
				)
			)
		)
	)
	(symbol
		(lib_id "antmicroCapacitors0402:C_1u_25V_0402")
		(at 344.17 73.66 90)
		(unit 1)
		(exclude_from_sim no)
		(in_bom yes)
		(on_board yes)
		(dnp no)
		(property "Reference" "C237"
			(at 346.202 69.85 90)
			(effects
				(font
					(size 1.27 1.27)
					(thickness 0.15)
				)
				(justify right)
			)
		)
		(property "Value" "C_1u_25V_0402"
			(at 354.33 53.34 0)
			(effects
				(font
					(size 1.27 1.27)
					(thickness 0.15)
				)
				(justify left bottom)
				(hide yes)
			)
		)
		(property "Footprint" "antmicro-footprints:C_0402_1005Metric"
			(at 356.87 53.34 0)
			(effects
				(font
					(size 1.27 1.27)
					(thickness 0.15)
				)
				(justify left bottom)
				(hide yes)
			)
		)
		(property "Datasheet" "https://www.murata.com/products/productdetail?partno=GRM155R61E105KE11%23"
			(at 359.41 53.34 0)
			(effects
				(font
					(size 1.27 1.27)
					(thickness 0.15)
				)
				(justify left bottom)
				(hide yes)
			)
		)
		(property "Description" "SMD Multilayer Ceramic Capacitor, 1 µF, 25 V, 0402 [1005 Metric], ± 10%, X5R, GRM Series"
			(at 344.17 73.66 0)
			(effects
				(font
					(size 1.27 1.27)
				)
				(hide yes)
			)
		)
		(property "MPN" "GRM155R61E105KE11J"
			(at 361.95 53.34 0)
			(effects
				(font
					(size 1.27 1.27)
					(thickness 0.15)
				)
				(justify left bottom)
				(hide yes)
			)
		)
		(property "Manufacturer" "Murata"
			(at 364.49 53.34 0)
			(effects
				(font
					(size 1.27 1.27)
					(thickness 0.15)
				)
				(justify left bottom)
				(hide yes)
			)
		)
		(property "License" "Apache-2.0"
			(at 367.03 53.34 0)
			(effects
				(font
					(size 1.27 1.27)
					(thickness 0.15)
				)
				(justify left bottom)
				(hide yes)
			)
		)
		(property "Author" "Antmicro"
			(at 369.57 53.34 0)
			(effects
				(font
					(size 1.27 1.27)
					(thickness 0.15)
				)
				(justify left bottom)
				(hide yes)
			)
		)
		(property "Val" "1u"
			(at 346.202 72.39 90)
			(effects
				(font
					(size 1.27 1.27)
					(thickness 0.15)
				)
				(justify right)
			)
		)
		(property "Voltage" "25V"
			(at 372.11 53.34 0)
			(effects
				(font
					(size 1.27 1.27)
				)
				(justify left bottom)
				(hide yes)
			)
		)
		(property "Dielectric" "X5R"
			(at 374.65 53.34 0)
			(effects
				(font
					(size 1.27 1.27)
				)
				(justify left bottom)
				(hide yes)
			)
		)
		(pin "2"
		)
		(pin "1"
		)
		(instances
			(project "OCuLink to 10GbE adapter"
				(path ""
					(reference "C110")
					(unit 1)
				)
			)
			(project "thunderbolt-to-10gbe-adapter"
				(path ""
					(reference "C237")
					(unit 1)
				)
			)
		)
	)
	(symbol
		(lib_id "antmicropower:GND")
		(at 379.73 93.98 0)
		(unit 1)
		(exclude_from_sim no)
		(in_bom yes)
		(on_board yes)
		(dnp no)
		(property "Reference" "#PWR0343"
			(at 388.62 96.52 0)
			(effects
				(font
					(size 1.27 1.27)
					(thickness 0.15)
				)
				(justify left bottom)
				(hide yes)
			)
		)
		(property "Value" "GND"
			(at 379.73 97.79 0)
			(effects
				(font
					(size 1.27 1.27)
					(thickness 0.15)
				)
			)
		)
		(property "Footprint" ""
			(at 388.62 101.6 0)
			(effects
				(font
					(size 1.27 1.27)
					(thickness 0.15)
				)
				(justify left bottom)
				(hide yes)
			)
		)
		(property "Datasheet" ""
			(at 388.62 106.68 0)
			(effects
				(font
					(size 1.27 1.27)
					(thickness 0.15)
				)
				(justify left bottom)
				(hide yes)
			)
		)
		(property "Description" ""
			(at 379.73 93.98 0)
			(effects
				(font
					(size 1.27 1.27)
				)
				(hide yes)
			)
		)
		(property "Author" "Antmicro"
			(at 388.62 101.6 0)
			(effects
				(font
					(size 1.27 1.27)
					(thickness 0.15)
				)
				(justify left bottom)
				(hide yes)
			)
		)
		(property "License" "Apache-2.0"
			(at 388.62 104.14 0)
			(effects
				(font
					(size 1.27 1.27)
					(thickness 0.15)
				)
				(justify left bottom)
				(hide yes)
			)
		)
		(pin "1"
		)
		(instances
			(project "OCuLink to 10GbE adapter"
				(path ""
					(reference "#PWR0172")
					(unit 1)
				)
			)
			(project "thunderbolt-to-10gbe-adapter"
				(path ""
					(reference "#PWR0343")
					(unit 1)
				)
			)
		)
	)
	(symbol
		(lib_id "antmicropower:VCC")
		(at 270.51 78.74 0)
		(unit 1)
		(exclude_from_sim no)
		(in_bom yes)
		(on_board yes)
		(dnp no)
		(property "Reference" "#PWR0290"
			(at 270.51 82.55 0)
			(effects
				(font
					(size 1.27 1.27)
				)
				(hide yes)
			)
		)
		(property "Value" "VCCA"
			(at 270.51 74.93 0)
			(effects
				(font
					(size 1.27 1.27)
				)
			)
		)
		(property "Footprint" ""
			(at 270.51 78.74 0)
			(effects
				(font
					(size 1.27 1.27)
				)
				(hide yes)
			)
		)
		(property "Datasheet" ""
			(at 270.51 78.74 0)
			(effects
				(font
					(size 1.27 1.27)
				)
				(hide yes)
			)
		)
		(property "Description" ""
			(at 270.51 78.74 0)
			(effects
				(font
					(size 1.27 1.27)
				)
				(hide yes)
			)
		)
		(pin "1"
		)
		(instances
			(project "OCuLink to 10GbE adapter"
				(path ""
					(reference "#PWR0160")
					(unit 1)
				)
			)
			(project "thunderbolt-to-10gbe-adapter"
				(path ""
					(reference "#PWR0290")
					(unit 1)
				)
			)
		)
	)
	(symbol
		(lib_id "antmicropower:GND")
		(at 133.35 209.55 0)
		(unit 1)
		(exclude_from_sim no)
		(in_bom yes)
		(on_board yes)
		(dnp no)
		(property "Reference" "#PWR0266"
			(at 142.24 212.09 0)
			(effects
				(font
					(size 1.27 1.27)
					(thickness 0.15)
				)
				(justify left bottom)
				(hide yes)
			)
		)
		(property "Value" "GND"
			(at 133.35 213.36 0)
			(effects
				(font
					(size 1.27 1.27)
					(thickness 0.15)
				)
			)
		)
		(property "Footprint" ""
			(at 142.24 217.17 0)
			(effects
				(font
					(size 1.27 1.27)
					(thickness 0.15)
				)
				(justify left bottom)
				(hide yes)
			)
		)
		(property "Datasheet" ""
			(at 142.24 222.25 0)
			(effects
				(font
					(size 1.27 1.27)
					(thickness 0.15)
				)
				(justify left bottom)
				(hide yes)
			)
		)
		(property "Description" ""
			(at 133.35 209.55 0)
			(effects
				(font
					(size 1.27 1.27)
				)
				(hide yes)
			)
		)
		(property "Author" "Antmicro"
			(at 142.24 217.17 0)
			(effects
				(font
					(size 1.27 1.27)
					(thickness 0.15)
				)
				(justify left bottom)
				(hide yes)
			)
		)
		(property "License" "Apache-2.0"
			(at 142.24 219.71 0)
			(effects
				(font
					(size 1.27 1.27)
					(thickness 0.15)
				)
				(justify left bottom)
				(hide yes)
			)
		)
		(pin "1"
		)
		(instances
			(project "OCuLink to 10GbE adapter"
				(path ""
					(reference "#PWR0235")
					(unit 1)
				)
			)
			(project "thunderbolt-to-10gbe-adapter"
				(path ""
					(reference "#PWR0266")
					(unit 1)
				)
			)
		)
	)
	(symbol
		(lib_id "antmicropower:GND")
		(at 133.35 54.61 0)
		(unit 1)
		(exclude_from_sim no)
		(in_bom yes)
		(on_board yes)
		(dnp no)
		(property "Reference" "#PWR0261"
			(at 142.24 57.15 0)
			(effects
				(font
					(size 1.27 1.27)
					(thickness 0.15)
				)
				(justify left bottom)
				(hide yes)
			)
		)
		(property "Value" "GND"
			(at 133.35 58.42 0)
			(effects
				(font
					(size 1.27 1.27)
					(thickness 0.15)
				)
			)
		)
		(property "Footprint" ""
			(at 142.24 62.23 0)
			(effects
				(font
					(size 1.27 1.27)
					(thickness 0.15)
				)
				(justify left bottom)
				(hide yes)
			)
		)
		(property "Datasheet" ""
			(at 142.24 67.31 0)
			(effects
				(font
					(size 1.27 1.27)
					(thickness 0.15)
				)
				(justify left bottom)
				(hide yes)
			)
		)
		(property "Description" ""
			(at 133.35 54.61 0)
			(effects
				(font
					(size 1.27 1.27)
				)
				(hide yes)
			)
		)
		(property "Author" "Antmicro"
			(at 142.24 62.23 0)
			(effects
				(font
					(size 1.27 1.27)
					(thickness 0.15)
				)
				(justify left bottom)
				(hide yes)
			)
		)
		(property "License" "Apache-2.0"
			(at 142.24 64.77 0)
			(effects
				(font
					(size 1.27 1.27)
					(thickness 0.15)
				)
				(justify left bottom)
				(hide yes)
			)
		)
		(pin "1"
		)
		(instances
			(project "OCuLink to 10GbE adapter"
				(path ""
					(reference "#PWR0118")
					(unit 1)
				)
			)
			(project "thunderbolt-to-10gbe-adapter"
				(path ""
					(reference "#PWR0261")
					(unit 1)
				)
			)
		)
	)
	(symbol
		(lib_id "antmicroCapacitors0402:C_1u_25V_0402")
		(at 317.5 52.07 90)
		(unit 1)
		(exclude_from_sim no)
		(in_bom yes)
		(on_board yes)
		(dnp no)
		(property "Reference" "C222"
			(at 319.532 48.26 90)
			(effects
				(font
					(size 1.27 1.27)
					(thickness 0.15)
				)
				(justify right)
			)
		)
		(property "Value" "C_1u_25V_0402"
			(at 327.66 31.75 0)
			(effects
				(font
					(size 1.27 1.27)
					(thickness 0.15)
				)
				(justify left bottom)
				(hide yes)
			)
		)
		(property "Footprint" "antmicro-footprints:C_0402_1005Metric"
			(at 330.2 31.75 0)
			(effects
				(font
					(size 1.27 1.27)
					(thickness 0.15)
				)
				(justify left bottom)
				(hide yes)
			)
		)
		(property "Datasheet" "https://www.murata.com/products/productdetail?partno=GRM155R61E105KE11%23"
			(at 332.74 31.75 0)
			(effects
				(font
					(size 1.27 1.27)
					(thickness 0.15)
				)
				(justify left bottom)
				(hide yes)
			)
		)
		(property "Description" "SMD Multilayer Ceramic Capacitor, 1 µF, 25 V, 0402 [1005 Metric], ± 10%, X5R, GRM Series"
			(at 317.5 52.07 0)
			(effects
				(font
					(size 1.27 1.27)
				)
				(hide yes)
			)
		)
		(property "MPN" "GRM155R61E105KE11J"
			(at 335.28 31.75 0)
			(effects
				(font
					(size 1.27 1.27)
					(thickness 0.15)
				)
				(justify left bottom)
				(hide yes)
			)
		)
		(property "Manufacturer" "Murata"
			(at 337.82 31.75 0)
			(effects
				(font
					(size 1.27 1.27)
					(thickness 0.15)
				)
				(justify left bottom)
				(hide yes)
			)
		)
		(property "License" "Apache-2.0"
			(at 340.36 31.75 0)
			(effects
				(font
					(size 1.27 1.27)
					(thickness 0.15)
				)
				(justify left bottom)
				(hide yes)
			)
		)
		(property "Author" "Antmicro"
			(at 342.9 31.75 0)
			(effects
				(font
					(size 1.27 1.27)
					(thickness 0.15)
				)
				(justify left bottom)
				(hide yes)
			)
		)
		(property "Val" "1u"
			(at 319.532 50.8 90)
			(effects
				(font
					(size 1.27 1.27)
					(thickness 0.15)
				)
				(justify right)
			)
		)
		(property "Voltage" "25V"
			(at 345.44 31.75 0)
			(effects
				(font
					(size 1.27 1.27)
				)
				(justify left bottom)
				(hide yes)
			)
		)
		(property "Dielectric" "X5R"
			(at 347.98 31.75 0)
			(effects
				(font
					(size 1.27 1.27)
				)
				(justify left bottom)
				(hide yes)
			)
		)
		(pin "2"
		)
		(pin "1"
		)
		(instances
			(project "OCuLink to 10GbE adapter"
				(path ""
					(reference "C89")
					(unit 1)
				)
			)
			(project "thunderbolt-to-10gbe-adapter"
				(path ""
					(reference "C222")
					(unit 1)
				)
			)
		)
	)
)
